G04 ================== begin FILE IDENTIFICATION RECORD ==================*
G04 Layout Name:  9127_F0T_Expander_BD_F_v02_0110_1240.brd*
G04 Film Name:    smt*
G04 File Format:  Gerber RS274X*
G04 File Origin:  Cadence Allegro 17.2-S081*
G04 Origin Date:  Wed Jan 11 16:06:13 2023*
G04 *
G04 Layer:  DRAWING FORMAT/TITLE_BLOCK_A*
G04 Layer:  DRAWING FORMAT/TITLE_BLOCK*
G04 Layer:  VIA CLASS/SOLDERMASK_TOP*
G04 Layer:  PIN/SOLDERMASK_TOP*
G04 Layer:  PACKAGE GEOMETRY/SOLDERMASK_TOP*
G04 Layer:  MANUFACTURING/PHOTOPLOT_OUTLINE*
G04 Layer:  DRAWING FORMAT/TITLE_DATA_SMT*
G04 Layer:  BOARD GEOMETRY/SOLDERMASK_TOP*
G04 *
G04 Offset:    (0.00 0.00)*
G04 Mirror:    No*
G04 Mode:      Positive*
G04 Rotation:  0*
G04 FullContactRelief:  No*
G04 UndefLineWidth:     6.00*
G04 ================== end FILE IDENTIFICATION RECORD ====================*
%FSLAX25Y25*MOIN*%
%IR0*IPPOS*OFA0.00000B0.00000*MIA0B0*SFA1.00000B1.00000*%
%AMMACRO51*
4,1,40,.01381,-.00276,
.013749,-.003449,
.013568,-.004116,
.013275,-.004742,
.012878,-.005308,
.012388,-.005796,
.011821,-.006192,
.011194,-.006483,
.010526,-.006661,
.00984,-.00672,
-.00984,-.00672,
-.010529,-.00666,
-.011197,-.006482,
-.011824,-.00619,
-.012391,-.005794,
-.01288,-.005306,
-.013277,-.00474,
-.01357,-.004113,
-.013749,-.003445,
-.01381,-.00276,
-.01381,.00276,
-.013749,.003449,
-.013568,.004116,
-.013275,.004742,
-.012878,.005308,
-.012388,.005796,
-.011821,.006192,
-.011194,.006483,
-.010526,.006661,
-.00984,.00672,
.00984,.00672,
.010529,.00666,
.011197,.006482,
.011824,.00619,
.012391,.005794,
.01288,.005306,
.013277,.00474,
.01357,.004113,
.013749,.003445,
.01381,.00276,
.01381,-.00276,
0.0*
%
%ADD51MACRO51*%
%AMMACRO52*
4,1,40,-.00276,-.01381,
-.003449,-.013749,
-.004116,-.013568,
-.004742,-.013275,
-.005308,-.012878,
-.005796,-.012388,
-.006192,-.011821,
-.006483,-.011194,
-.006661,-.010526,
-.00672,-.00984,
-.00672,.00984,
-.00666,.010529,
-.006482,.011197,
-.00619,.011824,
-.005794,.012391,
-.005306,.01288,
-.00474,.013277,
-.004113,.01357,
-.003445,.013749,
-.00276,.01381,
.00276,.01381,
.003449,.013749,
.004116,.013568,
.004742,.013275,
.005308,.012878,
.005796,.012388,
.006192,.011821,
.006483,.011194,
.006661,.010526,
.00672,.00984,
.00672,-.00984,
.00666,-.010529,
.006482,-.011197,
.00619,-.011824,
.005794,-.012391,
.005306,-.01288,
.00474,-.013277,
.004113,-.01357,
.003445,-.013749,
.00276,-.01381,
-.00276,-.01381,
0.0*
%
%ADD52MACRO52*%
%AMMACRO47*
4,1,32,-.01575,.06201,
-.01575,.0502,
.00197,.0502,
.00197,.04035,
-.01575,.04035,
-.01575,.03248,
.00197,.03248,
.00197,.02461,
-.01575,.02461,
-.01575,.01673,
.00197,.01673,
.00197,.00886,
-.01575,.00886,
-.01575,.00098,
.00197,.00098,
.00197,-.00689,
-.01575,-.00689,
-.01575,-.01476,
.00197,-.01476,
.00197,-.02264,
-.01575,-.02264,
-.01575,-.03051,
.00197,-.03051,
.00197,-.03839,
-.01575,-.03839,
-.01575,-.04626,
.00197,-.04626,
.00197,-.05413,
-.01575,-.05413,
-.01575,-.06201,
.01575,-.06201,
.01575,.06201,
-.01575,.06201,
0.0*
%
%ADD47MACRO47*%
%AMMACRO226*
4,1,8,-.06499,-.03153,
-.06499,.03153,
-.01768,.03153,
-.01768,-.01571,
.01769,-.01571,
.01769,.03153,
.06499,.03153,
.06499,-.03153,
-.06499,-.03153,
0.0*
%
%ADD226MACRO226*%
%AMMACRO130*
4,1,21,-.0075,-.0115,
-.0075,.019,
.0075,.019,
.0075,-.0115,
.007386,-.012802,
.007048,-.014065,
.006495,-.01525,
.005745,-.016321,
.004821,-.017245,
.00375,-.017995,
.002565,-.018548,
.001302,-.018886,
0.0,-.019,
-.001302,-.018886,
-.002565,-.018548,
-.00375,-.017995,
-.004821,-.017245,
-.005745,-.016321,
-.006495,-.01525,
-.007048,-.014065,
-.007386,-.012802,
-.0075,-.0115,
0.0*
%
%ADD130MACRO130*%
%AMMACRO126*
4,1,21,.0115,-.0075,
-.019,-.0075,
-.019,.0075,
.0115,.0075,
.012802,.007386,
.014065,.007048,
.01525,.006495,
.016321,.005745,
.017245,.004821,
.017995,.00375,
.018548,.002565,
.018886,.001302,
.019,0.0,
.018886,-.001302,
.018548,-.002565,
.017995,-.00375,
.017245,-.004821,
.016321,-.005745,
.01525,-.006495,
.014065,-.007048,
.012802,-.007386,
.0115,-.0075,
0.0*
%
%ADD126MACRO126*%
%ADD24R,.103X.071*%
%ADD179R,.113X.044*%
%ADD75R,.071X.103*%
%ADD44R,.111X.082*%
%ADD132R,.103X.046*%
%ADD58R,.082X.111*%
%ADD112O,.141X.066*%
%AMMACRO22*
4,1,8,.01971,.00292,
-.00194,.00292,
-.00194,-.00292,
.01971,-.00292,
.01971,-.01676,
-.01972,-.01676,
-.01972,.01676,
.01971,.01676,
.01971,.00292,
0.0*
%
%ADD22MACRO22*%
%ADD200C,.02*%
%ADD53O,.141X.068*%
%ADD165C,.013*%
%ADD109C,.022*%
%ADD233C,.05*%
%ADD37R,.123X.067*%
%ADD147R,.067X.123*%
%ADD127R,.142X.067*%
%ADD201C,.052*%
%ADD174C,.061*%
%ADD158R,.067X.142*%
%ADD107C,.0322*%
%ADD80R,.073X.109*%
%ADD49R,.0081X.016*%
%ADD10C,.034*%
%AMMACRO155*
4,1,21,-.0135,.0055,
.019,.0055,
.019,-.0055,
-.0135,-.0055,
-.014455,-.005416,
-.015381,-.005168,
-.01625,-.004763,
-.017035,-.004213,
-.017713,-.003535,
-.018263,-.00275,
-.018668,-.001881,
-.018916,-.000955,
-.019,0.0,
-.018916,.000955,
-.018668,.001881,
-.018263,.00275,
-.017713,.003535,
-.017035,.004213,
-.01625,.004763,
-.015381,.005168,
-.014455,.005416,
-.0135,.0055,
0.0*
%
%ADD155MACRO155*%
%ADD135R,.174X.028*%
%ADD113R,.139X.054*%
%ADD95R,.016X.0081*%
%ADD64R,.077X.142*%
%ADD209C,.072*%
%AMMACRO141*
4,1,21,.0055,.0135,
.0055,-.019,
-.0055,-.019,
-.0055,.0135,
-.005416,.014455,
-.005168,.015381,
-.004763,.01625,
-.004213,.017035,
-.003535,.017713,
-.00275,.018263,
-.001881,.018668,
-.000955,.018916,
0.0,.019,
.000955,.018916,
.001881,.018668,
.00275,.018263,
.003535,.017713,
.004213,.017035,
.004763,.01625,
.005168,.015381,
.005416,.014455,
.0055,.0135,
0.0*
%
%ADD141MACRO141*%
%ADD55C,.064*%
%ADD242C,.065*%
%ADD136R,.115X.099*%
%ADD248C,.085*%
%ADD236R,.099X.134*%
%ADD111C,.068*%
%ADD108R,.0322X.0322*%
%AMMACRO175*
4,1,8,-.0445,-.08,
-.0445,.08,
.0445,.08,
.0445,.0216,
.0165,.0216,
.0165,-.0216,
.0445,-.0216,
.0445,-.08,
-.0445,-.08,
0.0*
%
%ADD175MACRO175*%
%ADD68R,.071X.071*%
%ADD194C,.07451*%
%ADD88C,.0395*%
%ADD244R,.065X.065*%
%ADD131R,.134X.0888*%
%ADD74C,.0785*%
%AMMACRO156*
4,1,5,-.01362,-.00692,
-.01873,-.00181,
-.01873,.00692,
.01873,.00692,
.01873,-.00692,
-.01362,-.00692,
0.0*
%
%ADD156MACRO156*%
%AMMACRO229*
4,1,14,.11716,.02956,
.11716,-.02956,
-.11716,-.02956,
-.11716,.02956,
.02817,.02956,
.03143,.027197,
.035051,.025436,
.038922,.02433,
.042927,.023914,
.046943,.024199,
.050849,.025177,
.054525,.026819,
.057861,.029074,
.05844,.02956,
.11716,.02956,
0.0*
%
%ADD229MACRO229*%
%ADD241R,.07451X.07451*%
%AMMACRO219*
4,1,8,.0034,-.0082,
-.0034,-.0082,
-.0082,-.0034,
-.0082,.00341,
-.00341,.0082,
.0034,.0082,
.0082,.0034,
.0082,-.0034,
.0034,-.0082,
0.0*
%
%ADD219MACRO219*%
%AMMACRO104*
4,1,28,-.01259,-.00426,
-.013262,-.003485,
-.013784,-.002602,
-.014146,-.001641,
-.014335,-.000633,
-.014346,.000393,
-.014178,.001405,
-.013838,.002373,
-.013334,.003267,
-.012683,.004061,
-.01264,.00411,
-.00733,.00942,
-.00566,.00775,
.00172,.01513,
.01513,.00172,
.00775,-.00566,
.00942,-.00733,
.00411,-.01264,
.003321,-.013297,
.002433,-.01381,
.001469,-.014162,
.000458,-.01434,
-.000568,-.014341,
-.001578,-.014163,
-.002543,-.013812,
-.003431,-.0133,
-.004218,-.01264,
-.00426,-.01259,
-.01259,-.00426,
0.0*
%
%ADD104MACRO104*%
%AMMACRO13*
4,1,28,-.00589,-.01192,
-.006913,-.011842,
-.007907,-.011587,
-.008842,-.011163,
-.009688,-.010584,
-.010422,-.009866,
-.011019,-.009032,
-.011463,-.008107,
-.011739,-.007119,
-.01184,-.006097,
-.01184,-.00603,
-.01184,.00148,
-.00948,.00148,
-.00948,.01191,
.00948,.01191,
.00948,.00148,
.01184,.00148,
.01184,-.00603,
.011751,-.007052,
.011486,-.008044,
.011053,-.008974,
.010465,-.009815,
.00974,-.010541,
.0089,-.01113,
.00797,-.011564,
.006979,-.01183,
.005957,-.01192,
.00589,-.01192,
-.00589,-.01192,
0.0*
%
%ADD13MACRO13*%
%AMMACRO220*
4,1,8,-.0082,-.0034,
-.0082,.0034,
-.0034,.0082,
.00341,.0082,
.0082,.00341,
.0082,-.0034,
.0034,-.0082,
-.0034,-.0082,
-.0082,-.0034,
0.0*
%
%ADD220MACRO220*%
%AMMACRO30*
4,1,28,-.01192,.00589,
-.011842,.006913,
-.011587,.007907,
-.011163,.008842,
-.010584,.009688,
-.009866,.010422,
-.009032,.011019,
-.008107,.011463,
-.007119,.011739,
-.006097,.01184,
-.00603,.01184,
.00148,.01184,
.00148,.00948,
.01191,.00948,
.01191,-.00948,
.00148,-.00948,
.00148,-.01184,
-.00603,-.01184,
-.007052,-.011751,
-.008044,-.011486,
-.008974,-.011053,
-.009815,-.010465,
-.010541,-.00974,
-.01113,-.0089,
-.011564,-.00797,
-.01183,-.006979,
-.01192,-.005957,
-.01192,-.00589,
-.01192,.00589,
0.0*
%
%ADD30MACRO30*%
%AMMACRO134*
4,1,6,-.1083,.04334,
.1083,.04334,
.1083,-.01578,
.03743,-.01578,
.03743,-.04334,
-.1083,-.04334,
-.1083,.04334,
0.0*
%
%ADD134MACRO134*%
%ADD106C,.03968*%
%AMMACRO231*
4,1,14,-.11716,-.02956,
-.11716,.02956,
.11716,.02956,
.11716,-.02956,
.05844,-.02956,
.05518,-.027197,
.051559,-.025436,
.047688,-.02433,
.043683,-.023914,
.039667,-.024199,
.035761,-.025177,
.032085,-.026819,
.028749,-.029074,
.02817,-.02956,
-.11716,-.02956,
0.0*
%
%ADD231MACRO231*%
%AMMACRO146*
4,1,8,-.02661,.02021,
.0266,.02021,
.0266,-.02021,
.01276,-.02021,
.01276,.00637,
-.01277,.00637,
-.01277,-.02021,
-.02661,-.02021,
-.02661,.02021,
0.0*
%
%ADD146MACRO146*%
%AMMACRO21*
4,1,9,.01972,.00969,
.01972,-.01676,
-.01971,-.01676,
-.01971,-.00292,
.00194,-.00292,
.00194,.00292,
-.01971,.00292,
-.01971,.01676,
.01264,.01676,
.01972,.00969,
0.0*
%
%ADD21MACRO21*%
%AMMACRO105*
4,1,28,.01259,.00425,
.013259,.003472,
.01378,.002588,
.01414,.001628,
.014328,.000619,
.014338,-.000407,
.01417,-.001419,
.013828,-.002387,
.013323,-.00328,
.012671,-.004072,
.01263,-.00412,
.00732,-.00943,
.00565,-.00776,
-.00173,-.01513,
-.01513,-.00173,
-.00776,.00565,
-.00943,.00732,
-.00412,.01263,
-.003332,.013288,
-.002444,.013802,
-.00148,.014154,
-.00047,.014333,
.000556,.014334,
.001567,.014157,
.002531,.013807,
.003421,.013295,
.004207,.012636,
.00425,.01259,
.01259,.00425,
0.0*
%
%ADD105MACRO105*%
%AMMACRO15*
4,1,28,.0059,.01191,
.006923,.01183,
.007916,.011573,
.00885,.011148,
.009696,.010567,
.010428,.009849,
.011024,.009013,
.011466,.008088,
.011741,.007099,
.01184,.006078,
.01184,.00602,
.01184,-.00149,
.00948,-.00149,
.00948,-.01192,
-.00948,-.01192,
-.00948,-.00149,
-.01184,-.00149,
-.01184,.00602,
-.011751,.007042,
-.011486,.008033,
-.011053,.008964,
-.010465,.009805,
-.00974,.010531,
-.0089,.01112,
-.007971,.011554,
-.00698,.01182,
-.005958,.01191,
-.0059,.01191,
.0059,.01191,
0.0*
%
%ADD15MACRO15*%
%AMMACRO29*
4,1,28,.01191,-.0059,
.01183,-.006923,
.011573,-.007916,
.011148,-.00885,
.010567,-.009696,
.009849,-.010428,
.009013,-.011024,
.008088,-.011466,
.007099,-.011741,
.006078,-.01184,
.00602,-.01184,
-.00149,-.01184,
-.00149,-.00948,
-.01192,-.00948,
-.01192,.00948,
-.00149,.00948,
-.00149,.01184,
.00602,.01184,
.007042,.011751,
.008033,.011486,
.008964,.011053,
.009805,.010465,
.010531,.00974,
.01112,.0089,
.011554,.007971,
.01182,.00698,
.01191,.005958,
.01191,.0059,
.01191,-.0059,
0.0*
%
%ADD29MACRO29*%
%AMMACRO205*
4,1,5,.10239,.10239,
.10239,-.10239,
-.08941,-.10239,
-.10239,-.08941,
-.10239,.10239,
.10239,.10239,
0.0*
%
%ADD205MACRO205*%
%ADD46R,.15X.12*%
%AMMACRO237*
4,1,5,.10239,-.10239,
-.10239,-.10239,
-.10239,.08941,
-.08941,.10239,
.10239,.10239,
.10239,-.10239,
0.0*
%
%ADD237MACRO237*%
%AMMACRO166*
4,1,5,-.05712,-.05712,
-.05712,.04217,
-.04217,.05712,
.05712,.05712,
.05712,-.05712,
-.05712,-.05712,
0.0*
%
%ADD166MACRO166*%
%AMMACRO227*
4,1,8,.06499,.03153,
.06499,-.03153,
.01768,-.03153,
.01768,.01571,
-.01769,.01571,
-.01769,-.03153,
-.06499,-.03153,
-.06499,.03153,
.06499,.03153,
0.0*
%
%ADD227MACRO227*%
%ADD117R,.04X.02*%
%ADD211R,.01X.032*%
%ADD188R,.02X.04*%
%ADD42R,.17X.201*%
%ADD212R,.024X.011*%
%ADD125R,.05X.021*%
%ADD18R,.021X.05*%
%ADD204R,.026X.011*%
%ADD202R,.022X.015*%
%AMMACRO149*
4,1,32,.01575,-.06201,
.01575,-.0502,
-.00197,-.0502,
-.00197,-.04035,
.01575,-.04035,
.01575,-.03248,
-.00197,-.03248,
-.00197,-.02461,
.01575,-.02461,
.01575,-.01673,
-.00197,-.01673,
-.00197,-.00886,
.01575,-.00886,
.01575,-.00098,
-.00197,-.00098,
-.00197,.00689,
.01575,.00689,
.01575,.01476,
-.00197,.01476,
-.00197,.02264,
.01575,.02264,
.01575,.03051,
-.00197,.03051,
-.00197,.03839,
.01575,.03839,
.01575,.04626,
-.00197,.04626,
-.00197,.05413,
.01575,.05413,
.01575,.06201,
-.01575,.06201,
-.01575,-.06201,
.01575,-.06201,
0.0*
%
%ADD149MACRO149*%
%ADD121R,.032X.014*%
%ADD96R,.024X.022*%
%ADD85R,.022X.024*%
%ADD79R,.04X.015*%
%ADD223R,.032X.05*%
%ADD206R,.011X.026*%
%ADD203R,.015X.022*%
%ADD153R,.024X.014*%
%ADD151R,.022X.016*%
%ADD138R,.033X.014*%
%ADD97R,.024X.022*%
%ADD84R,.022X.024*%
%ADD72R,.036X.011*%
%ADD71R,.04X.016*%
%ADD23R,.014X.032*%
%ADD253R,.063X.021*%
%ADD234R,.274X.13*%
%ADD187R,.015X.032*%
%ADD160R,.028X.011*%
%ADD159R,.044X.04*%
%AMMACRO148*
4,1,21,-.0115,.0075,
.019,.0075,
.019,-.0075,
-.0115,-.0075,
-.012802,-.007386,
-.014065,-.007048,
-.01525,-.006495,
-.016321,-.005745,
-.017245,-.004821,
-.017995,-.00375,
-.018548,-.002565,
-.018886,-.001302,
-.019,0.0,
-.018886,.001302,
-.018548,.002565,
-.017995,.00375,
-.017245,.004821,
-.016321,.005745,
-.01525,.006495,
-.014065,.007048,
-.012802,.007386,
-.0115,.0075,
0.0*
%
%ADD148MACRO148*%
%ADD140R,.014X.033*%
%ADD73C,.12*%
%ADD34R,.014X.024*%
%ADD28R,.028X.02*%
%ADD251R,.044X.032*%
%ADD245R,.021X.063*%
%ADD216R,.042X.06*%
%ADD177R,.024X.016*%
%ADD176R,.04X.036*%
%ADD167R,.06X.052*%
%ADD161R,.011X.028*%
%AMMACRO128*
4,1,21,.0075,.0115,
.0075,-.019,
-.0075,-.019,
-.0075,.0115,
-.007386,.012802,
-.007048,.014065,
-.006495,.01525,
-.005745,.016321,
-.004821,.017245,
-.00375,.017995,
-.002565,.018548,
-.001302,.018886,
0.0,.019,
.001302,.018886,
.002565,.018548,
.00375,.017995,
.004821,.017245,
.005745,.016321,
.006495,.01525,
.007048,.014065,
.007386,.012802,
.0075,.0115,
0.0*
%
%ADD128MACRO128*%
%ADD115R,.028X.021*%
%ADD57R,.02X.028*%
%ADD36R,.142X.119*%
%ADD197R,.018X.014*%
%ADD186R,.019X.013*%
%ADD172R,.021X.028*%
%ADD145R,.054X.014*%
%ADD76R,.119X.142*%
%ADD67R,.028X.013*%
%ADD63R,.036X.014*%
%ADD56R,.06X.044*%
%ADD45R,.036X.032*%
%ADD40R,.052X.06*%
%ADD39R,.036X.04*%
%ADD249R,.052X.044*%
%ADD243R,.073X.05*%
%ADD239R,.06X.054*%
%ADD225R,.02X.048*%
%AMMACRO224*
4,1,8,-.08468,-.09255,
-.08468,.0295,
-.09452,.0295,
-.09452,.09255,
.09452,.09255,
.09452,.0295,
.08468,.0295,
.08468,-.09255,
-.08468,-.09255,
0.0*
%
%ADD224MACRO224*%
%ADD218R,.032X.028*%
%ADD215R,.026X.06*%
%ADD214R,.132X.139*%
%ADD198R,.019X.014*%
%ADD196R,.014X.018*%
%ADD191R,.058X.02*%
%ADD185R,.013X.019*%
%ADD152R,.126X.136*%
%ADD124R,.05X.028*%
%AMMACRO90*
4,1,8,-.01971,-.00292,
.00194,-.00292,
.00194,.00292,
-.01971,.00292,
-.01971,.01676,
.01972,.01676,
.01972,-.01676,
-.01971,-.01676,
-.01971,-.00292,
0.0*
%
%ADD90MACRO90*%
%ADD66R,.013X.028*%
%ADD62R,.014X.054*%
%ADD61R,.014X.036*%
%ADD32R,.032X.036*%
%ADD12R,.044X.06*%
%ADD255C,.142*%
%ADD221R,.02X.058*%
%ADD217R,.044X.052*%
%ADD213R,.063X.052*%
%ADD195R,.014X.019*%
%ADD157R,.1732X.134*%
%AMMACRO119*
4,1,8,-.00292,.01971,
-.00292,-.00194,
.00292,-.00194,
.00292,.01971,
.01676,.01971,
.01676,-.01972,
-.01676,-.01972,
-.01676,.01971,
-.00292,.01971,
0.0*
%
%ADD119MACRO119*%
%ADD110R,.052X.018*%
%ADD98R,.028X.032*%
%ADD93R,.056X.032*%
%ADD92R,.015X.036*%
%AMMACRO86*
21,1,.016,.0081,0.0,0.0,135.*%
%ADD86MACRO86*%
%ADD81R,.064X.024*%
%ADD59R,.028X.015*%
%ADD48R,.036X.016*%
%ADD17R,.028X.05*%
%ADD246R,.072X.026*%
%ADD232R,.052X.063*%
%AMMACRO144*
4,1,21,-.0055,-.0135,
-.0055,.019,
.0055,.019,
.0055,-.0135,
.005416,-.014455,
.005168,-.015381,
.004763,-.01625,
.004213,-.017035,
.003535,-.017713,
.00275,-.018263,
.001881,-.018668,
.000955,-.018916,
0.0,-.019,
-.000955,-.018916,
-.001881,-.018668,
-.00275,-.018263,
-.003535,-.017713,
-.004213,-.017035,
-.004763,-.01625,
-.005168,-.015381,
-.005416,-.014455,
-.0055,-.0135,
0.0*
%
%ADD144MACRO144*%
%AMMACRO142*
4,1,21,.0135,-.0055,
-.019,-.0055,
-.019,.0055,
.0135,.0055,
.014455,.005416,
.015381,.005168,
.01625,.004763,
.017035,.004213,
.017713,.003535,
.018263,.00275,
.018668,.001881,
.018916,.000955,
.019,0.0,
.018916,-.000955,
.018668,-.001881,
.018263,-.00275,
.017713,-.003535,
.017035,-.004213,
.01625,-.004763,
.015381,-.005168,
.014455,-.005416,
.0135,-.0055,
0.0*
%
%ADD142MACRO142*%
%ADD94R,.019X.016*%
%ADD43R,.015X.028*%
%ADD26R,.054X.044*%
%ADD11C,.26*%
%ADD240R,.193X.19*%
%ADD238R,.052X.029*%
%ADD208R,.058X.014*%
%ADD192R,.063X.018*%
%ADD184R,.067X.05*%
%ADD137R,.071X.046*%
%ADD83R,.016X.019*%
%ADD25R,.044X.054*%
%ADD235R,.018X.063*%
%ADD199R,.044X.019*%
%ADD182C,.154*%
%ADD181R,.029X.052*%
%ADD180R,.036X.028*%
%ADD168R,.058X.015*%
%ADD70R,.016X.083*%
%ADD54R,.054X.019*%
%ADD38C,.145*%
%ADD33R,.046X.071*%
%ADD254O,.048X.091*%
%ADD250R,.056X.018*%
%ADD178R,.046X.028*%
%ADD169R,.015X.058*%
%ADD164R,.067X.016*%
%ADD154R,.083X.063*%
%ADD150R,.073X.081*%
%ADD116R,.057X.026*%
%ADD27R,.028X.028*%
%ADD207R,.036X.038*%
%ADD183R,.028X.046*%
%ADD171R,.026X.057*%
%ADD170R,.048X.018*%
%ADD118R,.018X.056*%
%ADD114R,.056X.028*%
%ADD35R,.063X.083*%
%ADD31R,.028X.028*%
%ADD252O,.048X.075*%
%ADD210R,.057X.019*%
%ADD193C,.319*%
%ADD173R,.067X.018*%
%ADD163R,.018X.048*%
%ADD87R,.028X.056*%
%AMMACRO50*
4,1,44,-.12011,.11614,
-.12005,.116829,
-.119871,.117497,
-.119579,.118124,
-.119183,.118691,
-.118694,.11918,
-.118127,.119577,
-.117501,.11987,
-.116833,.120049,
-.116143,.12011,
-.11614,.12011,
.11614,.12011,
.116829,.12005,
.117497,.119871,
.118124,.119579,
.118691,.119183,
.11918,.118694,
.119577,.118127,
.11987,.117501,
.120049,.116833,
.12011,.116143,
.12011,.11614,
.12011,-.11614,
.12005,-.116829,
.119871,-.117497,
.119579,-.118124,
.119183,-.118691,
.118694,-.11918,
.118127,-.119577,
.117501,-.11987,
.116833,-.120049,
.116143,-.12011,
.11614,-.12011,
-.11614,-.12011,
-.116829,-.12005,
-.117497,-.119871,
-.118124,-.119579,
-.118691,-.119183,
-.11918,-.118694,
-.119577,-.118127,
-.11987,-.117501,
-.120049,-.116833,
-.12011,-.116143,
-.12011,-.11614,
-.12011,.11614,
0.0*
%
%ADD50MACRO50*%
%ADD247R,.018X.067*%
%AMMACRO228*
4,1,8,.0445,.08,
.0445,-.08,
-.0445,-.08,
-.0445,-.0216,
-.0165,-.0216,
-.0165,.0216,
-.0445,.0216,
-.0445,.08,
.0445,.08,
0.0*
%
%ADD228MACRO228*%
%ADD190R,.058X.028*%
%ADD222R,.028X.058*%
%ADD143R,.17X.17*%
%ADD139R,.144X.144*%
%ADD99R,.058X.048*%
%ADD82R,.079X.036*%
%ADD129R,.172X.172*%
%ADD101R,.048X.058*%
%ADD133R,.095X.085*%
%ADD100C,.198*%
%ADD230R,.099X.028*%
%ADD189R,.138X.138*%
%ADD162R,.148X.148*%
%ADD91R,.093X.089*%
%ADD41C,.398*%
%ADD60R,.089X.093*%
%AMMACRO78*
4,1,5,.00692,-.01362,
.00181,-.01873,
-.00692,-.01873,
-.00692,.01873,
.00692,.01873,
.00692,-.01362,
0.0*
%
%ADD78MACRO78*%
%AMMACRO123*
4,1,28,-.00426,.01259,
-.003485,.013262,
-.002602,.013784,
-.001641,.014146,
-.000633,.014335,
.000393,.014346,
.001405,.014178,
.002373,.013838,
.003267,.013334,
.004061,.012683,
.00411,.01264,
.00942,.00733,
.00775,.00566,
.01513,-.00172,
.00172,-.01513,
-.00566,-.00775,
-.00733,-.00942,
-.01264,-.00411,
-.013297,-.003321,
-.01381,-.002433,
-.014162,-.001469,
-.01434,-.000458,
-.014341,.000568,
-.014163,.001578,
-.013812,.002543,
-.0133,.003431,
-.01264,.004218,
-.01259,.00426,
-.00426,.01259,
0.0*
%
%ADD123MACRO123*%
%AMMACRO103*
4,1,28,.01259,.00426,
.013262,.003485,
.013784,.002602,
.014146,.001641,
.014335,.000633,
.014346,-.000393,
.014178,-.001405,
.013838,-.002373,
.013334,-.003267,
.012683,-.004061,
.01264,-.00411,
.00733,-.00942,
.00566,-.00775,
-.00172,-.01513,
-.01513,-.00172,
-.00775,.00566,
-.00942,.00733,
-.00411,.01264,
-.003321,.013297,
-.002433,.01381,
-.001469,.014162,
-.000458,.01434,
.000568,.014341,
.001578,.014163,
.002543,.013812,
.003431,.0133,
.004218,.01264,
.00426,.01259,
.01259,.00426,
0.0*
%
%ADD103MACRO103*%
%AMMACRO65*
4,1,28,.00426,-.01259,
.003485,-.013262,
.002602,-.013784,
.001641,-.014146,
.000633,-.014335,
-.000393,-.014346,
-.001405,-.014178,
-.002373,-.013838,
-.003267,-.013334,
-.004061,-.012683,
-.00411,-.01264,
-.00942,-.00733,
-.00775,-.00566,
-.01513,.00172,
-.00172,.01513,
.00566,.00775,
.00733,.00942,
.01264,.00411,
.013297,.003321,
.01381,.002433,
.014162,.001469,
.01434,.000458,
.014341,-.000568,
.014163,-.001578,
.013812,-.002543,
.0133,-.003431,
.01264,-.004218,
.01259,-.00426,
.00426,-.01259,
0.0*
%
%ADD65MACRO65*%
%AMMACRO20*
4,1,28,.01192,-.00589,
.011842,-.006913,
.011587,-.007907,
.011163,-.008842,
.010584,-.009688,
.009866,-.010422,
.009032,-.011019,
.008107,-.011463,
.007119,-.011739,
.006097,-.01184,
.00603,-.01184,
-.00148,-.01184,
-.00148,-.00948,
-.01191,-.00948,
-.01191,.00948,
-.00148,.00948,
-.00148,.01184,
.00603,.01184,
.007052,.011751,
.008044,.011486,
.008974,.011053,
.009815,.010465,
.010541,.00974,
.01113,.0089,
.011564,.00797,
.01183,.006979,
.01192,.005957,
.01192,.00589,
.01192,-.00589,
0.0*
%
%ADD20MACRO20*%
%AMMACRO16*
4,1,28,.00589,.01192,
.006913,.011842,
.007907,.011587,
.008842,.011163,
.009688,.010584,
.010422,.009866,
.011019,.009032,
.011463,.008107,
.011739,.007119,
.01184,.006097,
.01184,.00603,
.01184,-.00148,
.00948,-.00148,
.00948,-.01191,
-.00948,-.01191,
-.00948,-.00148,
-.01184,-.00148,
-.01184,.00603,
-.011751,.007052,
-.011486,.008044,
-.011053,.008974,
-.010465,.009815,
-.00974,.010541,
-.0089,.01113,
-.00797,.011564,
-.006979,.01183,
-.005957,.01192,
-.00589,.01192,
.00589,.01192,
0.0*
%
%ADD16MACRO16*%
%AMMACRO120*
4,1,9,-.00969,.01972,
.01676,.01972,
.01676,-.01971,
.00292,-.01971,
.00292,.00194,
-.00292,.00194,
-.00292,-.01971,
-.01676,-.01971,
-.01676,.01264,
-.00969,.01972,
0.0*
%
%ADD120MACRO120*%
%AMMACRO89*
4,1,9,-.01972,-.00969,
-.01972,.01676,
.01971,.01676,
.01971,.00292,
-.00194,.00292,
-.00194,-.00292,
.01971,-.00292,
.01971,-.01676,
-.01264,-.01676,
-.01972,-.00969,
0.0*
%
%ADD89MACRO89*%
%AMMACRO77*
4,1,8,-.02021,-.02661,
-.02021,.0266,
.02021,.0266,
.02021,.01276,
-.00637,.01276,
-.00637,-.01277,
.02021,-.01277,
.02021,-.02661,
-.02021,-.02661,
0.0*
%
%ADD77MACRO77*%
%AMMACRO122*
4,1,28,.00425,-.01259,
.003472,-.013259,
.002588,-.01378,
.001628,-.01414,
.000619,-.014328,
-.000407,-.014338,
-.001419,-.01417,
-.002387,-.013828,
-.00328,-.013323,
-.004072,-.012671,
-.00412,-.01263,
-.00943,-.00732,
-.00776,-.00565,
-.01513,.00173,
-.00173,.01513,
.00565,.00776,
.00732,.00943,
.01263,.00412,
.013288,.003332,
.013802,.002444,
.014154,.00148,
.014333,.00047,
.014334,-.000556,
.014157,-.001567,
.013807,-.002531,
.013295,-.003421,
.012636,-.004207,
.01259,-.00425,
.00425,-.01259,
0.0*
%
%ADD122MACRO122*%
%AMMACRO102*
4,1,28,-.01259,-.00425,
-.013259,-.003472,
-.01378,-.002588,
-.01414,-.001628,
-.014328,-.000619,
-.014338,.000407,
-.01417,.001419,
-.013828,.002387,
-.013323,.00328,
-.012671,.004072,
-.01263,.00412,
-.00732,.00943,
-.00565,.00776,
.00173,.01513,
.01513,.00173,
.00776,-.00565,
.00943,-.00732,
.00412,-.01263,
.003332,-.013288,
.002444,-.013802,
.00148,-.014154,
.00047,-.014333,
-.000556,-.014334,
-.001567,-.014157,
-.002531,-.013807,
-.003421,-.013295,
-.004207,-.012636,
-.00425,-.01259,
-.01259,-.00425,
0.0*
%
%ADD102MACRO102*%
%AMMACRO69*
4,1,28,-.00425,.01259,
-.003472,.013259,
-.002588,.01378,
-.001628,.01414,
-.000619,.014328,
.000407,.014338,
.001419,.01417,
.002387,.013828,
.00328,.013323,
.004072,.012671,
.00412,.01263,
.00943,.00732,
.00776,.00565,
.01513,-.00173,
.00173,-.01513,
-.00565,-.00776,
-.00732,-.00943,
-.01263,-.00412,
-.013288,-.003332,
-.013802,-.002444,
-.014154,-.00148,
-.014333,-.00047,
-.014334,.000556,
-.014157,.001567,
-.013807,.002531,
-.013295,.003421,
-.012636,.004207,
-.01259,.00425,
-.00425,.01259,
0.0*
%
%ADD69MACRO69*%
%AMMACRO19*
4,1,28,-.01191,.0059,
-.01183,.006923,
-.011573,.007916,
-.011148,.00885,
-.010567,.009696,
-.009849,.010428,
-.009013,.011024,
-.008088,.011466,
-.007099,.011741,
-.006078,.01184,
-.00602,.01184,
.00149,.01184,
.00149,.00948,
.01192,.00948,
.01192,-.00948,
.00149,-.00948,
.00149,-.01184,
-.00602,-.01184,
-.007042,-.011751,
-.008033,-.011486,
-.008964,-.011053,
-.009805,-.010465,
-.010531,-.00974,
-.01112,-.0089,
-.011554,-.007971,
-.01182,-.00698,
-.01191,-.005958,
-.01191,-.0059,
-.01191,.0059,
0.0*
%
%ADD19MACRO19*%
%AMMACRO14*
4,1,28,-.0059,-.01191,
-.006923,-.01183,
-.007916,-.011573,
-.00885,-.011148,
-.009696,-.010567,
-.010428,-.009849,
-.011024,-.009013,
-.011466,-.008088,
-.011741,-.007099,
-.01184,-.006078,
-.01184,-.00602,
-.01184,.00149,
-.00948,.00149,
-.00948,.01192,
.00948,.01192,
.00948,.00149,
.01184,.00149,
.01184,-.00602,
.011751,-.007042,
.011486,-.008033,
.011053,-.008964,
.010465,-.009805,
.00974,-.010531,
.0089,-.01112,
.007971,-.011554,
.00698,-.01182,
.005958,-.01191,
.0059,-.01191,
-.0059,-.01191,
0.0*
%
%ADD14MACRO14*%
%ADD256C,.006*%
G75*
%LPD*%
G75*
G36*
G01X26772Y1574425D02*
G02Y1560220I0J-7103D01*
G01X20472D01*
G02Y1574425I0J7102D01*
G01X26772D01*
G37*
G36*
G01X134631Y1066535D02*
G02I-17900J0D01*
G37*
G36*
G01Y1263386D02*
G02I-17900J0D01*
G37*
G36*
G01X370852Y1066535D02*
G02I-17900J0D01*
G37*
G36*
G01Y1263386D02*
G02I-17900J0D01*
G37*
G36*
G01X591718Y1066535D02*
G02I-17900J0D01*
G37*
G36*
G01Y1263386D02*
G02I-17900J0D01*
G37*
G36*
G01X790357Y1490945D02*
G02I-19885J0D01*
G37*
G36*
G01X827938Y1066535D02*
G02I-17900J0D01*
G37*
G36*
G01Y1263386D02*
G02I-17900J0D01*
G37*
G36*
G01X839964Y388583D02*
G02I-19885J0D01*
G37*
G36*
G01X1040751D02*
G02I-19885J0D01*
G37*
G36*
G01X1048805Y1066535D02*
G02I-17900J0D01*
G37*
G36*
G01Y1263386D02*
G02I-17900J0D01*
G37*
G36*
G01X1090357Y1490945D02*
G02I-19885J0D01*
G37*
G36*
G01X1285025Y1066535D02*
G02I-17900J0D01*
G37*
G36*
G01Y1263386D02*
G02I-17900J0D01*
G37*
G36*
G01X1505891Y1066535D02*
G02I-17900J0D01*
G37*
G36*
G01Y1263386D02*
G02I-17900J0D01*
G37*
G36*
G01X1742112Y1066535D02*
G02I-17900J0D01*
G37*
G36*
G01Y1263386D02*
G02I-17900J0D01*
G37*
G36*
G01X1824425Y53543D02*
G02X1810220I-7103J0D01*
G01Y59843D01*
G02X1824425I7102J0D01*
G01Y53543D01*
G37*
G36*
G01X1827373Y1567323D02*
G02I-10050J0D01*
G37*
G54D100*
X116731Y1066535D03*
Y1263386D03*
X352952Y1066535D03*
Y1263386D03*
X573818Y1066535D03*
Y1263386D03*
X810038Y1066535D03*
Y1263386D03*
X1030905Y1066535D03*
Y1263386D03*
X1267125Y1066535D03*
Y1263386D03*
X1487991Y1066535D03*
Y1263386D03*
X1724212Y1066535D03*
Y1263386D03*
G54D101*
X114974Y1109408D03*
Y1122008D03*
Y1134608D03*
Y1147208D03*
Y1159808D03*
Y1172408D03*
Y1185008D03*
X134100Y1016671D03*
X126620D03*
X134100Y1029271D03*
X126620D03*
X122454Y1109408D03*
Y1122008D03*
Y1134608D03*
Y1147208D03*
Y1159808D03*
Y1172408D03*
Y1185008D03*
X572061Y1109408D03*
Y1122008D03*
Y1134608D03*
Y1147208D03*
Y1159808D03*
Y1172408D03*
Y1185008D03*
X583707Y1016671D03*
Y1029271D03*
X579541Y1109408D03*
Y1122008D03*
Y1134608D03*
Y1147208D03*
Y1159808D03*
Y1172408D03*
Y1185008D03*
X591187Y1016671D03*
Y1029271D03*
X1040793Y1016671D03*
Y1029271D03*
X1036627Y1109408D03*
X1029147D03*
X1036627Y1122008D03*
X1029147D03*
X1036627Y1134608D03*
X1029147D03*
X1036627Y1147208D03*
X1029147D03*
X1036627Y1159808D03*
X1029147D03*
X1036627Y1172408D03*
X1029147D03*
X1036627Y1185008D03*
X1029147D03*
X1048273Y1016671D03*
Y1029271D03*
X1497880Y1016671D03*
Y1029271D03*
X1493714Y1109408D03*
X1486234D03*
X1493714Y1122008D03*
X1486234D03*
X1493714Y1134608D03*
X1486234D03*
X1493714Y1147208D03*
X1486234D03*
X1493714Y1172408D03*
X1486234D03*
X1493714Y1159808D03*
X1486234D03*
X1493714Y1185008D03*
X1486234D03*
X1505360Y1016671D03*
Y1029271D03*
G54D110*
X181269Y384429D03*
Y386791D03*
Y382067D03*
Y391516D03*
Y389154D03*
Y398602D03*
Y405689D03*
Y393878D03*
Y400965D03*
Y408051D03*
Y396240D03*
Y403327D03*
Y412776D03*
Y419862D03*
Y415138D03*
Y422224D03*
Y410413D03*
Y417500D03*
Y424587D03*
Y434036D03*
Y441122D03*
Y426949D03*
Y436398D03*
Y429311D03*
Y431673D03*
Y438760D03*
Y443484D03*
Y445847D03*
Y465177D03*
Y469902D03*
Y472264D03*
Y467539D03*
Y474626D03*
Y476988D03*
Y484075D03*
Y479350D03*
Y486437D03*
Y481713D03*
Y488799D03*
Y491162D03*
Y493524D03*
Y495886D03*
Y514036D03*
Y521122D03*
Y516398D03*
Y523484D03*
Y511673D03*
Y518760D03*
Y528209D03*
Y535295D03*
Y530571D03*
Y537658D03*
Y525847D03*
Y532933D03*
Y542382D03*
Y544744D03*
Y554193D03*
Y540020D03*
Y547106D03*
Y549469D03*
Y551831D03*
Y556555D03*
Y558917D03*
Y561280D03*
Y563642D03*
Y566004D03*
Y568366D03*
Y570728D03*
Y573091D03*
Y575453D03*
Y597480D03*
Y599843D03*
Y604567D03*
Y592756D03*
Y595118D03*
Y602205D03*
Y609291D03*
Y606929D03*
Y618740D03*
Y614016D03*
Y616378D03*
Y611654D03*
Y623465D03*
Y621102D03*
X199380Y384429D03*
Y386791D03*
Y382067D03*
Y391516D03*
Y389154D03*
Y398602D03*
Y405689D03*
Y393878D03*
Y400965D03*
Y408051D03*
Y396240D03*
Y403327D03*
Y412776D03*
Y419862D03*
Y415138D03*
Y422224D03*
Y410413D03*
Y417500D03*
Y424587D03*
Y434036D03*
Y441122D03*
Y426949D03*
Y436398D03*
Y429311D03*
Y431673D03*
Y438760D03*
Y443484D03*
Y445847D03*
Y465177D03*
Y469902D03*
Y472264D03*
Y467539D03*
Y474626D03*
Y476988D03*
Y484075D03*
Y479350D03*
Y486437D03*
Y481713D03*
Y488799D03*
Y491162D03*
Y493524D03*
Y495886D03*
Y514036D03*
Y521122D03*
Y516398D03*
Y523484D03*
Y511673D03*
Y518760D03*
Y528209D03*
Y535295D03*
Y530571D03*
Y537658D03*
Y525847D03*
Y532933D03*
Y542382D03*
Y544744D03*
Y549469D03*
Y554193D03*
Y551831D03*
Y540020D03*
Y547106D03*
Y556555D03*
Y558917D03*
Y561280D03*
Y563642D03*
Y566004D03*
Y568366D03*
Y570728D03*
Y573091D03*
Y575453D03*
Y597480D03*
Y599843D03*
Y604567D03*
Y592756D03*
Y595118D03*
Y602205D03*
Y618740D03*
Y611654D03*
Y609291D03*
Y606929D03*
Y614016D03*
Y616378D03*
Y621102D03*
Y623465D03*
X270305Y386772D03*
Y391496D03*
Y389134D03*
Y384410D03*
Y382047D03*
Y393858D03*
Y408032D03*
Y405669D03*
Y396221D03*
Y398583D03*
Y400945D03*
Y403307D03*
Y412756D03*
Y410394D03*
Y441870D03*
Y439508D03*
Y437146D03*
Y434784D03*
Y432421D03*
Y430059D03*
Y448957D03*
Y446595D03*
Y444232D03*
Y456043D03*
Y451319D03*
Y453681D03*
Y458406D03*
Y463130D03*
Y460768D03*
Y470217D03*
Y467854D03*
Y472579D03*
Y465492D03*
Y484390D03*
Y477303D03*
Y489114D03*
Y482028D03*
Y474941D03*
Y486752D03*
Y479665D03*
Y491476D03*
Y493839D03*
Y521437D03*
Y514350D03*
Y519075D03*
Y511988D03*
Y516713D03*
Y509626D03*
Y535610D03*
Y528524D03*
Y533248D03*
Y526162D03*
Y537973D03*
Y530886D03*
Y523799D03*
Y540335D03*
Y571476D03*
Y564390D03*
Y569114D03*
Y562028D03*
Y566752D03*
Y559665D03*
Y585650D03*
Y578563D03*
Y583288D03*
Y576201D03*
Y588012D03*
Y580925D03*
Y573839D03*
Y599823D03*
Y592736D03*
Y604547D03*
Y597461D03*
Y590374D03*
Y602185D03*
Y595099D03*
Y618721D03*
Y613996D03*
Y606910D03*
Y611634D03*
Y616358D03*
Y609272D03*
Y621083D03*
Y623445D03*
X288416Y382047D03*
Y384410D03*
Y386772D03*
Y391496D03*
Y389134D03*
Y396221D03*
Y408032D03*
Y405669D03*
Y398583D03*
Y400945D03*
Y403307D03*
Y393858D03*
Y412756D03*
Y410394D03*
Y441870D03*
Y439508D03*
Y437146D03*
Y434784D03*
Y432421D03*
Y430059D03*
Y451319D03*
Y458406D03*
Y448957D03*
Y446595D03*
Y444232D03*
Y456043D03*
Y453681D03*
Y463130D03*
Y460768D03*
Y470217D03*
Y467854D03*
Y472579D03*
Y465492D03*
Y484390D03*
Y477303D03*
Y489114D03*
Y482028D03*
Y474941D03*
Y486752D03*
Y479665D03*
Y491476D03*
Y493839D03*
Y521437D03*
Y514350D03*
Y519075D03*
Y511988D03*
Y516713D03*
Y509626D03*
Y535610D03*
Y528524D03*
Y533248D03*
Y526162D03*
Y537973D03*
Y530886D03*
Y523799D03*
Y540335D03*
Y571476D03*
Y564390D03*
Y569114D03*
Y562028D03*
Y566752D03*
Y559665D03*
Y585650D03*
Y578563D03*
Y583288D03*
Y576201D03*
Y588012D03*
Y580925D03*
Y573839D03*
Y599823D03*
Y592736D03*
Y604547D03*
Y597461D03*
Y590374D03*
Y602185D03*
Y595099D03*
Y618721D03*
Y613996D03*
Y606910D03*
Y611634D03*
Y616358D03*
Y609272D03*
Y621083D03*
Y623445D03*
X638355Y384429D03*
Y386791D03*
Y382067D03*
Y391516D03*
Y389154D03*
Y398602D03*
Y405689D03*
Y393878D03*
Y400965D03*
Y408051D03*
Y396240D03*
Y403327D03*
Y412776D03*
Y419862D03*
Y415138D03*
Y422224D03*
Y410413D03*
Y417500D03*
Y424587D03*
Y434036D03*
Y441122D03*
Y426949D03*
Y436398D03*
Y429311D03*
Y431673D03*
Y438760D03*
Y443484D03*
Y445847D03*
Y465177D03*
Y469902D03*
Y472264D03*
Y467539D03*
Y474626D03*
Y476988D03*
Y484075D03*
Y479350D03*
Y486437D03*
Y481713D03*
Y488799D03*
Y491162D03*
Y493524D03*
Y495886D03*
Y514036D03*
Y521122D03*
Y516398D03*
Y523484D03*
Y511673D03*
Y518760D03*
Y528209D03*
Y535295D03*
Y530571D03*
Y537658D03*
Y525847D03*
Y532933D03*
Y542382D03*
Y544744D03*
Y554193D03*
Y540020D03*
Y547106D03*
Y549469D03*
Y551831D03*
Y556555D03*
Y558917D03*
Y561280D03*
Y563642D03*
Y566004D03*
Y568366D03*
Y570728D03*
Y573091D03*
Y575453D03*
Y597480D03*
Y599843D03*
Y604567D03*
Y592756D03*
Y595118D03*
Y602205D03*
Y609291D03*
Y606929D03*
Y618740D03*
Y614016D03*
Y616378D03*
Y611654D03*
Y623465D03*
Y621102D03*
X656466Y384429D03*
Y386791D03*
Y382067D03*
Y391516D03*
Y389154D03*
Y398602D03*
Y405689D03*
Y393878D03*
Y400965D03*
Y408051D03*
Y396240D03*
Y403327D03*
Y412776D03*
Y419862D03*
Y415138D03*
Y422224D03*
Y410413D03*
Y417500D03*
Y424587D03*
Y434036D03*
Y441122D03*
Y426949D03*
Y436398D03*
Y429311D03*
Y431673D03*
Y438760D03*
Y443484D03*
Y445847D03*
Y465177D03*
Y469902D03*
Y472264D03*
Y467539D03*
Y474626D03*
Y476988D03*
Y484075D03*
Y479350D03*
Y486437D03*
Y481713D03*
Y488799D03*
Y491162D03*
Y493524D03*
Y495886D03*
Y514036D03*
Y521122D03*
Y516398D03*
Y523484D03*
Y511673D03*
Y518760D03*
Y528209D03*
Y535295D03*
Y530571D03*
Y537658D03*
Y525847D03*
Y532933D03*
Y542382D03*
Y544744D03*
Y549469D03*
Y554193D03*
Y551831D03*
Y540020D03*
Y547106D03*
Y556555D03*
Y558917D03*
Y561280D03*
Y563642D03*
Y566004D03*
Y568366D03*
Y570728D03*
Y573091D03*
Y575453D03*
Y597480D03*
Y599843D03*
Y604567D03*
Y592756D03*
Y595118D03*
Y602205D03*
Y618740D03*
Y611654D03*
Y609291D03*
Y606929D03*
Y614016D03*
Y616378D03*
Y621102D03*
Y623465D03*
X727391Y386772D03*
Y391496D03*
Y389134D03*
Y384410D03*
Y382047D03*
Y393858D03*
Y408032D03*
Y405669D03*
Y396221D03*
Y398583D03*
Y400945D03*
Y403307D03*
Y412756D03*
Y410394D03*
Y441870D03*
Y439508D03*
Y437146D03*
Y434784D03*
Y432421D03*
Y430059D03*
Y448957D03*
Y446595D03*
Y444232D03*
Y456043D03*
Y451319D03*
Y453681D03*
Y458406D03*
Y463130D03*
Y460768D03*
Y470217D03*
Y467854D03*
Y472579D03*
Y465492D03*
Y484390D03*
Y477303D03*
Y489114D03*
Y482028D03*
Y474941D03*
Y486752D03*
Y479665D03*
Y491476D03*
Y493839D03*
Y521437D03*
Y514350D03*
Y519075D03*
Y511988D03*
Y516713D03*
Y509626D03*
Y535610D03*
Y528524D03*
Y533248D03*
Y526162D03*
Y537973D03*
Y530886D03*
Y523799D03*
Y540335D03*
Y571476D03*
Y564390D03*
Y569114D03*
Y562028D03*
Y566752D03*
Y559665D03*
Y585650D03*
Y578563D03*
Y583288D03*
Y576201D03*
Y588012D03*
Y580925D03*
Y573839D03*
Y599823D03*
Y592736D03*
Y604547D03*
Y597461D03*
Y590374D03*
Y602185D03*
Y595099D03*
Y618721D03*
Y613996D03*
Y606910D03*
Y611634D03*
Y616358D03*
Y609272D03*
Y621083D03*
Y623445D03*
X745502Y382047D03*
Y384410D03*
Y386772D03*
Y391496D03*
Y389134D03*
Y396221D03*
Y408032D03*
Y405669D03*
Y398583D03*
Y400945D03*
Y403307D03*
Y393858D03*
Y412756D03*
Y410394D03*
Y441870D03*
Y439508D03*
Y437146D03*
Y434784D03*
Y432421D03*
Y430059D03*
Y451319D03*
Y458406D03*
Y448957D03*
Y446595D03*
Y444232D03*
Y456043D03*
Y453681D03*
Y463130D03*
Y460768D03*
Y470217D03*
Y467854D03*
Y472579D03*
Y465492D03*
Y484390D03*
Y477303D03*
Y489114D03*
Y482028D03*
Y474941D03*
Y486752D03*
Y479665D03*
Y491476D03*
Y493839D03*
Y521437D03*
Y514350D03*
Y519075D03*
Y511988D03*
Y516713D03*
Y509626D03*
Y535610D03*
Y528524D03*
Y533248D03*
Y526162D03*
Y537973D03*
Y530886D03*
Y523799D03*
Y540335D03*
Y571476D03*
Y564390D03*
Y569114D03*
Y562028D03*
Y566752D03*
Y559665D03*
Y585650D03*
Y578563D03*
Y583288D03*
Y576201D03*
Y588012D03*
Y580925D03*
Y573839D03*
Y599823D03*
Y592736D03*
Y604547D03*
Y597461D03*
Y590374D03*
Y602185D03*
Y595099D03*
Y618721D03*
Y613996D03*
Y606910D03*
Y611634D03*
Y616358D03*
Y609272D03*
Y621083D03*
Y623445D03*
X1095442Y384429D03*
Y386791D03*
Y382067D03*
Y391516D03*
Y389154D03*
Y398602D03*
Y405689D03*
Y393878D03*
Y400965D03*
Y408051D03*
Y396240D03*
Y403327D03*
Y412776D03*
Y419862D03*
Y415138D03*
Y422224D03*
Y410413D03*
Y417500D03*
Y424587D03*
Y434036D03*
Y441122D03*
Y426949D03*
Y436398D03*
Y429311D03*
Y431673D03*
Y438760D03*
Y443484D03*
Y445847D03*
Y465177D03*
Y469902D03*
Y472264D03*
Y467539D03*
Y474626D03*
Y476988D03*
Y484075D03*
Y479350D03*
Y486437D03*
Y481713D03*
Y488799D03*
Y491162D03*
Y493524D03*
Y495886D03*
Y514036D03*
Y521122D03*
Y516398D03*
Y523484D03*
Y511673D03*
Y518760D03*
Y528209D03*
Y535295D03*
Y530571D03*
Y537658D03*
Y525847D03*
Y532933D03*
Y542382D03*
Y544744D03*
Y554193D03*
Y540020D03*
Y547106D03*
Y549469D03*
Y551831D03*
Y556555D03*
Y558917D03*
Y561280D03*
Y563642D03*
Y566004D03*
Y568366D03*
Y570728D03*
Y573091D03*
Y575453D03*
Y597480D03*
Y599843D03*
Y604567D03*
Y592756D03*
Y595118D03*
Y602205D03*
Y609291D03*
Y606929D03*
Y618740D03*
Y614016D03*
Y616378D03*
Y611654D03*
Y623465D03*
Y621102D03*
X1113553Y384429D03*
Y386791D03*
Y382067D03*
Y391516D03*
Y389154D03*
Y398602D03*
Y405689D03*
Y393878D03*
Y400965D03*
Y408051D03*
Y396240D03*
Y403327D03*
Y412776D03*
Y419862D03*
Y415138D03*
Y422224D03*
Y410413D03*
Y417500D03*
Y424587D03*
Y434036D03*
Y441122D03*
Y426949D03*
Y436398D03*
Y429311D03*
Y431673D03*
Y438760D03*
Y443484D03*
Y445847D03*
Y465177D03*
Y469902D03*
Y472264D03*
Y467539D03*
Y474626D03*
Y476988D03*
Y484075D03*
Y479350D03*
Y486437D03*
Y481713D03*
Y488799D03*
Y491162D03*
Y493524D03*
Y495886D03*
Y514036D03*
Y521122D03*
Y516398D03*
Y523484D03*
Y511673D03*
Y518760D03*
Y528209D03*
Y535295D03*
Y530571D03*
Y537658D03*
Y525847D03*
Y532933D03*
Y542382D03*
Y544744D03*
Y549469D03*
Y554193D03*
Y551831D03*
Y540020D03*
Y547106D03*
Y556555D03*
Y558917D03*
Y561280D03*
Y563642D03*
Y566004D03*
Y568366D03*
Y570728D03*
Y573091D03*
Y575453D03*
Y597480D03*
Y599843D03*
Y604567D03*
Y592756D03*
Y595118D03*
Y602205D03*
Y618740D03*
Y611654D03*
Y609291D03*
Y606929D03*
Y614016D03*
Y616378D03*
Y621102D03*
Y623465D03*
X1184478Y386772D03*
Y391496D03*
Y389134D03*
Y384410D03*
Y382047D03*
Y393858D03*
Y408032D03*
Y405669D03*
Y396221D03*
Y398583D03*
Y400945D03*
Y403307D03*
Y412756D03*
Y410394D03*
Y441870D03*
Y439508D03*
Y437146D03*
Y434784D03*
Y432421D03*
Y430059D03*
Y448957D03*
Y446595D03*
Y444232D03*
Y456043D03*
Y451319D03*
Y453681D03*
Y458406D03*
Y463130D03*
Y460768D03*
Y470217D03*
Y467854D03*
Y472579D03*
Y465492D03*
Y484390D03*
Y477303D03*
Y489114D03*
Y482028D03*
Y474941D03*
Y486752D03*
Y479665D03*
Y491476D03*
Y493839D03*
Y521437D03*
Y514350D03*
Y519075D03*
Y511988D03*
Y516713D03*
Y509626D03*
Y535610D03*
Y528524D03*
Y533248D03*
Y526162D03*
Y537973D03*
Y530886D03*
Y523799D03*
Y540335D03*
Y571476D03*
Y564390D03*
Y569114D03*
Y562028D03*
Y566752D03*
Y559665D03*
Y585650D03*
Y578563D03*
Y583288D03*
Y576201D03*
Y588012D03*
Y580925D03*
Y573839D03*
Y599823D03*
Y592736D03*
Y604547D03*
Y597461D03*
Y590374D03*
Y602185D03*
Y595099D03*
Y618721D03*
Y613996D03*
Y606910D03*
Y611634D03*
Y616358D03*
Y609272D03*
Y621083D03*
Y623445D03*
X1202589Y382047D03*
Y384410D03*
Y386772D03*
Y391496D03*
Y389134D03*
Y396221D03*
Y408032D03*
Y405669D03*
Y398583D03*
Y400945D03*
Y403307D03*
Y393858D03*
Y412756D03*
Y410394D03*
Y441870D03*
Y439508D03*
Y437146D03*
Y434784D03*
Y432421D03*
Y430059D03*
Y451319D03*
Y458406D03*
Y448957D03*
Y446595D03*
Y444232D03*
Y456043D03*
Y453681D03*
Y463130D03*
Y460768D03*
Y470217D03*
Y467854D03*
Y472579D03*
Y465492D03*
Y484390D03*
Y477303D03*
Y489114D03*
Y482028D03*
Y474941D03*
Y486752D03*
Y479665D03*
Y491476D03*
Y493839D03*
Y521437D03*
Y514350D03*
Y519075D03*
Y511988D03*
Y516713D03*
Y509626D03*
Y535610D03*
Y528524D03*
Y533248D03*
Y526162D03*
Y537973D03*
Y530886D03*
Y523799D03*
Y540335D03*
Y571476D03*
Y564390D03*
Y569114D03*
Y562028D03*
Y566752D03*
Y559665D03*
Y585650D03*
Y578563D03*
Y583288D03*
Y576201D03*
Y588012D03*
Y580925D03*
Y573839D03*
Y599823D03*
Y592736D03*
Y604547D03*
Y597461D03*
Y590374D03*
Y602185D03*
Y595099D03*
Y618721D03*
Y613996D03*
Y606910D03*
Y611634D03*
Y616358D03*
Y609272D03*
Y621083D03*
Y623445D03*
X1552529Y384429D03*
Y386791D03*
Y382067D03*
Y391516D03*
Y389154D03*
Y398602D03*
Y405689D03*
Y393878D03*
Y400965D03*
Y408051D03*
Y396240D03*
Y403327D03*
Y412776D03*
Y419862D03*
Y415138D03*
Y422224D03*
Y410413D03*
Y417500D03*
Y424587D03*
Y434036D03*
Y441122D03*
Y426949D03*
Y436398D03*
Y429311D03*
Y431673D03*
Y438760D03*
Y443484D03*
Y445847D03*
Y465177D03*
Y469902D03*
Y472264D03*
Y467539D03*
Y474626D03*
Y476988D03*
Y484075D03*
Y479350D03*
Y486437D03*
Y481713D03*
Y488799D03*
Y491162D03*
Y493524D03*
Y495886D03*
Y514036D03*
Y521122D03*
Y516398D03*
Y523484D03*
Y511673D03*
Y518760D03*
Y528209D03*
Y535295D03*
Y530571D03*
Y537658D03*
Y525847D03*
Y532933D03*
Y542382D03*
Y544744D03*
Y554193D03*
Y540020D03*
Y547106D03*
Y549469D03*
Y551831D03*
Y556555D03*
Y558917D03*
Y561280D03*
Y563642D03*
Y566004D03*
Y568366D03*
Y570728D03*
Y573091D03*
Y575453D03*
Y597480D03*
Y599843D03*
Y604567D03*
Y592756D03*
Y595118D03*
Y602205D03*
Y609291D03*
Y606929D03*
Y618740D03*
Y614016D03*
Y616378D03*
Y611654D03*
Y623465D03*
Y621102D03*
X1570640Y384429D03*
Y386791D03*
Y382067D03*
Y391516D03*
Y389154D03*
Y398602D03*
Y405689D03*
Y393878D03*
Y400965D03*
Y408051D03*
Y396240D03*
Y403327D03*
Y412776D03*
Y419862D03*
Y415138D03*
Y422224D03*
Y410413D03*
Y417500D03*
Y424587D03*
Y434036D03*
Y441122D03*
Y426949D03*
Y436398D03*
Y429311D03*
Y431673D03*
Y438760D03*
Y443484D03*
Y445847D03*
Y465177D03*
Y469902D03*
Y472264D03*
Y467539D03*
Y474626D03*
Y476988D03*
Y484075D03*
Y479350D03*
Y486437D03*
Y481713D03*
Y488799D03*
Y491162D03*
Y493524D03*
Y495886D03*
Y514036D03*
Y521122D03*
Y516398D03*
Y523484D03*
Y511673D03*
Y518760D03*
Y528209D03*
Y535295D03*
Y530571D03*
Y537658D03*
Y525847D03*
Y532933D03*
Y542382D03*
Y544744D03*
Y549469D03*
Y554193D03*
Y551831D03*
Y540020D03*
Y547106D03*
Y556555D03*
Y558917D03*
Y561280D03*
Y563642D03*
Y566004D03*
Y568366D03*
Y570728D03*
Y573091D03*
Y575453D03*
Y597480D03*
Y599843D03*
Y604567D03*
Y592756D03*
Y595118D03*
Y602205D03*
Y618740D03*
Y611654D03*
Y609291D03*
Y606929D03*
Y614016D03*
Y616378D03*
Y621102D03*
Y623465D03*
X1641565Y386772D03*
Y391496D03*
Y389134D03*
Y384410D03*
Y382047D03*
Y393858D03*
Y408032D03*
Y405669D03*
Y396221D03*
Y398583D03*
Y400945D03*
Y403307D03*
Y412756D03*
Y410394D03*
Y441870D03*
Y439508D03*
Y437146D03*
Y434784D03*
Y432421D03*
Y430059D03*
Y448957D03*
Y446595D03*
Y444232D03*
Y456043D03*
Y451319D03*
Y453681D03*
Y458406D03*
Y463130D03*
Y460768D03*
Y470217D03*
Y467854D03*
Y472579D03*
Y465492D03*
Y484390D03*
Y477303D03*
Y489114D03*
Y482028D03*
Y474941D03*
Y486752D03*
Y479665D03*
Y491476D03*
Y493839D03*
Y521437D03*
Y514350D03*
Y519075D03*
Y511988D03*
Y516713D03*
Y509626D03*
Y535610D03*
Y528524D03*
Y533248D03*
Y526162D03*
Y537973D03*
Y530886D03*
Y523799D03*
Y540335D03*
Y571476D03*
Y564390D03*
Y569114D03*
Y562028D03*
Y566752D03*
Y559665D03*
Y585650D03*
Y578563D03*
Y583288D03*
Y576201D03*
Y588012D03*
Y580925D03*
Y573839D03*
Y599823D03*
Y592736D03*
Y604547D03*
Y597461D03*
Y590374D03*
Y602185D03*
Y595099D03*
Y618721D03*
Y613996D03*
Y606910D03*
Y611634D03*
Y616358D03*
Y609272D03*
Y621083D03*
Y623445D03*
X1659676Y382047D03*
Y384410D03*
Y386772D03*
Y391496D03*
Y389134D03*
Y396221D03*
Y408032D03*
Y405669D03*
Y398583D03*
Y400945D03*
Y403307D03*
Y393858D03*
Y412756D03*
Y410394D03*
Y441870D03*
Y439508D03*
Y437146D03*
Y434784D03*
Y432421D03*
Y430059D03*
Y451319D03*
Y458406D03*
Y448957D03*
Y446595D03*
Y444232D03*
Y456043D03*
Y453681D03*
Y463130D03*
Y460768D03*
Y470217D03*
Y467854D03*
Y472579D03*
Y465492D03*
Y484390D03*
Y477303D03*
Y489114D03*
Y482028D03*
Y474941D03*
Y486752D03*
Y479665D03*
Y491476D03*
Y493839D03*
Y521437D03*
Y514350D03*
Y519075D03*
Y511988D03*
Y516713D03*
Y509626D03*
Y535610D03*
Y528524D03*
Y533248D03*
Y526162D03*
Y537973D03*
Y530886D03*
Y523799D03*
Y540335D03*
Y571476D03*
Y564390D03*
Y569114D03*
Y562028D03*
Y566752D03*
Y559665D03*
Y585650D03*
Y578563D03*
Y583288D03*
Y576201D03*
Y588012D03*
Y580925D03*
Y573839D03*
Y599823D03*
Y592736D03*
Y604547D03*
Y597461D03*
Y590374D03*
Y602185D03*
Y595099D03*
Y618721D03*
Y613996D03*
Y606910D03*
Y611634D03*
Y616358D03*
Y609272D03*
Y621083D03*
Y623445D03*
G54D200*
G01X0Y7874D02*
G03X7874Y0I7874J0D01*
G01X0Y323353D02*
Y7874D01*
G01X12654Y339269D02*
X2306Y328920D01*
G01D02*
G03X0Y323353I5567J-5567D01*
G01Y1640118D02*
Y970427D01*
G01D02*
G03X2306Y964859I7874J0D01*
G01D02*
X12654Y954511D01*
G01X7874Y1647992D02*
G03X0Y1640118I0J-7874D01*
G01X7874Y0D02*
X23484D01*
G01X14961Y948943D02*
Y344836D01*
G01D02*
G02X12654Y339269I-7873J1D01*
G01Y954511D02*
G02X14961Y948943I-5568J-5569D01*
G01X789297Y1647992D02*
X7874D01*
G01X23484Y0D02*
G03X31358Y7874I0J7874D01*
G01D02*
Y46654D01*
G01D02*
G02X35295Y50591I3937J0D01*
G01D02*
X66791D01*
G01D02*
G02X70728Y46654I0J-3937D01*
G01Y7874D02*
G03X78602Y0I7874J0D01*
G01D02*
X125846D01*
G01X70728Y46654D02*
Y7874D01*
G01X125846Y0D02*
G03X133720Y7874I0J7874D01*
G01D02*
Y46654D01*
G01D02*
G02X137657Y50591I3937J0D01*
G01D02*
X169154D01*
G01X173091Y7874D02*
G03X180965Y0I7874J0D01*
G01D02*
X228209D01*
G01X173091Y46654D02*
Y7874D01*
G01X169154Y50591D02*
G02X173091Y46654I0J-3937D01*
G01X228209Y0D02*
G03X236083Y7874I0J7874D01*
G01D02*
Y46654D01*
G01D02*
G02X240020Y50591I3937J0D01*
G01D02*
X271516D01*
G01X275453Y7874D02*
G03X283327Y0I7874J0D01*
G01X275453Y46654D02*
Y7874D01*
G01X271516Y50591D02*
G02X275453Y46654I0J-3937D01*
G01X283327Y0D02*
X330571D01*
G01D02*
G03X338445Y7874I0J7874D01*
G01D02*
Y46654D01*
G01D02*
G02X342382Y50591I3937J0D01*
G01D02*
X373878D01*
G01D02*
G02X377815Y46654I0J-3937D01*
G01Y7874D02*
G03X385689Y0I7874J0D01*
G01D02*
X480571D01*
G01X377815Y46654D02*
Y7874D01*
G01X480571Y0D02*
G03X488445Y7874I0J7874D01*
G01D02*
Y46654D01*
G01D02*
G02X492382Y50591I3937J0D01*
G01D02*
X523878D01*
G01X527815Y7874D02*
G03X535689Y0I7874J0D01*
G01D02*
X582933D01*
G01X527815Y46654D02*
Y7874D01*
G01X523878Y50591D02*
G02X527815Y46654I0J-3937D01*
G01X582933Y0D02*
G03X590807Y7874I0J7874D01*
G01D02*
Y46654D01*
G01D02*
G02X594744Y50591I3937J0D01*
G01D02*
X626240D01*
G01X630177Y7874D02*
G03X638051Y0I7874J0D01*
G01X630177Y46654D02*
Y7874D01*
G01X626240Y50591D02*
G02X630177Y46654I0J-3937D01*
G01X638051Y0D02*
X685295D01*
G01D02*
G03X693169Y7874I0J7874D01*
G01D02*
Y46654D01*
G01D02*
G02X697106Y50591I3937J0D01*
G01D02*
X728602D01*
G01X732539Y7874D02*
G03X740413Y0I7874J0D01*
G01X732539Y46654D02*
Y7874D01*
G01X728602Y50591D02*
G02X732539Y46654I0J-3937D01*
G01X740413Y0D02*
X787657D01*
G01D02*
G03X795531Y7874I0J7874D01*
G01D02*
Y46654D01*
G01X799469Y50591D02*
X830965D01*
G01X795531Y46654D02*
G02X799469Y50591I3937J0D01*
G01X800966Y1642819D02*
G02X795131Y1645406I0J7875D01*
G01D02*
G03X789297Y1647992I-5834J-5287D01*
G01X1070058Y1642819D02*
X800966D01*
G01X830965Y50591D02*
G02X834902Y46654I0J-3937D01*
G01Y7874D02*
G03X842776Y0I7874J0D01*
G01D02*
X937657D01*
G01X834902Y46654D02*
Y7874D01*
G01X937657Y0D02*
G03X945531Y7874I0J7874D01*
G01D02*
Y46654D01*
G01D02*
G02X949469Y50591I3938J0D01*
G01D02*
X980965D01*
G01X984902Y7874D02*
G03X992776Y0I7874J0D01*
G01D02*
X1040020D01*
G01X984902Y46654D02*
Y7874D01*
G01X980965Y50591D02*
G02X984902Y46654I0J-3937D01*
G01X1040020Y0D02*
G03X1047894Y7874I0J7874D01*
G01D02*
Y46654D01*
G01D02*
G02X1051831Y50591I3937J0D01*
G01D02*
X1083327D01*
G01X1075892Y1645406D02*
G02X1070058Y1642819I-5835J5286D01*
G01X1087264Y7874D02*
G03X1095138Y0I7874J0D01*
G01X1087264Y46654D02*
Y7874D01*
G01X1083327Y50591D02*
G02X1087264Y46654I0J-3937D01*
G01X1833071Y1647992D02*
X1081727D01*
G01D02*
G03X1075892Y1645406I-1J-7874D01*
G01X1095138Y0D02*
X1142382D01*
G01D02*
G03X1150256Y7874I0J7874D01*
G01D02*
Y46654D01*
G01D02*
G02X1154193Y50591I3937J0D01*
G01D02*
X1185689D01*
G01D02*
G02X1189626Y46654I0J-3937D01*
G01Y7874D02*
G03X1197500Y0I7874J0D01*
G01D02*
X1244744D01*
G01X1189626Y46654D02*
Y7874D01*
G01X1244744Y0D02*
G03X1252618Y7874I0J7874D01*
G01D02*
Y46654D01*
G01D02*
G02X1256555Y50591I3937J0D01*
G01D02*
X1288051D01*
G01X1291988Y7874D02*
G03X1299862Y0I7874J0D01*
G01D02*
X1394744D01*
G01X1291988Y46654D02*
Y7874D01*
G01X1288051Y50591D02*
G02X1291988Y46654I0J-3937D01*
G01X1394744Y0D02*
G03X1402618Y7874I0J7874D01*
G01D02*
Y46654D01*
G01D02*
G02X1406555Y50591I3937J0D01*
G01D02*
X1438051D01*
G01X1441988Y7874D02*
G03X1449862Y0I7874J0D01*
G01X1441988Y46654D02*
Y7874D01*
G01X1438051Y50591D02*
G02X1441988Y46654I0J-3937D01*
G01X1449862Y0D02*
X1497106D01*
G01D02*
G03X1504980Y7874I0J7874D01*
G01D02*
Y46654D01*
G01D02*
G02X1508917Y50591I3937J0D01*
G01D02*
X1540413D01*
G01X1544350Y7874D02*
G03X1552224Y0I7874J0D01*
G01X1544350Y46654D02*
Y7874D01*
G01X1540413Y50591D02*
G02X1544350Y46654I0J-3937D01*
G01X1552224Y0D02*
X1599469D01*
G01D02*
G03X1607343Y7874I0J7874D01*
G01D02*
Y46654D01*
G01X1611280Y50591D02*
X1642776D01*
G01X1607343Y46654D02*
G02X1611280Y50591I3937J0D01*
G01X1642776D02*
G02X1646713Y46654I0J-3937D01*
G01Y7874D02*
G03X1654587Y0I7874J0D01*
G01D02*
X1701831D01*
G01X1646713Y46654D02*
Y7874D01*
G01X1701831Y0D02*
G03X1709705Y7874I0J7874D01*
G01D02*
Y46654D01*
G01D02*
G02X1713642Y50591I3937J0D01*
G01D02*
X1745138D01*
G01X1749075Y7874D02*
G03X1756949Y0I7874J0D01*
G01D02*
X1833071D01*
G01X1749075Y46654D02*
Y7874D01*
G01X1745138Y50591D02*
G02X1749075Y46654I0J-3937D01*
G01X1833071Y0D02*
G03X1840945Y7874I0J7874D01*
G01Y323353D02*
G03X1838639Y328920I-7873J0D01*
G01X1825984Y344836D02*
Y948943D01*
G01X1838639Y328920D02*
X1828290Y339269D01*
G01D02*
G02X1825984Y344836I5567J5567D01*
G01Y948943D02*
G02X1828290Y954511I7874J0D01*
G01D02*
X1838639Y964859D01*
G01D02*
G03X1840945Y970427I-5568J5568D01*
G01Y1640118D02*
G03X1833071Y1647992I-7874J0D01*
G01X1840945Y7874D02*
Y323353D01*
G01Y970427D02*
Y1640118D01*
X879794Y837418D03*
Y840568D03*
Y843717D03*
Y846867D03*
Y850016D03*
Y853166D03*
Y856316D03*
Y859465D03*
Y862615D03*
Y865764D03*
Y872064D03*
Y878363D03*
Y868914D03*
Y875213D03*
Y881512D03*
Y884662D03*
X886093Y846867D03*
X882944Y840568D03*
X889243Y846867D03*
X882944D03*
X895542D03*
Y840568D03*
X892392D03*
X895542Y837418D03*
Y843717D03*
X889243Y837418D03*
X892392Y846867D03*
X889243Y843717D03*
X892392D03*
X886093Y840568D03*
X882944Y837418D03*
X886093Y843717D03*
Y837418D03*
X882944Y843717D03*
X892392Y837418D03*
X889243Y840568D03*
X892392Y859465D03*
Y856316D03*
X895542Y862615D03*
Y859465D03*
Y856316D03*
X886093Y850016D03*
X889243Y856316D03*
Y853166D03*
Y850016D03*
X882944D03*
X886093Y856316D03*
Y853166D03*
X882944D03*
X892392D03*
X895542Y850016D03*
Y853166D03*
X892392Y850016D03*
X889243Y859465D03*
X886093D03*
X892392Y862615D03*
X889243D03*
X882944Y856316D03*
Y859465D03*
X886093Y862615D03*
X882944D03*
X892392Y865764D03*
Y868914D03*
X889243Y875213D03*
X895542Y872064D03*
Y868914D03*
Y865764D03*
X882944Y868914D03*
X886093Y872064D03*
X882944Y875213D03*
X886093D03*
X892392Y878363D03*
X882944Y865764D03*
X886093Y868914D03*
X882944Y872064D03*
X889243D03*
X882944Y878363D03*
X889243D03*
X886093Y865764D03*
X889243Y868914D03*
Y865764D03*
X892392Y872064D03*
X895542Y878363D03*
X886093D03*
X892392Y875213D03*
X895542D03*
X882944Y881512D03*
X886093D03*
X882944Y884662D03*
X886093D03*
X889243Y881512D03*
Y884662D03*
X892392Y881512D03*
Y884662D03*
X895542Y881512D03*
Y884662D03*
X904991Y840568D03*
X908140Y846867D03*
X911290D03*
X908140Y843717D03*
X911290D03*
X908140Y840568D03*
X901841D03*
Y843717D03*
X904991Y837418D03*
X901841Y846867D03*
X898692Y840568D03*
Y837418D03*
X901841D03*
X911290D03*
Y840568D03*
X908140Y837418D03*
X904991Y843717D03*
Y846867D03*
X898692Y843717D03*
Y846867D03*
X901841Y853166D03*
X904991D03*
X898692D03*
X901841Y850016D03*
X904991D03*
X898692D03*
X901841Y862615D03*
X904991D03*
X908140D03*
X911290D03*
X898692D03*
X901841Y859465D03*
X904991D03*
X908140D03*
X911290D03*
X898692D03*
X901841Y856316D03*
X904991D03*
X908140D03*
X911290D03*
X898692D03*
X911290Y853166D03*
Y850016D03*
X908140Y853166D03*
Y850016D03*
X901841Y875213D03*
X904991D03*
X911290Y872064D03*
X908140Y875213D03*
X898692D03*
X901841Y872064D03*
X904991D03*
X908140D03*
X898692D03*
X901841Y868914D03*
X904991D03*
X908140D03*
X911290D03*
X898692D03*
X901841Y865764D03*
X904991D03*
X908140D03*
X911290D03*
X898692D03*
Y878363D03*
X901841D03*
X904991D03*
X911290Y875213D03*
X908140Y878363D03*
X911290D03*
X898692Y881512D03*
Y884662D03*
X901841Y881512D03*
Y884662D03*
X904991D03*
Y881512D03*
X908140Y884662D03*
Y881512D03*
X911290Y884662D03*
Y881512D03*
X927038Y837418D03*
X914440Y840568D03*
X917589D03*
Y837418D03*
X914440D03*
Y843717D03*
Y846867D03*
X920739Y843717D03*
X917589D03*
X923888Y837418D03*
X920739Y840568D03*
Y837418D03*
X917589Y846867D03*
X923888D03*
X927038D03*
X923888Y843717D03*
X920739Y846867D03*
X927038Y843717D03*
Y840568D03*
X923888D03*
X914440Y859465D03*
Y856316D03*
X917589Y859465D03*
Y856316D03*
X920739D03*
Y853166D03*
X917589Y850016D03*
Y853166D03*
X914440D03*
Y850016D03*
X920739Y862615D03*
X923888Y850016D03*
X920739Y859465D03*
X927038Y850016D03*
Y856316D03*
X923888Y853166D03*
Y856316D03*
X927038Y853166D03*
X914440Y862615D03*
X927038Y859465D03*
X923888D03*
X920739Y850016D03*
X927038Y862615D03*
X923888D03*
X917589D03*
X914440Y868914D03*
Y865764D03*
X923888D03*
X917589D03*
X920739D03*
X927038Y875213D03*
X923888D03*
X920739D03*
X927038Y872064D03*
X923888D03*
X920739D03*
X927038Y868914D03*
X923888D03*
X917589Y872064D03*
Y868914D03*
X920739D03*
X927038Y865764D03*
X914440Y872064D03*
Y875213D03*
X920739Y878363D03*
X923888D03*
X914440D03*
X927038D03*
X917589D03*
Y875213D03*
X914440Y884662D03*
X917589D03*
X914440Y881512D03*
X917589D03*
X920739Y884662D03*
X923888D03*
X920739Y881512D03*
X927038Y884662D03*
X923888Y881512D03*
X927038D03*
X1315330Y831445D03*
X1318480D03*
Y844044D03*
Y834595D03*
Y837744D03*
X1315330Y834595D03*
Y837744D03*
X1318480Y840894D03*
X1315330D03*
Y844044D03*
X1318480Y847193D03*
X1315330D03*
X1318480Y850343D03*
X1315330D03*
X1318480Y853492D03*
X1315330D03*
X1318480Y856642D03*
X1315330D03*
X1318480Y859792D03*
X1315330D03*
Y862941D03*
X1318480D03*
Y866091D03*
X1315330Y878689D03*
X1318480D03*
X1315330Y866091D03*
Y869240D03*
X1318480D03*
X1315330Y872390D03*
X1318480D03*
X1315330Y875540D03*
X1318480D03*
Y881839D03*
Y891288D03*
X1315330Y894437D03*
X1318480D03*
X1315330Y881839D03*
Y884988D03*
X1318480D03*
X1315330Y888138D03*
X1318480D03*
X1315330Y891288D03*
Y897587D03*
X1318480D03*
X1324779Y831445D03*
X1321629D03*
X1334228D03*
X1331078D03*
X1327929D03*
X1334228Y837744D03*
X1321629Y844044D03*
X1334228Y840894D03*
Y847193D03*
X1324779Y834595D03*
X1327929Y840894D03*
X1324779Y837744D03*
X1321629Y834595D03*
X1331078Y847193D03*
Y844044D03*
X1334228Y834595D03*
Y844044D03*
X1331078Y840894D03*
Y834595D03*
Y837744D03*
X1327929D03*
Y834595D03*
Y844044D03*
X1324779Y840894D03*
X1321629Y837744D03*
Y840894D03*
X1327929Y847193D03*
X1324779Y844044D03*
Y847193D03*
X1321629D03*
X1324779Y862941D03*
X1321629D03*
X1334228Y850343D03*
X1331078D03*
X1327929D03*
X1324779D03*
X1321629D03*
X1334228Y853492D03*
X1331078D03*
X1334228Y856642D03*
X1327929Y853492D03*
X1324779D03*
X1321629D03*
X1331078Y856642D03*
X1327929D03*
X1334228Y859792D03*
X1331078D03*
X1327929D03*
X1324779Y856642D03*
X1334228Y862941D03*
X1321629Y856642D03*
X1324779Y859792D03*
X1321629D03*
X1327929Y862941D03*
X1331078D03*
X1321629Y875540D03*
X1324779D03*
Y878689D03*
X1321629D03*
X1331078Y875540D03*
X1327929Y878689D03*
X1334228Y875540D03*
X1331078Y878689D03*
X1334228D03*
X1324779Y866091D03*
X1321629D03*
X1327929D03*
X1331078D03*
X1321629Y869240D03*
X1324779D03*
X1327929D03*
X1334228Y866091D03*
X1331078Y869240D03*
X1334228D03*
X1321629Y872390D03*
X1324779D03*
X1327929D03*
Y875540D03*
X1331078Y872390D03*
X1334228D03*
X1327929Y884988D03*
X1334228Y894437D03*
X1321629Y881839D03*
X1334228Y891288D03*
Y881839D03*
X1331078Y884988D03*
X1334228Y888138D03*
X1331078Y891288D03*
Y894437D03*
X1334228Y884988D03*
X1331078Y888138D03*
X1327929Y894437D03*
Y891288D03*
Y888138D03*
X1324779Y894437D03*
X1321629D03*
X1324779Y891288D03*
X1321629D03*
X1324779Y881839D03*
X1321629Y884988D03*
X1327929Y881839D03*
X1324779Y884988D03*
X1331078Y881839D03*
X1324779Y888138D03*
X1321629D03*
X1334228Y897587D03*
X1331078D03*
X1327929D03*
X1324779D03*
X1321629D03*
X1349976Y831445D03*
X1346826D03*
X1343677D03*
X1340527D03*
X1337377D03*
X1349976Y840894D03*
X1346826D03*
X1349976Y834595D03*
Y844044D03*
Y847193D03*
Y837744D03*
X1346826D03*
Y844044D03*
Y834595D03*
Y847193D03*
X1343677Y834595D03*
Y837744D03*
X1340527D03*
X1343677Y840894D03*
Y844044D03*
Y847193D03*
X1340527Y834595D03*
Y840894D03*
X1337377Y837744D03*
Y834595D03*
Y840894D03*
X1340527Y844044D03*
Y847193D03*
X1337377D03*
Y844044D03*
Y853492D03*
X1349976Y856642D03*
X1346826D03*
X1343677D03*
X1340527D03*
Y859792D03*
X1343677Y862941D03*
X1340527D03*
X1337377D03*
Y856642D03*
Y859792D03*
X1349976Y853492D03*
X1346826D03*
X1343677D03*
X1340527D03*
X1343677Y859792D03*
X1349976Y862941D03*
X1346826D03*
X1349976Y859792D03*
X1346826D03*
X1337377Y850343D03*
X1349976D03*
X1346826D03*
X1343677D03*
X1340527D03*
X1343677Y866091D03*
X1340527D03*
Y869240D03*
X1349976Y872390D03*
X1346826D03*
X1343677D03*
X1340527D03*
X1343677Y875540D03*
X1337377D03*
Y869240D03*
Y872390D03*
Y866091D03*
X1349976Y875540D03*
X1346826D03*
X1340527D03*
X1343677Y878689D03*
X1349976Y866091D03*
X1346826D03*
X1349976Y869240D03*
X1346826D03*
X1343677D03*
X1349976Y878689D03*
X1346826D03*
X1340527D03*
X1337377D03*
X1346826Y891288D03*
X1349976D03*
X1343677D03*
Y888138D03*
X1340527Y884988D03*
X1337377D03*
X1349976Y881839D03*
Y894437D03*
Y884988D03*
Y888138D03*
X1346826D03*
Y884988D03*
Y894437D03*
Y881839D03*
X1343677Y894437D03*
Y884988D03*
Y881839D03*
X1340527D03*
Y894437D03*
Y888138D03*
Y891288D03*
X1337377Y894437D03*
Y888138D03*
Y891288D03*
Y881839D03*
X1349976Y897587D03*
X1346826D03*
X1343677D03*
X1340527D03*
X1337377D03*
X1365724Y831445D03*
X1362574D03*
X1359425D03*
X1356275D03*
X1353125D03*
X1365724Y847193D03*
X1362574Y837744D03*
Y840894D03*
X1365724Y844044D03*
X1362574Y847193D03*
X1365724Y840894D03*
X1362574Y844044D03*
X1365724Y837744D03*
Y834595D03*
X1359425Y847193D03*
Y844044D03*
X1362574Y834595D03*
X1359425Y840894D03*
Y837744D03*
Y834595D03*
X1356275Y840894D03*
Y837744D03*
Y834595D03*
Y844044D03*
Y847193D03*
X1353125Y840894D03*
Y837744D03*
Y834595D03*
Y847193D03*
Y844044D03*
X1365724Y850343D03*
X1362574Y853492D03*
X1365724D03*
X1362574Y856642D03*
X1365724D03*
Y859792D03*
X1362574D03*
Y862941D03*
X1365724D03*
X1359425Y853492D03*
X1356275Y856642D03*
X1353125D03*
X1356275Y859792D03*
Y862941D03*
X1353125D03*
X1356275Y853492D03*
X1353125D03*
X1359425Y856642D03*
Y859792D03*
Y862941D03*
X1353125Y859792D03*
X1362574Y850343D03*
X1359425D03*
X1356275D03*
X1353125D03*
X1365724Y878689D03*
X1362574D03*
Y866091D03*
X1365724D03*
X1362574Y869240D03*
X1365724D03*
Y872390D03*
X1362574D03*
Y875540D03*
X1365724D03*
X1356275Y866091D03*
X1353125D03*
X1356275Y869240D03*
Y872390D03*
X1353125D03*
X1359425Y875540D03*
X1353125D03*
X1359425Y866091D03*
Y869240D03*
Y872390D03*
X1356275Y875540D03*
X1353125Y878689D03*
Y869240D03*
X1359425Y878689D03*
X1356275D03*
X1365724Y881839D03*
X1362574Y894437D03*
Y891288D03*
X1365724Y884988D03*
X1362574Y881839D03*
X1359425Y884988D03*
X1356275D03*
X1359425Y881839D03*
X1365724Y888138D03*
X1362574Y884988D03*
Y888138D03*
X1365724Y891288D03*
Y894437D03*
X1359425Y888138D03*
Y891288D03*
Y894437D03*
X1356275Y881839D03*
Y888138D03*
Y891288D03*
Y894437D03*
X1353125Y888138D03*
Y891288D03*
Y894437D03*
Y881839D03*
Y884988D03*
X1365724Y897587D03*
X1362574D03*
X1359425D03*
X1356275D03*
X1353125D03*
X1381472Y831445D03*
X1378322D03*
X1375173D03*
X1372023D03*
X1368873D03*
X1375173Y837744D03*
X1372023Y840894D03*
X1375173D03*
X1368873Y844044D03*
X1372023D03*
X1378322Y837744D03*
X1381472Y834595D03*
X1368873Y847193D03*
X1372023D03*
X1378322Y840894D03*
X1381472Y837744D03*
X1375173Y847193D03*
X1381472Y840894D03*
Y844044D03*
X1378322Y847193D03*
X1381472D03*
X1378322Y844044D03*
X1375173D03*
X1378322Y834595D03*
X1368873Y840894D03*
X1372023Y837744D03*
X1375173Y834595D03*
X1372023D03*
X1368873Y837744D03*
Y834595D03*
Y850343D03*
X1372023D03*
X1375173D03*
X1368873Y853492D03*
X1372023D03*
X1375173D03*
X1368873Y856642D03*
X1372023D03*
X1378322Y850343D03*
X1381472D03*
X1375173Y856642D03*
X1381472D03*
X1378322Y853492D03*
X1381472D03*
X1372023Y859792D03*
X1375173D03*
X1378322Y856642D03*
X1381472Y859792D03*
X1368873D03*
X1372023Y862941D03*
X1375173D03*
X1378322D03*
X1381472D03*
X1378322Y859792D03*
X1368873Y862941D03*
X1375173Y875540D03*
X1378322D03*
X1381472D03*
X1368873Y878689D03*
X1372023D03*
X1375173D03*
X1378322D03*
X1381472D03*
Y866091D03*
X1378322D03*
X1381472Y869240D03*
X1375173Y866091D03*
X1372023D03*
X1368873Y869240D03*
X1372023D03*
X1375173D03*
Y872390D03*
X1381472D03*
X1378322D03*
X1372023D03*
X1368873D03*
Y875540D03*
X1372023D03*
X1368873Y866091D03*
X1378322Y869240D03*
X1372023Y881839D03*
X1368873D03*
X1381472D03*
X1375173Y884988D03*
X1372023D03*
X1378322D03*
X1381472D03*
X1375173Y888138D03*
X1372023D03*
X1378322D03*
X1381472D03*
Y891288D03*
X1378322D03*
X1368873Y884988D03*
X1378322Y881839D03*
X1375173D03*
X1381472Y894437D03*
X1375173Y891288D03*
X1372023D03*
X1378322Y894437D03*
X1375173D03*
X1368873Y888138D03*
Y891288D03*
X1372023Y894437D03*
X1368873D03*
X1381472Y897587D03*
X1378322D03*
X1375173D03*
X1372023D03*
X1368873D03*
G54D102*
X115257Y1202289D03*
X106772Y1210774D03*
X118091Y1223388D03*
X129405Y1212075D03*
X126576Y1214903D03*
X120918Y1220560D03*
X572344Y1202289D03*
X563859Y1210774D03*
X586492Y1212075D03*
X583663Y1214903D03*
X578005Y1220560D03*
X575178Y1223388D03*
X1020945Y1210774D03*
X1029430Y1202289D03*
X1040749Y1214903D03*
X1043578Y1212075D03*
X1035091Y1220560D03*
X1032264Y1223388D03*
X1478032Y1210774D03*
X1486517Y1202289D03*
X1492178Y1220560D03*
X1497836Y1214903D03*
X1489351Y1223388D03*
X1500665Y1212075D03*
G54D120*
X360727Y453485D03*
X466821Y467960D03*
X817813Y447485D03*
X1274900Y453485D03*
X1731987D03*
G54D210*
X903297Y245669D03*
Y243307D03*
Y240945D03*
Y238583D03*
Y236221D03*
Y233858D03*
Y231496D03*
Y262205D03*
Y259843D03*
Y257480D03*
Y255118D03*
Y252756D03*
Y250394D03*
Y248032D03*
Y274016D03*
Y271654D03*
Y269291D03*
Y266929D03*
Y264567D03*
X915423Y245669D03*
Y243307D03*
Y240945D03*
Y238583D03*
Y236221D03*
Y233858D03*
Y231496D03*
Y262205D03*
Y259843D03*
Y257480D03*
Y255118D03*
Y252756D03*
Y250394D03*
Y248032D03*
Y274016D03*
Y271654D03*
Y269291D03*
Y266929D03*
Y264567D03*
G54D111*
X173829Y455492D03*
Y583957D03*
X202844Y455492D03*
Y583957D03*
X266841Y421555D03*
Y550020D03*
X295856Y421555D03*
Y550020D03*
X630915Y455492D03*
Y583957D03*
X659930Y455492D03*
Y583957D03*
X723927Y421555D03*
Y550020D03*
X752942Y421555D03*
Y550020D03*
X1088002Y455492D03*
Y583957D03*
X1117017Y455492D03*
Y583957D03*
X1181014Y421555D03*
Y550020D03*
X1210029Y421555D03*
Y550020D03*
X1545089Y455492D03*
Y583957D03*
X1574104Y455492D03*
Y583957D03*
X1638101Y421555D03*
Y550020D03*
X1667116Y421555D03*
Y550020D03*
G54D201*
X895384Y228740D03*
Y276772D03*
X923336Y226772D03*
Y278740D03*
G54D103*
X117356Y1204388D03*
X108871Y1212873D03*
X131504Y1214174D03*
X128675Y1217002D03*
X123017Y1222659D03*
X120190Y1225487D03*
X565958Y1212873D03*
X574443Y1204388D03*
X588591Y1214174D03*
X585762Y1217002D03*
X580104Y1222659D03*
X577277Y1225487D03*
X1023044Y1212873D03*
X1031529Y1204388D03*
X1042848Y1217002D03*
X1037190Y1222659D03*
X1034363Y1225487D03*
X1045677Y1214174D03*
X1480131Y1212873D03*
X1488616Y1204388D03*
X1494277Y1222659D03*
X1491450Y1225487D03*
X1502764Y1214174D03*
X1499935Y1217002D03*
G54D121*
X356790Y454076D03*
Y456044D03*
Y458012D03*
X364664D03*
Y456044D03*
Y454076D03*
X470758Y472487D03*
Y470519D03*
Y468551D03*
X462884Y472487D03*
Y470519D03*
Y468551D03*
X813876Y452012D03*
Y450044D03*
Y448076D03*
X821750Y452012D03*
Y450044D03*
Y448076D03*
X1270963Y458012D03*
Y456044D03*
Y454076D03*
X1278837Y458012D03*
Y456044D03*
Y454076D03*
X1735924Y458012D03*
Y456044D03*
Y454076D03*
X1728050Y458012D03*
Y456044D03*
Y454076D03*
G54D202*
X887685Y569450D03*
Y571419D03*
Y575356D03*
Y579293D03*
Y583230D03*
Y585199D03*
Y577325D03*
Y587167D03*
Y573387D03*
Y581261D03*
Y589136D03*
X912291Y571419D03*
Y569450D03*
Y585199D03*
Y581261D03*
Y577325D03*
Y579293D03*
Y587167D03*
Y573387D03*
Y575356D03*
Y583230D03*
Y589136D03*
X1010047Y322072D03*
Y326009D03*
Y327978D03*
Y324041D03*
Y329947D03*
Y333883D03*
Y337821D03*
Y339789D03*
Y331915D03*
Y341758D03*
Y335852D03*
X1034653Y327978D03*
Y326009D03*
Y324041D03*
Y322072D03*
Y341758D03*
Y337821D03*
Y335852D03*
Y331915D03*
Y339789D03*
Y333883D03*
Y329947D03*
G54D211*
X906811Y312857D03*
X908385D03*
X906811Y309235D03*
X908385D03*
G54D220*
X944695Y874268D03*
X950691Y857440D03*
X947541D03*
X950691Y861440D03*
X947541D03*
X947845Y874268D03*
G54D10*
X6385Y997697D03*
X22792Y997712D03*
X16647Y997670D03*
X11449Y997669D03*
X16463Y1536219D03*
X16080Y1541684D03*
X21080Y1543113D03*
X34987Y997724D03*
X29275Y997737D03*
X24074Y1496519D03*
X26017Y1543931D03*
X36364Y1544384D03*
X31221Y1544634D03*
X31105Y1549755D03*
X50285Y172879D03*
X51946Y997678D03*
X46108Y997664D03*
X40334Y997805D03*
X46818Y1544660D03*
X52264Y1545189D03*
X41522Y1545112D03*
X68448Y997793D03*
X62211Y997892D03*
X57214Y997884D03*
X57598Y1544760D03*
X61611Y1539765D03*
X77688Y847363D03*
X97033Y679427D03*
X111733Y154865D03*
X116731Y1052235D03*
X106619Y1056423D03*
X102431Y1066535D03*
X106619Y1076647D03*
X116731Y1080835D03*
Y1249086D03*
X106619Y1253274D03*
X102431Y1263386D03*
X106619Y1273498D03*
X116731Y1277686D03*
X126843Y1056423D03*
Y1076647D03*
X131031Y1066535D03*
X126843Y1253274D03*
X131031Y1263386D03*
X126843Y1273498D03*
X158929Y382600D03*
X159020Y465177D03*
X159044Y552674D03*
X158982Y564371D03*
Y559371D03*
X158198Y596321D03*
X159020Y591388D03*
X158220Y606190D03*
X159042Y601257D03*
X159046Y621005D03*
X159049Y611126D03*
X158242Y616069D03*
X158555Y637979D03*
X159023Y630886D03*
X158219Y625950D03*
X214095Y154865D03*
X213594Y462800D03*
X213662Y549469D03*
X213797Y554598D03*
X214000Y619500D03*
Y625400D03*
X241825Y380718D03*
X246141Y387884D03*
X244960Y393858D03*
X242398Y404718D03*
X242561Y412718D03*
X243278Y628696D03*
X248984Y628670D03*
X249867Y645941D03*
X243078Y645900D03*
X253186Y391496D03*
X252004Y384718D03*
X251601Y408718D03*
X252819Y400718D03*
X256091Y542712D03*
X256120Y620788D03*
X280600Y894200D03*
X279500Y904200D03*
X294841Y317911D03*
X286784Y858900D03*
X287471Y868900D03*
X288580Y929400D03*
X288084Y939400D03*
X310665Y540335D03*
X310756Y622912D03*
X316457Y154865D03*
X342840Y1056423D03*
X338652Y1066535D03*
X342840Y1076647D03*
X345631Y1174897D03*
X342399Y1198783D03*
X344444Y1211312D03*
X342840Y1253274D03*
X338652Y1263386D03*
X342840Y1273498D03*
X352952Y1052235D03*
Y1080835D03*
Y1249086D03*
Y1277686D03*
X363064Y1056423D03*
Y1076647D03*
X367252Y1066535D03*
X363064Y1253274D03*
X367252Y1263386D03*
X363064Y1273498D03*
X383900Y744100D03*
X384600Y750005D03*
X382607Y764500D03*
X386500Y782100D03*
X383200Y790225D03*
X411800Y790900D03*
X408967Y854329D03*
X416200Y786700D03*
X420400Y790700D03*
X423104Y892213D03*
X431600Y777564D03*
X466458Y154865D03*
X472148Y996052D03*
X477248D03*
X471443Y1001144D03*
X477248Y1001052D03*
X467878Y1042357D03*
X461897Y1041794D03*
X486623Y655447D03*
X491006Y1000497D03*
X484497Y1001466D03*
X491647Y1011963D03*
X492042Y1020491D03*
X491210Y1027453D03*
X499263Y665627D03*
X508833Y765565D03*
X495574Y1004176D03*
X495663Y1015420D03*
X497073Y1026059D03*
X501422Y1037680D03*
X526210Y768013D03*
X518782Y754155D03*
X556334Y755432D03*
X568820Y154865D03*
X567445Y738419D03*
X563706Y1056423D03*
X559518Y1066535D03*
X563706Y1076647D03*
Y1253274D03*
X559518Y1263386D03*
X563706Y1273498D03*
X575295Y743494D03*
X579444Y784955D03*
X584200Y790791D03*
X583930Y1056423D03*
X573818Y1052235D03*
X583930Y1076647D03*
X588118Y1066535D03*
X573818Y1080835D03*
X583930Y1253274D03*
X573818Y1249086D03*
X588118Y1263386D03*
X573818Y1277686D03*
X583930Y1273498D03*
X596871Y949646D03*
X616015Y382600D03*
X616106Y465177D03*
X616130Y552674D03*
X616068Y564371D03*
Y559371D03*
X616128Y601257D03*
X616106Y591388D03*
X615306Y606190D03*
X615284Y596321D03*
X616132Y621005D03*
X616135Y611126D03*
X615328Y616069D03*
X615641Y637979D03*
X615305Y625950D03*
X616109Y630886D03*
X610562Y648262D03*
X651602Y704366D03*
X671182Y154865D03*
X670680Y462800D03*
X670748Y549469D03*
X670770Y554598D03*
X671086Y619500D03*
Y625400D03*
X664168Y684077D03*
X661346Y763137D03*
X661846Y779137D03*
X661346Y771137D03*
Y787137D03*
X674416Y689694D03*
X674846Y763137D03*
X675346Y779137D03*
X674846Y771137D03*
Y787137D03*
X702046Y393858D03*
X700364Y628696D03*
X700164Y645900D03*
X699272Y707772D03*
X708305Y387884D03*
X709905Y400718D03*
X713206Y620788D03*
X706070Y628670D03*
X706953Y645941D03*
X711738Y691609D03*
X713401Y709949D03*
X721141Y730734D03*
X715607Y747977D03*
X716346Y760137D03*
X719846Y764137D03*
X716346Y768637D03*
X719846Y756137D03*
Y772637D03*
X724994Y690625D03*
X726897Y750559D03*
X751927Y317911D03*
X740530Y1524113D03*
X744188Y1624699D03*
X768460Y448957D03*
X767751Y540335D03*
X767842Y622912D03*
X760433Y1480906D03*
X756274Y1490945D03*
X760433Y1500984D03*
X754862Y1592302D03*
X753985Y1620898D03*
X773544Y154865D03*
X776094Y441165D03*
X774099Y446595D03*
X770545Y900475D03*
X780511Y1480906D03*
X770472Y1476747D03*
Y1505143D03*
X780511Y1500984D03*
X799926Y1056423D03*
X795738Y1066535D03*
X799926Y1076647D03*
X802291Y1211461D03*
X795411Y1212399D03*
X799926Y1253274D03*
X795738Y1263386D03*
X799926Y1273498D03*
X790361Y1447895D03*
X790754Y1441399D03*
X790296Y1463459D03*
X787038Y1460533D03*
X790989Y1455695D03*
X784670Y1490945D03*
X787885Y1631364D03*
X810040Y378544D03*
X805881Y388583D03*
X810040Y398622D03*
X813635Y762000D03*
X811279Y869693D03*
X809500Y887500D03*
X810500Y900000D03*
X810038Y1052235D03*
Y1080835D03*
X802606Y1175026D03*
X810038Y1249086D03*
Y1277686D03*
X825977Y327207D03*
X819977Y317368D03*
Y324648D03*
X820196Y332149D03*
X820079Y374385D03*
X830118Y378544D03*
X820079Y402781D03*
X830118Y398622D03*
X834282Y536085D03*
X827284Y721262D03*
X829484Y903759D03*
X820150Y1056423D03*
Y1076647D03*
X824338Y1066535D03*
X820150Y1253274D03*
X824338Y1263386D03*
X820150Y1273498D03*
X826204Y1444689D03*
X826219Y1455244D03*
X830400Y1473900D03*
X834277Y388583D03*
X843284Y721262D03*
X836284Y721273D03*
X850377Y1443959D03*
X850744Y1461959D03*
X847600Y1474100D03*
X865331Y717919D03*
X852284Y721273D03*
X865012Y727387D03*
X865567Y849885D03*
X861832Y846197D03*
X864760Y840928D03*
X861599Y836900D03*
X867179Y855265D03*
X861663Y853141D03*
X862776Y862467D03*
X863726Y872719D03*
X863091Y867659D03*
X863792Y877798D03*
X852774Y1001027D03*
X860514Y1000691D03*
X859900Y1008686D03*
X880138Y549603D03*
X879449Y568863D03*
X877339Y574408D03*
X879449Y562703D03*
X879055Y582828D03*
X875887Y682223D03*
X881836Y682219D03*
X869970Y704561D03*
X882765Y713846D03*
X879190Y821364D03*
X867858Y845174D03*
X867876Y836956D03*
X868123Y865298D03*
Y860298D03*
Y875298D03*
Y870298D03*
Y880298D03*
Y885298D03*
X879147Y896530D03*
X879664Y901568D03*
X874002Y1009399D03*
X868934Y1009274D03*
X879086Y1009110D03*
X878954Y1446432D03*
X878245Y1465859D03*
X875800Y1478600D03*
X878244Y1471359D03*
X889414Y544911D03*
X887939Y558338D03*
X893536Y558394D03*
X897689Y544660D03*
X891527Y728033D03*
X896161Y824930D03*
X889190Y821364D03*
X884190D03*
X899190Y821269D03*
X886664Y825717D03*
X894154Y896438D03*
X899103Y899321D03*
X889154Y896438D03*
X884154D03*
X896654Y903807D03*
X891654Y900773D03*
X886654D03*
X884110Y1009264D03*
X889202Y1009184D03*
X899313Y1009197D03*
X894225Y1009250D03*
X892616Y1446517D03*
X892101Y1467602D03*
X893200Y1478600D03*
X905114Y551773D03*
X903710Y544382D03*
X902236Y689332D03*
Y694332D03*
X906457Y723731D03*
X901226Y796828D03*
X904940Y821364D03*
X908378Y825308D03*
X901690Y825699D03*
X904154Y896438D03*
X914154D03*
X909154D03*
X901654Y903844D03*
X911654Y900773D03*
X906654D03*
X911352Y1012137D03*
X904484Y1011004D03*
X923544Y154865D03*
X920544Y570607D03*
X920870Y575763D03*
X919328Y685622D03*
X928672Y703241D03*
X929822Y709770D03*
X927662Y821009D03*
X925302Y825658D03*
X922431Y821308D03*
X924154Y896438D03*
X919154D03*
X916654Y900773D03*
X921654D03*
X926654D03*
X918503Y1009401D03*
X929069Y1009103D03*
X923576Y1009292D03*
X931159Y1379427D03*
X920360Y1387039D03*
X931199Y1371951D03*
X931159Y1390827D03*
Y1406027D03*
X920235Y1443493D03*
X921629Y1463235D03*
X921653Y1476971D03*
X937567Y306013D03*
X938858Y844582D03*
X938820Y836863D03*
X938984Y849888D03*
X939000Y863474D03*
X939042Y854928D03*
X945100Y852400D03*
X946482Y869624D03*
X939309Y879021D03*
X939269Y868921D03*
X938729Y874396D03*
X934525Y1009346D03*
X939966Y1009184D03*
X945166Y1009189D03*
X939559Y1398427D03*
X953692Y696577D03*
X955576Y1009333D03*
X960845Y1008941D03*
X950389Y1009350D03*
X972792Y710988D03*
X966466Y1009238D03*
X971798Y1009319D03*
X980018Y1009991D03*
X988192Y327561D03*
X994830Y326789D03*
X988045Y355812D03*
X1001443Y357523D03*
X1011862Y354276D03*
X1010827Y378544D03*
X1006668Y388583D03*
X1010827Y398622D03*
X1005814Y1351584D03*
X1025906Y154865D03*
X1025418Y310476D03*
X1018820Y311772D03*
X1013664Y311359D03*
X1025885Y352848D03*
X1020866Y374385D03*
Y402781D03*
X1020793Y1056423D03*
X1016605Y1066535D03*
X1020793Y1076647D03*
Y1253274D03*
X1016605Y1263386D03*
X1020793Y1273498D03*
X1021406Y1323530D03*
X1019109Y1353132D03*
X1024316Y1358339D03*
X1019330Y1380797D03*
X1041496Y311094D03*
X1030418Y310476D03*
X1045939Y332533D03*
X1030905Y378544D03*
X1035064Y388583D03*
X1030905Y398622D03*
X1037934Y847222D03*
X1029913Y853842D03*
X1038432Y946661D03*
X1041017Y1056423D03*
X1030905Y1052235D03*
X1041017Y1076647D03*
X1030905Y1080835D03*
X1041017Y1253274D03*
X1030905Y1249086D03*
Y1277686D03*
X1041017Y1273498D03*
X1034196Y1309624D03*
X1038996Y1376272D03*
X1050632Y314539D03*
X1047063Y361176D03*
X1053358Y826499D03*
X1045205Y1066535D03*
Y1263386D03*
X1049174Y1315612D03*
X1062053Y1437930D03*
X1053194Y1456493D03*
X1060433Y1480906D03*
X1056274Y1490945D03*
X1060433Y1500984D03*
X1073102Y382600D03*
X1073193Y465177D03*
X1073217Y552674D03*
X1073155Y564371D03*
Y559371D03*
X1073215Y601257D03*
X1072371Y596321D03*
X1073193Y591388D03*
X1072393Y606190D03*
X1072415Y616069D03*
X1073222Y611126D03*
X1073219Y621005D03*
X1072728Y637979D03*
X1072392Y625950D03*
X1073196Y630886D03*
X1070472Y1476747D03*
Y1505143D03*
X1080511Y1480906D03*
X1084670Y1490945D03*
X1080511Y1500984D03*
X1109113Y706901D03*
X1122228Y683055D03*
X1128268Y154865D03*
X1138571Y329148D03*
X1127767Y462800D03*
X1127857Y554598D03*
X1127835Y549469D03*
X1128173Y619500D03*
Y625400D03*
X1133869Y648421D03*
X1130970Y689694D03*
X1155998Y380718D03*
X1159133Y393858D03*
X1156571Y404718D03*
X1156734Y412718D03*
X1157451Y628696D03*
X1157251Y645900D03*
X1152485Y775642D03*
X1156485Y779142D03*
X1159485Y834142D03*
Y820642D03*
X1169668Y373503D03*
X1166177Y384718D03*
X1167359Y391496D03*
X1160314Y387884D03*
X1165774Y408718D03*
X1166992Y400718D03*
X1170264Y542712D03*
X1170293Y620788D03*
X1163157Y628670D03*
X1164040Y645941D03*
X1168985Y775642D03*
X1164985Y779142D03*
X1160485Y775642D03*
X1175485Y833642D03*
X1167485Y834142D03*
Y820642D03*
X1175485Y820142D03*
X1181155Y329703D03*
X1180312Y319267D03*
X1183485Y834142D03*
Y820642D03*
X1209014Y317911D03*
X1230630Y154865D03*
X1224838Y540335D03*
X1224929Y622912D03*
X1256938Y894863D03*
X1252825Y1066535D03*
X1252381Y1207061D03*
X1252825Y1263386D03*
X1268457Y864487D03*
Y854487D03*
Y859487D03*
Y879487D03*
Y869487D03*
Y874487D03*
Y889487D03*
Y884487D03*
X1261622Y907067D03*
X1267125Y1052235D03*
X1257013Y1056423D03*
Y1076647D03*
X1267125Y1080835D03*
X1259802Y1174426D03*
X1257411Y1211284D03*
X1272351Y1230750D03*
X1267125Y1249086D03*
X1257013Y1253274D03*
Y1273498D03*
X1267125Y1277686D03*
X1282055Y857317D03*
X1279822Y968916D03*
X1277237Y1056423D03*
Y1076647D03*
X1281425Y1066535D03*
X1277237Y1253274D03*
X1281425Y1263386D03*
X1277237Y1273498D03*
X1296770Y828775D03*
X1299990Y847500D03*
X1295943Y855500D03*
X1299855Y862312D03*
X1299488Y868440D03*
X1295758Y877783D03*
X1301482Y881783D03*
X1301314Y873484D03*
X1301379Y889783D03*
X1295799Y885783D03*
X1318063Y359511D03*
X1317000Y817500D03*
X1321000Y814200D03*
X1313000D03*
X1325007Y360259D03*
X1334071Y757675D03*
X1334340Y768876D03*
X1325000Y817500D03*
X1333000D03*
X1337000Y814200D03*
X1329000D03*
X1322500Y915300D03*
X1334500Y911643D03*
X1326500Y911500D03*
X1338500Y915300D03*
X1330500D03*
X1345000Y814200D03*
X1353000D03*
X1349000Y817500D03*
X1341000D03*
X1344500Y911500D03*
X1351380Y915164D03*
X1349566Y1102794D03*
X1365000Y817500D03*
X1368381Y814312D03*
X1357000Y817500D03*
X1361000Y814200D03*
X1368000Y911500D03*
X1364500Y915300D03*
X1361000Y911500D03*
X1356500Y915000D03*
X1380631Y154865D03*
X1380544Y815248D03*
X1371604Y817398D03*
X1384090Y817377D03*
X1375600Y814702D03*
X1382000Y911500D03*
X1371500Y915300D03*
X1378500D03*
X1375000Y911500D03*
X1386322Y996052D03*
X1385617Y1001144D03*
X1376071Y1041794D03*
X1382052Y1042357D03*
X1401583Y832491D03*
X1395998Y837744D03*
X1397000Y850343D03*
X1402500Y856000D03*
X1398909Y872000D03*
X1391422Y996052D03*
X1398671Y1001466D03*
X1391422Y1001052D03*
X1405180Y1000497D03*
X1405821Y1011963D03*
X1409748Y1004176D03*
X1406216Y1020491D03*
X1410397Y1027097D03*
X1405384Y1027452D03*
X1409837Y1015420D03*
X1415596Y1037680D03*
X1416396Y1538143D03*
X1416319Y1543379D03*
X1415241Y1556416D03*
X1415962Y1564320D03*
X1432806Y947059D03*
X1428212Y933016D03*
X1432818Y941439D03*
X1421560Y1511532D03*
X1431788Y1503314D03*
X1426593Y1503302D03*
X1424573Y1548351D03*
X1423817Y1569486D03*
X1443428Y1029000D03*
X1436448Y1549610D03*
X1444598Y1566170D03*
X1461585Y939543D03*
X1461441Y944864D03*
X1456669Y933701D03*
X1482993Y154865D03*
X1477879Y1056423D03*
X1473691Y1066535D03*
X1477879Y1076647D03*
Y1253274D03*
X1473691Y1263386D03*
X1477879Y1273498D03*
X1498103Y1056423D03*
X1487991Y1052235D03*
X1498103Y1076647D03*
X1487991Y1080835D03*
X1498103Y1253274D03*
X1487991Y1249086D03*
Y1277686D03*
X1498103Y1273498D03*
X1502291Y1066535D03*
Y1263386D03*
X1530189Y382600D03*
X1530280Y465177D03*
X1530304Y552674D03*
X1530242Y559371D03*
Y564371D03*
X1529458Y596321D03*
X1530302Y601257D03*
X1530280Y591388D03*
X1529480Y606190D03*
X1530309Y611126D03*
X1529502Y616069D03*
X1530306Y621005D03*
X1530283Y630886D03*
X1529815Y637979D03*
X1529479Y625950D03*
X1535221Y971822D03*
X1562810Y954054D03*
X1578448Y683787D03*
X1566655Y707314D03*
X1585355Y154865D03*
X1584854Y462800D03*
X1584944Y554598D03*
X1584922Y549469D03*
X1585260Y619500D03*
Y625400D03*
X1586978Y652399D03*
X1590707Y1451470D03*
X1587746Y1465452D03*
X1613085Y380718D03*
X1613658Y404718D03*
X1613821Y412718D03*
X1614538Y628696D03*
X1614338Y645900D03*
X1608750Y788150D03*
X1603251Y797012D03*
X1609400Y803800D03*
X1609800Y817300D03*
X1602595Y802852D03*
X1603966Y816799D03*
X1602862Y829738D03*
X1611522Y1540314D03*
X1617925Y370700D03*
X1616220Y393858D03*
X1624446Y391496D03*
X1617401Y387884D03*
X1623264Y384718D03*
X1622861Y408718D03*
X1624079Y400718D03*
X1627351Y542712D03*
X1627380Y620788D03*
X1620244Y628670D03*
X1621127Y645941D03*
X1621111Y687047D03*
X1620600Y699930D03*
X1620500Y717830D03*
X1621200Y732430D03*
X1621700Y750630D03*
X1616655Y769300D03*
X1629500Y782300D03*
X1629700Y795700D03*
X1628400Y809400D03*
X1625500Y826900D03*
X1639300Y708900D03*
X1640100Y723200D03*
X1635300Y743400D03*
X1634541Y761759D03*
X1666101Y317911D03*
X1687717Y154865D03*
X1681925Y540335D03*
X1682016Y622912D03*
X1709912Y1066535D03*
Y1263386D03*
X1724212Y1052235D03*
X1714100Y1056423D03*
Y1076647D03*
X1724212Y1080835D03*
X1716700Y1174526D03*
X1724212Y1249086D03*
X1714100Y1253274D03*
Y1273498D03*
X1724212Y1277686D03*
X1734324Y1056423D03*
Y1076647D03*
X1738512Y1066535D03*
X1729553Y1230788D03*
X1734324Y1253274D03*
X1738512Y1263386D03*
X1734324Y1273498D03*
X1757879Y879213D03*
X1757933Y897260D03*
X1757914Y884667D03*
X1757805Y913336D03*
X1757275Y926200D03*
X1756060Y1010750D03*
X1761745Y1010616D03*
X1773278Y1010643D03*
X1767133Y1010601D03*
X1782357Y919151D03*
X1789774Y918954D03*
X1790820Y1010736D03*
X1779761Y1010668D03*
X1785473Y1010655D03*
X1782088Y1430956D03*
X1786936Y1467917D03*
X1804600Y910175D03*
X1795764Y918695D03*
X1796594Y1010595D03*
X1807688Y1010616D03*
X1802432Y1010609D03*
X1795100Y1463678D03*
X1795147Y1478147D03*
X1814900Y907025D03*
X1813114Y973235D03*
X1818934Y1010724D03*
X1812697D03*
X1903466Y2079348D03*
X1915566D03*
X1927666Y2067248D03*
Y2079348D03*
X1949818Y2056098D03*
X1939605Y2057393D03*
G54D112*
X190325Y368760D03*
X279360Y636752D03*
X647411Y368760D03*
X736446Y636752D03*
X1104498Y368760D03*
X1193533Y636752D03*
X1561585Y368760D03*
X1650620Y636752D03*
G54D130*
X393536Y780320D03*
X395505D03*
X397473D03*
X399442D03*
X401410D03*
X403379D03*
X405347D03*
X407316D03*
X409284D03*
X411253D03*
X413221D03*
X415190D03*
X417158D03*
X419127D03*
X421095D03*
X423064D03*
X1766236Y912920D03*
X1768205D03*
X1770173D03*
X1772142D03*
X1774110D03*
X1776079D03*
X1778047D03*
X1780016D03*
X1781984D03*
X1783953D03*
X1785921D03*
X1787890D03*
X1789858D03*
X1791827D03*
X1793795D03*
X1795764D03*
G54D122*
X361815Y1221308D03*
X818902D03*
X1275988D03*
X1733075D03*
G54D20*
X9272Y105001D03*
X16773Y242078D03*
X12803Y248371D03*
X16773Y262078D03*
X12803Y268371D03*
X12173Y1496782D03*
X9515Y1556883D03*
X25879Y51296D03*
Y55305D03*
X29787Y67527D03*
Y63527D03*
Y59527D03*
X27897Y106495D03*
X32415Y177448D03*
X24581Y206864D03*
X23752Y242078D03*
Y262078D03*
X33414Y250599D03*
Y270599D03*
X26537Y292608D03*
X34753Y281272D03*
X31457Y536726D03*
Y531726D03*
Y552726D03*
Y540726D03*
Y544726D03*
X33175Y629311D03*
Y625311D03*
X48384Y177606D03*
X41288Y478982D03*
Y483982D03*
Y487982D03*
Y499982D03*
Y491982D03*
X43582Y597393D03*
X50237Y631212D03*
X43674Y1093757D03*
X42510Y1248448D03*
X59232Y847718D03*
X53207Y1072761D03*
X67567Y1091656D03*
X61268Y1213720D03*
X65386Y1544571D03*
X77258Y151540D03*
X80717Y168697D03*
X80912Y191941D03*
X82881Y224321D03*
X83259Y571614D03*
Y575614D03*
X72002Y575841D03*
X81797Y686107D03*
X71718Y843118D03*
X97869Y149768D03*
X104805Y192665D03*
Y196665D03*
X104900Y204864D03*
X115165Y252371D03*
X130268Y106495D03*
X126943Y206864D03*
X119135Y242078D03*
X126114D03*
X135776Y250599D03*
X147171Y554555D03*
Y558555D03*
Y562555D03*
X154083Y382600D03*
Y463600D03*
X153451Y595588D03*
Y591588D03*
X153483Y603600D03*
X153451Y599588D03*
X153483Y611600D03*
Y619600D03*
X153451Y607588D03*
X153483Y615600D03*
Y623600D03*
Y627600D03*
Y637969D03*
Y641974D03*
X179620Y151540D03*
X196981Y68581D03*
Y80581D03*
X183079Y168697D03*
X183274Y191941D03*
X185243Y224321D03*
X206306Y58013D03*
X202524Y114488D03*
X200231Y149768D03*
X207167Y196665D03*
Y192665D03*
X207262Y204864D03*
X229305Y206864D03*
X221497Y242078D03*
X228476D03*
X217527Y252371D03*
X221283Y458800D03*
X230083Y553700D03*
X221483Y545800D03*
X230083Y557700D03*
X230527Y1474522D03*
X230526Y1478442D03*
Y1486442D03*
X232621Y106495D03*
X238138Y250599D03*
X233747Y384718D03*
Y380718D03*
Y392718D03*
Y396718D03*
Y400718D03*
Y404718D03*
Y408718D03*
Y412718D03*
X244908Y675832D03*
X232526Y1510442D03*
X232531Y1518578D03*
X252183Y453873D03*
Y458859D03*
X251368Y542712D03*
X249369Y816300D03*
X248369Y836800D03*
X249368Y1506058D03*
X251668Y1517958D03*
X281982Y151540D03*
X285441Y168697D03*
X285636Y191941D03*
X287605Y224321D03*
X312164Y35007D03*
X308668Y58013D03*
X299343Y68581D03*
Y80581D03*
X304886Y114488D03*
X302593Y149768D03*
X309529Y192665D03*
Y196665D03*
X309624Y204864D03*
X323859Y242078D03*
X319889Y252371D03*
X326940Y306652D03*
X318568Y545912D03*
Y626912D03*
X334983Y106495D03*
X331667Y206864D03*
X330838Y242078D03*
X340500Y250599D03*
X350508Y458334D03*
Y450334D03*
X346908Y1146071D03*
X360881Y1170370D03*
X354250Y1191599D03*
X371383Y488816D03*
X377369Y764500D03*
X366951Y943480D03*
X375915Y959812D03*
Y955812D03*
Y951812D03*
Y963812D03*
Y967812D03*
Y971812D03*
X387803Y168697D03*
X387998Y191941D03*
X389967Y224321D03*
X391151Y470382D03*
X379069Y745300D03*
X392678Y868286D03*
X387500Y1547700D03*
Y1555700D03*
X407248Y114488D03*
X407039Y331589D03*
Y335589D03*
X402784Y467560D03*
Y479560D03*
X405871Y889786D03*
X407448Y1446807D03*
X419958Y35983D03*
X411891Y192665D03*
Y196665D03*
X411986Y204864D03*
X418616Y425413D03*
X421156Y455301D03*
Y459101D03*
Y463101D03*
X424784Y474560D03*
X414272Y889551D03*
X413684Y1523296D03*
X431983Y151540D03*
X427099Y1537088D03*
X427619Y1550211D03*
X452594Y149768D03*
X455642Y328285D03*
Y324685D03*
Y344033D03*
Y340433D03*
Y336159D03*
Y332559D03*
Y351907D03*
Y348307D03*
X443656Y424601D03*
Y428101D03*
Y431601D03*
X456602Y464809D03*
Y472809D03*
X445923Y508999D03*
X453460Y638279D03*
X456768Y1012325D03*
Y1016325D03*
X448574Y1022766D03*
Y1034266D03*
Y1030266D03*
X455652Y1043140D03*
X455575Y1047047D03*
X473860Y242078D03*
X469890Y252371D03*
X465886Y495669D03*
Y516609D03*
X459268Y1002180D03*
Y1007180D03*
X484984Y106495D03*
X481668Y206864D03*
X480839Y242078D03*
X490501Y250599D03*
X488393Y387089D03*
Y391589D03*
X488543Y536726D03*
Y531726D03*
Y544726D03*
Y540726D03*
X490261Y629311D03*
Y625311D03*
X481845Y652906D03*
X485268Y1031680D03*
X498374Y478982D03*
Y483982D03*
Y487982D03*
Y499982D03*
Y491982D03*
X500668Y597393D03*
X507323Y631212D03*
X502586Y660441D03*
X504074Y1004766D03*
Y996766D03*
Y1008766D03*
X503941Y1020258D03*
X504074Y1030766D03*
X494268Y1032180D03*
X518690Y749443D03*
X508077Y989235D03*
X512074Y1000766D03*
Y1004766D03*
Y996766D03*
Y1016266D03*
Y1020266D03*
Y1030766D03*
X534345Y151540D03*
X537804Y168697D03*
X537999Y191941D03*
X539968Y224321D03*
X538669Y345723D03*
Y359223D03*
Y354723D03*
Y350223D03*
Y363723D03*
Y377223D03*
Y372723D03*
Y368223D03*
Y386223D03*
Y390723D03*
X529088Y575841D03*
X535507Y779889D03*
X532169Y840700D03*
X551706Y68581D03*
Y80581D03*
X554956Y149768D03*
X548669Y345723D03*
Y350223D03*
Y359223D03*
Y354723D03*
Y377223D03*
Y372723D03*
Y368223D03*
Y363723D03*
Y381723D03*
X540345Y571614D03*
Y575614D03*
X552956Y684509D03*
Y700509D03*
Y688509D03*
Y692509D03*
Y696509D03*
Y704509D03*
Y708509D03*
Y712509D03*
Y716509D03*
Y720509D03*
X555609Y841388D03*
X561031Y58013D03*
X557249Y114488D03*
X561892Y192665D03*
Y196665D03*
X561987Y204864D03*
X572252Y252371D03*
X570486Y747079D03*
X587346Y106495D03*
X584030Y206864D03*
X583201Y242078D03*
X576222D03*
X588772Y957207D03*
X576286Y961807D03*
X588415Y1509687D03*
X592863Y250599D03*
X604257Y554555D03*
Y558555D03*
Y562555D03*
X597968Y1493658D03*
Y1497558D03*
X598068Y1501458D03*
X594164Y1505794D03*
X611169Y382600D03*
Y463600D03*
X610537Y595588D03*
Y591588D03*
X610569Y603600D03*
X610537Y599588D03*
X610569Y611600D03*
Y619600D03*
X610537Y607588D03*
X610569Y615600D03*
Y623600D03*
Y627600D03*
Y637969D03*
Y641974D03*
X636707Y151540D03*
X640166Y168697D03*
X640361Y191941D03*
X642330Y224321D03*
X663393Y58013D03*
X654068Y68581D03*
Y80581D03*
X659611Y114488D03*
X657318Y149768D03*
X664254Y192665D03*
Y196665D03*
X664349Y204864D03*
X658810Y666275D03*
X660926Y710129D03*
X678584Y242078D03*
X685563D03*
X674614Y252371D03*
X678369Y458800D03*
X678569Y545800D03*
Y558800D03*
Y562800D03*
X689708Y106495D03*
X686392Y206864D03*
X695225Y250599D03*
X690833Y384718D03*
Y380718D03*
Y392718D03*
Y396718D03*
Y400718D03*
Y404718D03*
Y408718D03*
Y412718D03*
X687169Y553700D03*
Y557700D03*
X701994Y675832D03*
X709269Y453873D03*
Y458859D03*
X708454Y542712D03*
X716258Y696718D03*
X713333Y783453D03*
X727829Y756137D03*
Y764137D03*
X720179Y779958D03*
X727829Y768137D03*
Y772137D03*
X739069Y151540D03*
X742528Y168697D03*
X742723Y191941D03*
X744692Y224321D03*
X735883Y1606600D03*
X735234Y1634485D03*
X735250Y1630030D03*
X765755Y58013D03*
X756430Y68581D03*
Y80581D03*
X761973Y114488D03*
X759680Y149768D03*
X766616Y196665D03*
Y192665D03*
X766711Y204864D03*
X780946Y242078D03*
X776976Y252371D03*
X775654Y545912D03*
Y626912D03*
X783232Y1427432D03*
Y1431432D03*
Y1439432D03*
X781486Y1458066D03*
X774615Y1449870D03*
X792070Y106495D03*
X788754Y206864D03*
X787925Y242078D03*
X797587Y250599D03*
X784026Y306652D03*
X784575Y442498D03*
X784607Y450510D03*
Y446510D03*
X799327Y1436559D03*
X807594Y444334D03*
Y452334D03*
X811807Y836919D03*
X815307Y893419D03*
X803995Y1146071D03*
X806327Y1436559D03*
X807988Y1476616D03*
X828469Y483816D03*
X829983Y758500D03*
Y762500D03*
Y780500D03*
Y776500D03*
Y794500D03*
Y798500D03*
Y812500D03*
Y816500D03*
X822217Y830038D03*
X819807Y900919D03*
X817925Y1171120D03*
X844890Y168697D03*
X845085Y191941D03*
X847054Y224321D03*
X848237Y465382D03*
X845768Y831558D03*
X839299Y839953D03*
X845840Y839292D03*
X842941Y879459D03*
X845728Y875507D03*
X843251Y871459D03*
X842941Y883459D03*
X844161Y892564D03*
X842848Y887490D03*
X837983Y901500D03*
X845214Y1440859D03*
X834187Y1444849D03*
X845227Y1448959D03*
Y1444959D03*
Y1457959D03*
X858792Y68581D03*
Y80581D03*
X864335Y114488D03*
X863744Y713170D03*
Y705170D03*
X864483Y768000D03*
Y786000D03*
Y804000D03*
Y822000D03*
X856711Y831469D03*
X856742Y843459D03*
Y847459D03*
Y839459D03*
Y863459D03*
Y859459D03*
Y855459D03*
Y851459D03*
Y867459D03*
Y879459D03*
Y875459D03*
Y871459D03*
Y892959D03*
Y883459D03*
Y887759D03*
X868117Y58013D03*
X868978Y192665D03*
Y196665D03*
X869073Y204864D03*
X875567Y337342D03*
X866937Y491303D03*
Y479303D03*
X872551Y554703D03*
Y558703D03*
Y574703D03*
Y586828D03*
X871977Y698388D03*
X889069Y151540D03*
X883460Y309368D03*
Y305368D03*
Y313368D03*
Y325368D03*
Y321368D03*
Y317368D03*
Y329368D03*
Y337342D03*
Y333368D03*
X888937Y486303D03*
X895483Y529633D03*
X881744Y686970D03*
Y698970D03*
X886744Y718570D03*
X890364Y1102760D03*
X886200Y1257451D03*
X886727Y1440859D03*
Y1448859D03*
Y1464859D03*
X886702Y1452663D03*
X886727Y1472859D03*
X909680Y149768D03*
X902243Y362369D03*
Y370369D03*
X913636Y547348D03*
X909944Y683770D03*
Y695770D03*
Y699770D03*
X899897Y1081764D03*
X904958Y1222723D03*
X919828Y304585D03*
X913942Y441754D03*
X916482Y471642D03*
Y479442D03*
Y475442D03*
X929135Y561578D03*
Y565578D03*
X929119Y585578D03*
Y589578D03*
X929135Y594329D03*
Y598329D03*
X923933Y704111D03*
X914257Y1104659D03*
Y1100659D03*
X924711Y1472100D03*
X942070Y106495D03*
X939420Y192035D03*
X945626Y236866D03*
X930635Y305255D03*
X941660Y351281D03*
X938982Y440942D03*
Y444442D03*
Y447942D03*
X945630Y536726D03*
Y531726D03*
Y544726D03*
Y540726D03*
X939353Y883790D03*
X939355Y887508D03*
X947572Y316739D03*
X955461Y478982D03*
Y483982D03*
Y487982D03*
Y499982D03*
Y491982D03*
X957755Y597393D03*
X947348Y629311D03*
Y625311D03*
X952667Y792505D03*
X957540Y846665D03*
X950626Y846635D03*
X947753Y878216D03*
X956181Y870278D03*
X947897Y899890D03*
X954341Y1102760D03*
X950177Y1257451D03*
X964410Y631212D03*
X963874Y1081764D03*
X978234Y1100659D03*
Y1104659D03*
X968935Y1222723D03*
X991431Y151540D03*
X982608Y338972D03*
X981089Y343112D03*
X982608Y331972D03*
X981089Y346612D03*
X986175Y575841D03*
X982604Y848597D03*
X984686Y837159D03*
X986918Y1104622D03*
X986955Y1100302D03*
X1008792Y68581D03*
Y80581D03*
X994890Y168697D03*
X995085Y191941D03*
X997054Y224321D03*
X997432Y571614D03*
Y575614D03*
X1018117Y58013D03*
X1014335Y114488D03*
X1012042Y149768D03*
X1018978Y196665D03*
Y192665D03*
X1011654Y196620D03*
X1019073Y204864D03*
X1018186Y837659D03*
X1017902Y958822D03*
X1013991Y1353714D03*
X1013944Y1363533D03*
X1013966Y1372734D03*
X1013961Y1376752D03*
X1041116Y206864D03*
X1033308Y242078D03*
X1040287D03*
X1029338Y252371D03*
X1032971Y847222D03*
X1030388Y954222D03*
X1044432Y106495D03*
X1049949Y250599D03*
X1058708Y314539D03*
Y322843D03*
Y328156D03*
Y319243D03*
X1058595Y339509D03*
X1058708Y331756D03*
X1058187Y360151D03*
Y364276D03*
X1068256Y382600D03*
Y463600D03*
X1061344Y554555D03*
Y558555D03*
Y562555D03*
X1067624Y595588D03*
Y591588D03*
X1067656Y603600D03*
X1067624Y599588D03*
X1067656Y611600D03*
Y619600D03*
X1067624Y607588D03*
X1067656Y615600D03*
Y623600D03*
Y627600D03*
Y637969D03*
Y641974D03*
X1093793Y151540D03*
X1097252Y168697D03*
X1097447Y191941D03*
X1099416Y224321D03*
X1120479Y58013D03*
X1111154Y68581D03*
Y80581D03*
X1116697Y114488D03*
X1114404Y149768D03*
X1112961Y168713D03*
X1121340Y192665D03*
Y196665D03*
X1121435Y204864D03*
X1120483Y329000D03*
Y334000D03*
Y339000D03*
X1115897Y666275D03*
X1118013Y710129D03*
X1135670Y242078D03*
X1131700Y252371D03*
X1128983Y329000D03*
Y334000D03*
Y339000D03*
X1135456Y458800D03*
X1135656Y545800D03*
Y558800D03*
Y562800D03*
X1146794Y106495D03*
X1143478Y206864D03*
X1142649Y242078D03*
X1152311Y250599D03*
X1147920Y392718D03*
Y384718D03*
Y380718D03*
Y404718D03*
Y408718D03*
Y396718D03*
Y400718D03*
Y412718D03*
X1144256Y553700D03*
Y557700D03*
X1166356Y453873D03*
Y458859D03*
X1165541Y542712D03*
X1159081Y675832D03*
X1187067Y324142D03*
X1177653Y774434D03*
X1196155Y151540D03*
X1199614Y168697D03*
X1199809Y191941D03*
X1201778Y224321D03*
X1191947Y329398D03*
X1213516Y68581D03*
Y80581D03*
X1219059Y114488D03*
X1216766Y149768D03*
X1215323Y168713D03*
X1222841Y58013D03*
X1223702Y192665D03*
Y196665D03*
X1223797Y204864D03*
X1238032Y242078D03*
X1234062Y252371D03*
X1232741Y545912D03*
Y626912D03*
X1249156Y106495D03*
X1245840Y206864D03*
X1245011Y242078D03*
X1254673Y250599D03*
X1241113Y306652D03*
X1260983Y336000D03*
X1264681Y450334D03*
Y458334D03*
X1264677Y894866D03*
X1261081Y1146071D03*
X1255923Y1192376D03*
X1260168Y1523458D03*
X1260129Y1527334D03*
X1260168Y1543558D03*
X1260129Y1531334D03*
Y1539334D03*
X1260153Y1535385D03*
X1285556Y488816D03*
X1284997Y768576D03*
Y780576D03*
X1276654Y848145D03*
X1276750Y864487D03*
Y859487D03*
X1276738Y852029D03*
X1276750Y874487D03*
Y869487D03*
Y879487D03*
Y889487D03*
Y884487D03*
X1286983Y919500D03*
X1283359Y933598D03*
X1275011Y1171120D03*
X1301976Y168697D03*
X1302171Y191941D03*
X1298483Y326500D03*
Y337000D03*
Y330000D03*
Y333500D03*
X1290983Y819500D03*
Y839500D03*
Y843500D03*
Y847500D03*
Y851500D03*
Y863500D03*
Y867000D03*
X1290978Y885783D03*
X1317685Y168713D03*
X1304140Y224321D03*
X1305324Y470382D03*
X1316957Y467560D03*
Y479560D03*
X1303983Y942500D03*
X1334131Y35983D03*
X1321421Y114488D03*
X1326064Y196665D03*
Y192665D03*
X1326159Y204864D03*
X1332789Y425413D03*
X1335329Y455301D03*
Y459101D03*
Y463101D03*
X1332483Y558500D03*
Y562500D03*
Y566500D03*
X1324483D03*
X1332483Y574500D03*
Y586500D03*
Y578500D03*
Y582500D03*
X1324483D03*
Y586500D03*
X1332483Y590500D03*
Y605000D03*
X1324483Y590500D03*
X1332483Y609000D03*
Y613000D03*
Y621000D03*
X1324483Y613000D03*
X1332483Y637000D03*
Y633000D03*
Y625000D03*
Y629000D03*
X1324483D03*
Y633000D03*
Y637000D03*
X1332483Y653500D03*
Y649500D03*
X1324483Y645000D03*
X1332483Y665500D03*
Y657500D03*
X1324483D03*
X1332483Y669500D03*
X1324483Y677500D03*
Y681500D03*
Y673500D03*
X1332483D03*
Y681500D03*
Y677500D03*
Y696500D03*
Y700500D03*
X1324483Y704500D03*
X1332483D03*
Y712500D03*
Y716500D03*
X1324483Y720500D03*
Y728500D03*
Y724500D03*
X1332483Y728500D03*
Y724500D03*
Y720500D03*
X1324453Y736464D03*
X1346156Y151540D03*
X1338957Y474560D03*
X1342276Y749675D03*
Y745675D03*
Y741675D03*
Y737675D03*
Y765675D03*
Y761675D03*
Y757675D03*
Y753675D03*
Y769675D03*
Y781675D03*
X1366767Y149768D03*
X1358227Y327777D03*
Y331377D03*
Y335651D03*
Y339251D03*
Y343525D03*
Y347125D03*
Y351399D03*
Y354999D03*
X1357829Y424601D03*
Y428101D03*
Y431601D03*
X1362748Y1022766D03*
Y1034266D03*
Y1030266D03*
X1384063Y252371D03*
X1373442Y1002180D03*
Y1007180D03*
X1370942Y1012325D03*
Y1016325D03*
X1369826Y1043140D03*
X1369749Y1047047D03*
X1399157Y106495D03*
X1395841Y206864D03*
X1395012Y242078D03*
X1388033D03*
X1390934Y361371D03*
Y356871D03*
X1388569Y577192D03*
X1388570Y627817D03*
X1399442Y1031680D03*
X1404674Y250599D03*
X1412548Y478982D03*
Y483982D03*
Y487982D03*
Y499982D03*
Y491982D03*
X1402717Y536726D03*
Y531726D03*
Y544726D03*
Y540726D03*
X1414842Y597393D03*
X1404435Y629311D03*
Y625311D03*
X1402483Y652000D03*
Y660000D03*
X1415483Y689000D03*
X1402483Y703000D03*
Y707000D03*
X1415483Y705000D03*
Y713000D03*
Y709000D03*
Y733000D03*
X1415452Y720894D03*
X1415483Y749000D03*
Y753000D03*
Y757000D03*
X1415506Y765343D03*
X1411081Y815683D03*
X1410983Y832000D03*
Y828000D03*
X1410932Y823934D03*
X1410885Y819817D03*
X1410983Y848000D03*
Y840000D03*
Y836000D03*
Y852000D03*
Y864000D03*
Y856000D03*
Y880000D03*
Y868000D03*
Y884000D03*
Y896000D03*
Y900000D03*
X1414052Y992307D03*
X1408442Y1032180D03*
X1411594Y1539557D03*
X1411102Y1562235D03*
X1421497Y631212D03*
X1423483Y681000D03*
Y685000D03*
Y689000D03*
Y697000D03*
Y701000D03*
Y713000D03*
Y709000D03*
Y705000D03*
Y725000D03*
Y729000D03*
Y733000D03*
Y741000D03*
Y745000D03*
Y749000D03*
Y753000D03*
Y757000D03*
X1432483Y774500D03*
Y798500D03*
Y790500D03*
Y794500D03*
Y818500D03*
Y834500D03*
Y838500D03*
Y842500D03*
X1421197Y939292D03*
X1428064Y951563D03*
X1428004Y947595D03*
X1418248Y1004766D03*
X1426248Y1000766D03*
X1418248Y996766D03*
Y1008766D03*
X1426248Y1004766D03*
Y996766D03*
Y1016266D03*
X1418252Y1020250D03*
X1426248Y1020266D03*
X1418248Y1030766D03*
X1426248D03*
X1426454Y1494706D03*
X1429424Y1524252D03*
X1448518Y151540D03*
X1446190Y320861D03*
Y325361D03*
Y329861D03*
Y334361D03*
Y338861D03*
Y343361D03*
Y347861D03*
Y352361D03*
Y356861D03*
X1443262Y575841D03*
X1440483Y766500D03*
Y774500D03*
Y770500D03*
Y782500D03*
Y798500D03*
Y794500D03*
Y790500D03*
Y786500D03*
Y814500D03*
Y810500D03*
Y830500D03*
Y826500D03*
Y818500D03*
Y834500D03*
Y838500D03*
Y842500D03*
X1465879Y68581D03*
Y80581D03*
X1451977Y168697D03*
X1452172Y191941D03*
X1454141Y224321D03*
X1456190Y320861D03*
Y325361D03*
Y329861D03*
Y334361D03*
Y338861D03*
Y343361D03*
Y347861D03*
Y352361D03*
X1454519Y571614D03*
Y575614D03*
X1459601Y950980D03*
X1479880Y38244D03*
X1475204Y58013D03*
X1471422Y114488D03*
X1469129Y149768D03*
X1467686Y168713D03*
X1476065Y196665D03*
Y192665D03*
X1476160Y204864D03*
X1469600Y947600D03*
X1498203Y206864D03*
X1490395Y242078D03*
X1497374D03*
X1486425Y252371D03*
X1493029Y358700D03*
Y354200D03*
X1484983Y685630D03*
X1485483Y727500D03*
X1501519Y106495D03*
X1507036Y250599D03*
X1502483Y769000D03*
Y813000D03*
X1500266Y907240D03*
X1525343Y382600D03*
Y463600D03*
X1518431Y554555D03*
Y558555D03*
Y562555D03*
X1524711Y595588D03*
Y591588D03*
X1524743Y603600D03*
X1524711Y599588D03*
X1524743Y611600D03*
Y619600D03*
X1524711Y607588D03*
X1524743Y615600D03*
Y623600D03*
Y627600D03*
Y637969D03*
Y641974D03*
X1520368Y968739D03*
X1546630Y969737D03*
X1550880Y151540D03*
X1554339Y168697D03*
X1554534Y191941D03*
X1556503Y224321D03*
X1561362Y316363D03*
Y325363D03*
X1551362Y316363D03*
Y325363D03*
X1561362Y329863D03*
Y334363D03*
Y343363D03*
X1551362Y329863D03*
Y334363D03*
Y343363D03*
X1561362Y352363D03*
X1577566Y58013D03*
X1568241Y68581D03*
Y80581D03*
X1573784Y114488D03*
X1571491Y149768D03*
X1570048Y168713D03*
X1578427Y192665D03*
Y196665D03*
X1578522Y204864D03*
X1574683Y341600D03*
X1572984Y666275D03*
X1575100Y710129D03*
X1592757Y242078D03*
X1588787Y252371D03*
X1592543Y458800D03*
X1592743Y545800D03*
X1593791Y1442557D03*
X1603881Y106495D03*
X1600565Y206864D03*
X1599736Y242078D03*
X1609398Y250599D03*
X1611780Y336252D03*
Y344252D03*
Y340252D03*
X1605007Y384718D03*
Y380718D03*
Y392718D03*
Y400718D03*
Y404718D03*
Y408718D03*
Y396718D03*
Y412718D03*
X1601343Y553700D03*
Y557700D03*
X1602349Y1468023D03*
X1606586Y1527334D03*
X1623443Y453873D03*
Y458859D03*
X1622628Y542712D03*
X1616168Y675832D03*
X1614085Y699917D03*
Y717817D03*
X1614385Y732417D03*
X1619485Y828117D03*
X1615668Y1528558D03*
X1619268Y1539358D03*
X1615368Y1535258D03*
X1634085Y711417D03*
X1641485Y728117D03*
X1630485Y744317D03*
X1629785Y762717D03*
X1643733Y881999D03*
X1644081Y917241D03*
X1643839Y952125D03*
X1653242Y151540D03*
X1656701Y168697D03*
X1656896Y191941D03*
X1658865Y224321D03*
X1651298Y871345D03*
X1651835Y909279D03*
X1651442Y942136D03*
X1670603Y68581D03*
Y80581D03*
X1676146Y114488D03*
X1673853Y149768D03*
X1672410Y168713D03*
X1679928Y58013D03*
X1680789Y192665D03*
Y196665D03*
X1680884Y204864D03*
X1691149Y252371D03*
X1689828Y545912D03*
Y626912D03*
X1706243Y106495D03*
X1702927Y206864D03*
X1695119Y242078D03*
X1702098D03*
X1698200Y306652D03*
X1711760Y250599D03*
X1721768Y458334D03*
Y450334D03*
X1718168Y1146071D03*
X1732098Y1171120D03*
X1742643Y488816D03*
X1753090Y879199D03*
X1753145Y897279D03*
X1757183Y935100D03*
X1772965Y68581D03*
Y80581D03*
X1759063Y168697D03*
X1759258Y191941D03*
X1761227Y224321D03*
X1762411Y470382D03*
X1774044Y471560D03*
Y479560D03*
X1782290Y58013D03*
X1778508Y114488D03*
X1774772Y168713D03*
X1783151Y196665D03*
Y192665D03*
X1783246Y204864D03*
X1789876Y425413D03*
X1790117Y1430956D03*
X1792645Y200716D03*
X1792416Y455301D03*
Y459101D03*
Y463101D03*
X1796044Y474560D03*
X1805032Y985060D03*
X1792546Y989660D03*
X1798321Y1103246D03*
X1794157Y1257937D03*
X1814916Y424601D03*
Y428101D03*
Y431601D03*
X1807854Y1082250D03*
X1822214Y1101145D03*
Y1105145D03*
X1812915Y1223209D03*
G54D230*
X958968Y1367717D03*
Y1383465D03*
Y1379528D03*
Y1375591D03*
Y1371654D03*
Y1399213D03*
Y1395276D03*
Y1391339D03*
Y1387402D03*
Y1407087D03*
Y1403150D03*
X972512Y1381496D03*
Y1377559D03*
Y1373622D03*
Y1369685D03*
Y1397245D03*
Y1393308D03*
Y1389370D03*
Y1385434D03*
Y1405119D03*
Y1401182D03*
G54D11*
X13780Y1226024D03*
X79331Y1186654D03*
X235433Y1606142D03*
X390354Y1141024D03*
X536418Y1086654D03*
X581890Y1606142D03*
X854291Y1225118D03*
X993504Y1170748D03*
X1259055Y1606142D03*
X1304528Y1141024D03*
X1450591Y1086654D03*
X1605512Y1606142D03*
X1761614Y1215000D03*
X1827165Y1235630D03*
G54D221*
X944439Y944423D03*
X941880D03*
X939321D03*
X936762D03*
Y967455D03*
X939321D03*
X941880D03*
X944439D03*
X959794Y944423D03*
X957235D03*
X952117D03*
X949558D03*
X946998D03*
X954676D03*
X957235Y967455D03*
X946998D03*
X949558D03*
X952117D03*
X954676D03*
X959794D03*
G54D140*
X406996Y1534417D03*
X403059D03*
X405028D03*
X401090D03*
X408964D03*
X406996Y1553413D03*
X408964D03*
X405028D03*
X403059D03*
X401090D03*
X412902Y1534417D03*
X410933D03*
Y1553413D03*
X412902D03*
X927249Y353756D03*
X921343D03*
X917406D03*
X925280D03*
X919375D03*
X915437D03*
X923311D03*
X921343Y372752D03*
X923311D03*
X919375D03*
X917406D03*
X915437D03*
X925280D03*
X927249D03*
G54D203*
X894082Y566990D03*
X892114D03*
X890145D03*
X896051D03*
X890145Y591596D03*
X894082D03*
X896051D03*
X892114D03*
X901956Y566990D03*
X898020D03*
X909831D03*
X899988D03*
X905894D03*
X903925D03*
X907862D03*
X899988Y591596D03*
X903925D03*
X905894D03*
X907862D03*
X898020D03*
X909831D03*
X901956D03*
X1024318Y319612D03*
X1020382D03*
X1014476D03*
X1022350D03*
X1016444D03*
X1018413D03*
X1026287D03*
X1012507D03*
Y344218D03*
X1018413D03*
X1022350D03*
X1026287D03*
X1020382D03*
X1016444D03*
X1014476D03*
X1024318D03*
X1032193Y319612D03*
X1028256D03*
X1030224D03*
X1028256Y344218D03*
X1032193D03*
X1030224D03*
G54D212*
X910492Y311046D03*
Y309471D03*
X904704Y311046D03*
Y309471D03*
X910492Y312621D03*
X904704D03*
G54D104*
X112430Y1205118D03*
X109601Y1207947D03*
X103591Y1213957D03*
X115265Y1226217D03*
X123749Y1217733D03*
X132235Y1209248D03*
X349826Y401783D03*
X569517Y1205118D03*
X566688Y1207947D03*
X560678Y1213957D03*
X572352Y1226217D03*
X580836Y1217733D03*
X589322Y1209248D03*
X1026603Y1205118D03*
X1023774Y1207947D03*
X1017764Y1213957D03*
X1037922Y1217733D03*
X1029438Y1226217D03*
X1046408Y1209248D03*
X1263999Y401783D03*
X1480861Y1207947D03*
X1474851Y1213957D03*
X1483690Y1205118D03*
X1495009Y1217733D03*
X1486525Y1226217D03*
X1503495Y1209248D03*
X1721086Y401783D03*
G54D131*
X412752Y898688D03*
Y921718D03*
G54D113*
X226566Y836900D03*
Y904200D03*
X238062Y826900D03*
Y846900D03*
Y894200D03*
Y914200D03*
X306966Y868900D03*
X307966Y939400D03*
X318462Y858900D03*
Y878900D03*
X319462Y929400D03*
Y949400D03*
X521372Y982854D03*
X532868Y972854D03*
Y992854D03*
X754354Y1417617D03*
X765850Y1407617D03*
Y1427617D03*
X780265Y883294D03*
X781479Y933808D03*
X791761Y873294D03*
Y893294D03*
X792975Y923808D03*
Y943808D03*
X915799Y506429D03*
X927295Y496429D03*
Y516429D03*
X989695Y705383D03*
X1001191Y695383D03*
Y715383D03*
X1287323Y999634D03*
X1298819Y989634D03*
Y1009634D03*
X1404030Y954473D03*
X1392534Y964473D03*
X1404030Y974473D03*
X1430174Y976075D03*
X1441670Y966075D03*
Y986075D03*
X1552266Y980400D03*
X1563762Y970400D03*
Y990400D03*
X1584776Y906608D03*
X1573280Y916608D03*
X1584776Y926608D03*
X1623653Y881353D03*
X1623084Y952120D03*
X1635149Y871353D03*
Y891353D03*
X1634580Y942120D03*
Y962120D03*
G54D123*
X359716Y1223407D03*
X816803D03*
X1273889D03*
X1730976D03*
G54D222*
X933810Y944423D03*
Y967455D03*
X962746Y944423D03*
Y967455D03*
G54D114*
X294959Y19408D03*
Y14408D03*
Y29408D03*
Y24408D03*
X315825Y14408D03*
Y19408D03*
Y29408D03*
Y24408D03*
X1462675Y17645D03*
Y32645D03*
Y27645D03*
Y22645D03*
X1483541Y17645D03*
Y32645D03*
Y22645D03*
Y27645D03*
G54D150*
X420656Y1116630D03*
X452784D03*
X486243D03*
X518371D03*
X1334830D03*
X1366958D03*
X1400417D03*
X1432545D03*
G54D240*
X1019768Y1411117D03*
G54D213*
X911630Y533706D03*
Y540006D03*
X919976D03*
Y533706D03*
G54D12*
X14751Y66681D03*
X7271D03*
X11011Y75343D03*
X117708Y153296D03*
X125188D03*
X121448Y161958D03*
X133095Y450750D03*
X140575D03*
X136835Y459412D03*
X197929Y99259D03*
X194189Y107921D03*
X201669D03*
X227550Y153296D03*
X220070D03*
X223810Y161958D03*
X296551Y107921D03*
X300291Y99259D03*
X304031Y107921D03*
X322432Y153296D03*
X326172Y161958D03*
X328945Y560043D03*
X329912Y153296D03*
X332685Y551381D03*
X336425Y560043D03*
X402653Y99259D03*
X398913Y107921D03*
X406393D03*
X472433Y153296D03*
X479913D03*
X476173Y161958D03*
X552654Y99259D03*
X548914Y107921D03*
X556394D03*
X582275Y153296D03*
X574795D03*
X578535Y161958D03*
X597661Y450750D03*
X590181D03*
X593921Y459412D03*
X651276Y107921D03*
X655016Y99259D03*
X658756Y107921D03*
X684637Y153296D03*
X677157D03*
X680897Y161958D03*
X757378Y99259D03*
X753638Y107921D03*
X761118D03*
X779519Y153296D03*
X783259Y161958D03*
X786999Y153296D03*
X789771Y551381D03*
X786031Y560043D03*
X793511D03*
X859740Y99259D03*
X856000Y107921D03*
X863480D03*
X929519Y153296D03*
X936999D03*
X933259Y161958D03*
X1009740Y99259D03*
X1006000Y107921D03*
X1013480D03*
X1039361Y153296D03*
X1031881D03*
X1035621Y161958D03*
X1054748Y450750D03*
X1047268D03*
X1051008Y459412D03*
X1108362Y107921D03*
X1112102Y99259D03*
X1115842Y107921D03*
X1141723Y153296D03*
X1134243D03*
X1137983Y161958D03*
X1214464Y99259D03*
X1210724Y107921D03*
X1218204D03*
X1236605Y153296D03*
X1244085D03*
X1240345Y161958D03*
X1246858Y551381D03*
X1243118Y560043D03*
X1250598D03*
X1316826Y99259D03*
X1313086Y107921D03*
X1320566D03*
X1394086Y153296D03*
X1386606D03*
X1390346Y161958D03*
X1466827Y99259D03*
X1463087Y107921D03*
X1470567D03*
X1496448Y153296D03*
X1488968D03*
X1492708Y161958D03*
X1511835Y450750D03*
X1504355D03*
X1508095Y459412D03*
X1569189Y99259D03*
X1565449Y107921D03*
X1572929D03*
X1591330Y153296D03*
X1595070Y161958D03*
X1598810Y153296D03*
X1671551Y99259D03*
X1667811Y107921D03*
X1675291D03*
X1693692Y153296D03*
X1701172D03*
X1697432Y161958D03*
X1703945Y551381D03*
X1700205Y560043D03*
X1707685D03*
X1773913Y99259D03*
X1770173Y107921D03*
X1777653D03*
G54D204*
X884732Y570435D03*
Y568466D03*
Y566498D03*
Y572403D03*
Y586183D03*
Y584214D03*
Y582246D03*
Y580277D03*
Y578309D03*
Y576340D03*
Y574372D03*
Y592088D03*
Y590120D03*
Y588151D03*
X915244Y566498D03*
Y568466D03*
Y570435D03*
Y572403D03*
Y574372D03*
Y576340D03*
Y578309D03*
Y580277D03*
Y582246D03*
Y584214D03*
Y586183D03*
Y588151D03*
Y590120D03*
Y592088D03*
X1007094Y321088D03*
Y323057D03*
Y325025D03*
Y326994D03*
Y319120D03*
Y332899D03*
Y334868D03*
Y328962D03*
Y330931D03*
Y342742D03*
Y340773D03*
Y338805D03*
Y336836D03*
Y344710D03*
X1037606Y319120D03*
Y321088D03*
Y323057D03*
Y325025D03*
Y326994D03*
Y330931D03*
Y332899D03*
Y334868D03*
Y336836D03*
Y338805D03*
Y340773D03*
Y342742D03*
Y328962D03*
Y344710D03*
G54D105*
X111700Y1210046D03*
X114529Y1207217D03*
X105690Y1216056D03*
X117364Y1228316D03*
X125848Y1219832D03*
X134334Y1211347D03*
X351925Y403882D03*
X568787Y1210046D03*
X571616Y1207217D03*
X562777Y1216056D03*
X582935Y1219832D03*
X574451Y1228316D03*
X591421Y1211347D03*
X1025873Y1210046D03*
X1019863Y1216056D03*
X1028702Y1207217D03*
X1040021Y1219832D03*
X1031537Y1228316D03*
X1048507Y1211347D03*
X1266098Y403882D03*
X1476950Y1216056D03*
X1497108Y1219832D03*
X1482960Y1210046D03*
X1485789Y1207217D03*
X1488624Y1228316D03*
X1505594Y1211347D03*
X1723185Y403882D03*
G54D21*
X14360Y160100D03*
X60595Y455494D03*
X110758Y117621D03*
X213120D03*
X315482D03*
X465483D03*
X515681Y452494D03*
X567845Y117621D03*
X670207D03*
X772569D03*
X922569D03*
X974768Y455494D03*
X1024931Y117621D03*
X1127293D03*
X1229655D03*
X1379656D03*
X1429855Y452494D03*
X1482018Y117621D03*
X1584380D03*
X1686742D03*
G54D231*
X965740Y1413859D03*
G54D30*
X9837Y252371D03*
Y272371D03*
X8427Y284118D03*
X16396Y1464612D03*
X16307Y1496782D03*
X12724Y1501619D03*
X29115Y97667D03*
X24931Y102495D03*
X30844Y241681D03*
X31787Y289272D03*
Y285272D03*
X28491Y527726D03*
Y548726D03*
X30209Y621311D03*
X35247Y1078372D03*
X38057Y177606D03*
X38322Y495982D03*
X50510Y529269D03*
X49541Y688473D03*
X51680Y1124923D03*
X41902Y1193263D03*
X48941Y1192250D03*
X51428Y1213709D03*
X60320Y483388D03*
X57209Y608311D03*
X56266Y843118D03*
X64601Y1071656D03*
Y1075656D03*
Y1067656D03*
Y1083656D03*
Y1087656D03*
Y1079656D03*
X58302Y1209720D03*
X85241Y141247D03*
X78262D03*
X74292Y147540D03*
X84631Y678107D03*
Y682107D03*
X84233Y1021048D03*
X94903Y145768D03*
X91528Y1021177D03*
X101839Y172665D03*
Y180665D03*
Y176665D03*
Y168665D03*
Y184665D03*
Y188665D03*
X101934Y200864D03*
Y208864D03*
Y212864D03*
Y216864D03*
Y221864D03*
X101931Y225719D03*
X112199Y248371D03*
X108321Y1027361D03*
X131477Y97667D03*
X127293Y102495D03*
X121722Y134838D03*
Y138838D03*
X133206Y241681D03*
X151117Y378600D03*
Y459600D03*
X151205Y554555D03*
X151237Y562567D03*
X151205Y558555D03*
X150517Y631421D03*
X180624Y141247D03*
X176654Y147540D03*
X183349Y80140D03*
Y76140D03*
Y84140D03*
X194060Y76587D03*
Y72587D03*
X197265Y145768D03*
X187603Y141247D03*
X204201Y172665D03*
Y180665D03*
Y176665D03*
Y168665D03*
Y184665D03*
Y188665D03*
X204296Y208864D03*
Y212864D03*
Y216864D03*
Y221864D03*
X204293Y225719D03*
X214561Y248371D03*
X229655Y102495D03*
X224084Y134838D03*
Y138838D03*
X230781Y388718D03*
X218317Y462800D03*
X218517Y549800D03*
X227117Y549700D03*
X218517Y562800D03*
Y558800D03*
X218917Y621400D03*
Y625400D03*
X227554Y1494361D03*
X227560Y1482442D03*
Y1490442D03*
X229565Y1514578D03*
X220032Y1515642D03*
X219732Y1522542D03*
X229565Y1526578D03*
Y1522578D03*
X233839Y97667D03*
X235568Y241681D03*
X246583Y1514169D03*
Y1510142D03*
X249217Y445873D03*
Y449873D03*
Y462859D03*
X248402Y546712D03*
X248782Y675889D03*
X279016Y147540D03*
X283886Y27156D03*
X285711Y84140D03*
Y76140D03*
Y80140D03*
X289965Y141247D03*
X282986D03*
X287032Y317873D03*
X296422Y76587D03*
Y72587D03*
X299627Y145768D03*
X306563Y180665D03*
Y172665D03*
Y176665D03*
Y168665D03*
Y184665D03*
X299608Y196286D03*
X306563Y188665D03*
X306658Y208864D03*
Y212864D03*
Y216864D03*
Y221864D03*
X306655Y225719D03*
X325423Y15806D03*
Y19806D03*
Y11806D03*
Y27806D03*
Y23806D03*
Y31806D03*
X326446Y134838D03*
Y138838D03*
X316923Y248371D03*
X317425Y350850D03*
X315602Y541912D03*
Y622912D03*
X336201Y97667D03*
X332017Y102495D03*
X337930Y241681D03*
X347542Y454334D03*
X350873Y1171120D03*
X361493Y406532D03*
X361837Y447357D03*
X370541Y458309D03*
Y454309D03*
Y462309D03*
X376117Y750000D03*
X374417Y786400D03*
X372949Y939976D03*
Y943812D03*
Y947812D03*
X388073Y84140D03*
Y80140D03*
Y76140D03*
X386931Y401923D03*
X388185Y466409D03*
Y474382D03*
Y487382D03*
Y482382D03*
Y478382D03*
X389687Y864408D03*
X384534Y1539700D03*
Y1543700D03*
Y1551700D03*
Y1559700D03*
X408925Y180665D03*
Y172665D03*
Y176665D03*
Y168665D03*
Y184665D03*
Y188665D03*
X401601Y196620D03*
X409020Y208864D03*
Y212864D03*
Y216864D03*
Y221864D03*
X409017Y225719D03*
X399818Y471560D03*
Y475560D03*
X400717Y789000D03*
X398926Y860535D03*
Y864409D03*
X398868Y868286D03*
X396842Y948536D03*
X397037Y971780D03*
X409207Y1098826D03*
X404632Y1442942D03*
X416920Y26534D03*
X417015Y22627D03*
X416992Y30483D03*
X416955Y834800D03*
X417221Y1523296D03*
X424741Y1546372D03*
X439966Y141247D03*
X432987D03*
X429017Y147540D03*
X440690Y435101D03*
Y439101D03*
Y443101D03*
Y447101D03*
Y452601D03*
X434608Y620456D03*
X442353Y711199D03*
X441335Y1098826D03*
X431741Y1550158D03*
X449628Y145768D03*
X453636Y468809D03*
X443154Y620456D03*
X450494Y634279D03*
X443525Y640876D03*
X450489Y642588D03*
X445608Y1026266D03*
X454108Y1024766D03*
X466924Y248371D03*
X467908Y461864D03*
X462920Y491669D03*
Y499669D03*
Y503669D03*
Y507669D03*
Y512669D03*
X474794Y1098826D03*
X486202Y97667D03*
X482018Y102495D03*
X476447Y134838D03*
Y138838D03*
X487931Y241681D03*
X475324Y347995D03*
Y352495D03*
X475427Y360089D03*
X485324Y347995D03*
Y352495D03*
X485427Y360089D03*
X475427Y364589D03*
Y369089D03*
Y373589D03*
X485427Y364589D03*
Y369089D03*
Y373589D03*
X475427Y378089D03*
Y382589D03*
Y387089D03*
Y391589D03*
X485427Y378089D03*
Y382589D03*
X476635Y468784D03*
Y472784D03*
Y476784D03*
X485577Y527726D03*
Y548726D03*
X487295Y621311D03*
X478923Y648968D03*
X495408Y495982D03*
X499697Y655149D03*
X495451Y685006D03*
Y689006D03*
Y697006D03*
Y693006D03*
X506258Y844649D03*
X501108Y1000766D03*
Y1016266D03*
Y1012266D03*
X506922Y1098826D03*
X517406Y483388D03*
X507596Y529269D03*
X514295Y608311D03*
X510787Y969933D03*
X510739Y973885D03*
X538074Y80140D03*
Y76140D03*
Y84140D03*
X535349Y141247D03*
X531379Y147540D03*
X535703Y381723D03*
X532084Y394309D03*
X539541Y779889D03*
X525197Y1103717D03*
X548785Y76587D03*
Y72587D03*
X542328Y141247D03*
X551990Y145768D03*
X545703Y386223D03*
Y390723D03*
X552698Y738558D03*
X544719Y746514D03*
X548615Y1021177D03*
X541320Y1021048D03*
X558926Y180665D03*
Y172665D03*
Y176665D03*
Y168665D03*
Y184665D03*
Y188665D03*
X559021Y208864D03*
Y212864D03*
Y216864D03*
Y221864D03*
X559018Y225719D03*
X569286Y248371D03*
X567537Y743122D03*
X561304Y754992D03*
X572131Y776700D03*
Y780700D03*
X564862Y1026933D03*
X572274Y1526224D03*
X588564Y97667D03*
X584380Y102495D03*
X578809Y134838D03*
Y138838D03*
X573320Y957207D03*
X585449Y1497687D03*
Y1493687D03*
X582232Y1514042D03*
X585449Y1501687D03*
X581483Y1505724D03*
X590293Y241681D03*
X608203Y378600D03*
Y459600D03*
X608291Y554555D03*
Y558555D03*
X608323Y562567D03*
X607603Y631421D03*
X633741Y147540D03*
X640436Y76140D03*
Y84140D03*
Y80140D03*
X651147Y76587D03*
Y72587D03*
X644690Y141247D03*
X637711D03*
X653363Y759137D03*
Y767137D03*
Y763137D03*
Y779137D03*
Y775137D03*
Y771137D03*
Y783137D03*
Y787137D03*
X654352Y145768D03*
X661288Y180665D03*
Y172665D03*
Y176665D03*
Y168665D03*
Y184665D03*
Y188665D03*
X661383Y208864D03*
Y212864D03*
Y216864D03*
Y221864D03*
X661380Y225719D03*
X658059Y660402D03*
X662080Y689694D03*
X666863Y763137D03*
Y779137D03*
Y771137D03*
Y787137D03*
X681171Y134838D03*
Y138838D03*
X671648Y248371D03*
X675403Y462800D03*
X675603Y549800D03*
X684203Y549700D03*
X676003Y621400D03*
Y625400D03*
X690926Y97667D03*
X686742Y102495D03*
X692655Y241681D03*
X687867Y388718D03*
X706303Y445873D03*
Y449873D03*
Y462859D03*
X705488Y546712D03*
X705868Y675889D03*
X717306Y691609D03*
X704102Y709303D03*
X707107Y728050D03*
X724863Y760137D03*
X742798Y84140D03*
Y76140D03*
Y80140D03*
X747052Y141247D03*
X740073D03*
X736103Y147540D03*
X744118Y317873D03*
X736247Y1622015D03*
X753509Y72562D03*
Y76587D03*
X756714Y145768D03*
X763650Y180665D03*
Y172665D03*
Y176665D03*
Y168665D03*
Y184665D03*
Y188665D03*
X756326Y196620D03*
X763745Y200864D03*
Y208864D03*
Y212864D03*
Y216864D03*
Y221864D03*
X783533Y134838D03*
Y138838D03*
X774010Y248371D03*
X774511Y350850D03*
X772688Y541912D03*
Y622912D03*
X780278Y1443445D03*
X780266Y1435432D03*
X771727Y1454305D03*
X793288Y97667D03*
X789104Y102495D03*
X795017Y241681D03*
X788641Y442510D03*
Y450510D03*
Y446510D03*
X811994Y305368D03*
Y309368D03*
X803994Y305368D03*
Y309368D03*
X811994Y313368D03*
X803994D03*
X811994Y317368D03*
Y321368D03*
Y325368D03*
X803994Y317368D03*
Y321368D03*
Y325368D03*
X811994Y329368D03*
X803994D03*
X811994Y333368D03*
X803994Y337368D03*
Y333368D03*
X811994Y346368D03*
X803994D03*
X811994Y350368D03*
X811991Y354741D03*
X804628Y448334D03*
X808841Y840919D03*
X807960Y1171120D03*
X807146Y1404769D03*
X805011Y1484354D03*
X818900Y441389D03*
X827627Y456309D03*
Y448309D03*
Y452309D03*
X817080Y742502D03*
X827017Y766500D03*
Y784500D03*
Y802500D03*
Y820500D03*
X820494Y933571D03*
X831221Y1440849D03*
Y1448849D03*
X825927Y1462461D03*
X831239Y1454525D03*
X845160Y76140D03*
Y80140D03*
Y84140D03*
X845271Y461382D03*
Y469382D03*
Y473382D03*
Y482382D03*
Y477382D03*
X838359Y827459D03*
X846157Y827686D03*
X840781Y843790D03*
Y847490D03*
X842826Y835459D03*
Y851459D03*
X840254Y863413D03*
X840381Y855395D03*
X840254Y867413D03*
X842261Y1461959D03*
X855871Y76587D03*
Y72587D03*
X858688Y196620D03*
X862262Y340454D03*
X850491Y414760D03*
X861748Y414533D03*
X850491Y418760D03*
X863971Y487303D03*
Y483303D03*
X860778Y701170D03*
Y709170D03*
X860578Y722670D03*
X861517Y756000D03*
Y760000D03*
Y764000D03*
Y778000D03*
Y782000D03*
Y774000D03*
Y792000D03*
Y796000D03*
Y800000D03*
Y814000D03*
Y810000D03*
X853848Y827468D03*
X861517Y818000D03*
X853776Y835459D03*
X866012Y180665D03*
Y172665D03*
Y176665D03*
Y168665D03*
Y184665D03*
Y188665D03*
X866107Y208864D03*
Y212864D03*
Y216864D03*
Y221864D03*
X872494Y309368D03*
Y305368D03*
Y313368D03*
Y325368D03*
Y321368D03*
Y317368D03*
Y329368D03*
Y333368D03*
X880494Y341342D03*
Y345342D03*
X869430Y549771D03*
X869585Y562703D03*
Y570703D03*
Y566703D03*
Y578703D03*
Y582828D03*
X878778Y694970D03*
Y690970D03*
X873245Y794227D03*
X897052Y141247D03*
X890073D03*
X886103Y147540D03*
X888404Y341537D03*
X882257Y415264D03*
X883778Y727178D03*
Y722770D03*
X881937Y1087375D03*
X885592Y1202266D03*
X892631Y1201253D03*
X895118Y1222712D03*
X883761Y1444859D03*
Y1460859D03*
Y1476859D03*
Y1468859D03*
X906714Y145768D03*
X899277Y358369D03*
Y354369D03*
Y374369D03*
Y366369D03*
X906978Y687770D03*
Y691770D03*
X907778Y718970D03*
X903851Y948607D03*
X911291Y1076659D03*
Y1080659D03*
Y1084659D03*
Y1088659D03*
Y1092659D03*
Y1096659D03*
X898370Y1133926D03*
X901992Y1218723D03*
X917084Y310985D03*
X917903Y547348D03*
X926169Y557641D03*
Y569578D03*
Y573578D03*
Y577578D03*
Y581578D03*
X927723Y798271D03*
X922357Y1449536D03*
X921721Y1468100D03*
X943288Y97667D03*
X939104Y102495D03*
X933533Y134838D03*
Y138838D03*
X945683Y226852D03*
X936016Y451442D03*
Y455442D03*
Y459442D03*
Y463442D03*
Y468942D03*
X942664Y527726D03*
Y548726D03*
X944382Y621311D03*
X940603Y792330D03*
X944644Y864862D03*
X944581Y883146D03*
X936345Y891216D03*
X945914Y1087375D03*
X952495Y495982D03*
X949545Y782467D03*
X949701Y799233D03*
X949470Y786366D03*
X952081Y899890D03*
X962347Y1133926D03*
X949569Y1202122D03*
X956608Y1201253D03*
X959095Y1222712D03*
X974493Y483388D03*
X964683Y529269D03*
X971382Y608311D03*
X973602Y831799D03*
X973608Y827907D03*
X975268Y1076659D03*
Y1088659D03*
Y1084659D03*
Y1080659D03*
Y1092659D03*
Y1096659D03*
X965969Y1218723D03*
X992435Y141247D03*
X988465Y147540D03*
X994694Y314653D03*
X979642Y328472D03*
Y335472D03*
X981720Y825159D03*
Y829159D03*
Y833159D03*
X995160Y84140D03*
Y76140D03*
Y80140D03*
X1005871Y72587D03*
Y76587D03*
X999414Y141247D03*
X1009076Y145768D03*
X1005701Y1021177D03*
X1011021Y1357938D03*
X1011009Y1368835D03*
X1011004Y1380797D03*
X1016012Y180665D03*
Y172665D03*
Y176665D03*
Y168665D03*
Y184665D03*
Y188665D03*
X1016107Y200864D03*
Y208864D03*
Y212864D03*
Y216864D03*
Y221864D03*
X1016104Y225719D03*
X1026372Y248371D03*
X1016412Y754546D03*
Y771974D03*
Y775974D03*
X1016375Y815046D03*
X1016412Y825981D03*
Y818974D03*
X1015220Y833659D03*
X1015720Y848680D03*
X1014936Y954222D03*
X1021948Y1026933D03*
X1041466Y102495D03*
X1035895Y134838D03*
Y138838D03*
X1040180Y1309487D03*
X1035957Y1357372D03*
X1035900Y1361287D03*
X1035908Y1365009D03*
X1045650Y97667D03*
X1047379Y241681D03*
X1055742Y310574D03*
X1055629Y343509D03*
X1055221Y356151D03*
Y368276D03*
X1054504Y1311436D03*
X1054550Y1315605D03*
X1048453Y1323611D03*
X1058352Y1456486D03*
X1065290Y378600D03*
Y459600D03*
X1065378Y554555D03*
Y558555D03*
X1065410Y562567D03*
X1064690Y631421D03*
X1090827Y147540D03*
X1097522Y76140D03*
Y80140D03*
Y84140D03*
X1108233Y72587D03*
Y76587D03*
X1101776Y141247D03*
X1094797D03*
X1111438Y145768D03*
X1118374Y180665D03*
Y172665D03*
Y176665D03*
Y168665D03*
Y188665D03*
Y184665D03*
X1118469Y200864D03*
Y208864D03*
Y212864D03*
Y216864D03*
Y221864D03*
X1118466Y225719D03*
X1115146Y660402D03*
X1119167Y689694D03*
X1138257Y134838D03*
Y138838D03*
X1128734Y248371D03*
X1132490Y462800D03*
X1132690Y549800D03*
X1133090Y621400D03*
Y625400D03*
X1148012Y97667D03*
X1143828Y102495D03*
X1149741Y241681D03*
X1144954Y388718D03*
X1141290Y549700D03*
X1163390Y445873D03*
Y449873D03*
Y462859D03*
X1162575Y546712D03*
X1162955Y675889D03*
X1179853Y339103D03*
X1199884Y84140D03*
Y76140D03*
Y80140D03*
X1204138Y141247D03*
X1197159D03*
X1193189Y147540D03*
X1201205Y317873D03*
X1210595Y72587D03*
Y76587D03*
X1213800Y145768D03*
X1220736Y180665D03*
Y172665D03*
Y176665D03*
Y168665D03*
Y184665D03*
Y188665D03*
X1213412Y196620D03*
X1220831Y200864D03*
Y208864D03*
Y212864D03*
Y216864D03*
Y221864D03*
X1220828Y225719D03*
X1231096Y248371D03*
X1231598Y350850D03*
X1229775Y541912D03*
Y622912D03*
X1250374Y97667D03*
X1246190Y102495D03*
X1240619Y134838D03*
Y138838D03*
X1252103Y241681D03*
X1247632Y1531342D03*
X1259017Y327000D03*
X1261715Y454334D03*
X1268807Y914949D03*
Y918956D03*
X1265046Y1171120D03*
X1257150Y1519459D03*
X1275666Y406532D03*
X1276010Y447357D03*
X1284714Y458309D03*
Y454309D03*
Y462309D03*
X1282031Y776576D03*
Y772576D03*
Y784576D03*
X1278017Y914000D03*
X1302246Y84140D03*
Y76140D03*
Y80140D03*
X1301104Y401923D03*
X1302358Y466409D03*
Y474382D03*
Y487382D03*
Y482382D03*
Y478382D03*
X1295583Y796321D03*
X1288017Y827500D03*
Y831500D03*
Y823500D03*
Y835500D03*
Y859500D03*
Y855500D03*
X1288012Y877783D03*
Y881783D03*
Y889767D03*
X1291017Y919500D03*
X1315774Y196620D03*
X1313991Y471560D03*
Y475560D03*
X1331093Y26534D03*
X1331165Y30483D03*
X1331188Y22627D03*
X1323098Y168665D03*
Y176665D03*
Y172665D03*
Y180665D03*
Y184665D03*
Y188665D03*
X1323193Y200864D03*
Y208864D03*
Y212864D03*
Y216864D03*
Y221864D03*
X1323190Y225719D03*
X1321517Y558500D03*
Y562500D03*
Y574500D03*
Y578500D03*
X1329517Y594500D03*
X1321517D03*
Y605000D03*
Y621000D03*
Y609000D03*
Y625000D03*
X1329517Y641000D03*
X1321517Y653500D03*
Y641000D03*
Y649500D03*
Y665500D03*
Y669500D03*
Y685500D03*
X1329517D03*
X1321517Y700500D03*
Y696500D03*
Y716500D03*
Y712500D03*
Y732500D03*
X1329517D03*
X1323381Y1098826D03*
X1347160Y141247D03*
X1343190Y147540D03*
X1339310Y773675D03*
X1354139Y141247D03*
X1363801Y145768D03*
X1354863Y435101D03*
Y439101D03*
Y443101D03*
Y447101D03*
Y452601D03*
X1359782Y1026266D03*
X1368282Y1024766D03*
X1355509Y1098826D03*
X1381097Y248371D03*
X1377968Y320871D03*
Y325371D03*
Y343371D03*
Y338871D03*
Y334371D03*
Y329871D03*
Y347871D03*
Y361371D03*
Y356871D03*
Y352371D03*
X1400375Y97667D03*
X1396191Y102495D03*
X1390620Y134838D03*
Y138838D03*
X1387968Y320871D03*
Y325371D03*
Y329871D03*
Y343371D03*
Y338871D03*
Y334371D03*
Y352371D03*
Y347871D03*
X1399751Y527726D03*
Y548726D03*
X1385258Y569000D03*
Y565000D03*
Y561000D03*
X1385604Y581317D03*
X1385258Y615500D03*
Y611500D03*
Y607500D03*
X1385603Y623692D03*
X1391517Y652000D03*
X1399517Y656000D03*
X1391517D03*
Y660000D03*
X1391017Y675000D03*
X1399017D03*
X1391517Y699000D03*
X1399517D03*
X1391517Y703000D03*
Y707000D03*
X1399017Y722000D03*
X1391017D03*
X1388968Y1098826D03*
X1402104Y241681D03*
X1409582Y495982D03*
X1401469Y621311D03*
X1412517Y681000D03*
Y685000D03*
Y697000D03*
Y701000D03*
Y717000D03*
Y725000D03*
Y729000D03*
Y741000D03*
Y745000D03*
Y761000D03*
X1408017Y844000D03*
Y860000D03*
Y876000D03*
Y872000D03*
Y888000D03*
Y892000D03*
Y904000D03*
X1407831Y911137D03*
Y915186D03*
X1411085Y988403D03*
X1415282Y1000766D03*
Y1016266D03*
Y1012266D03*
X1416681Y1548217D03*
X1416039Y1569486D03*
X1431580Y483388D03*
X1421770Y529269D03*
X1428469Y608311D03*
X1420517Y717000D03*
X1429517Y766500D03*
X1420517Y761000D03*
X1429517Y770500D03*
Y782500D03*
Y786500D03*
Y802500D03*
Y814500D03*
Y810500D03*
Y830500D03*
Y826500D03*
Y846500D03*
X1425050Y943390D03*
X1432611Y1001519D03*
X1421096Y1098826D03*
X1423494Y1498545D03*
X1426456Y1520364D03*
X1449522Y141247D03*
X1445552Y147540D03*
X1434700Y359673D03*
X1437517Y802500D03*
Y846500D03*
X1435973Y951902D03*
X1440129Y1001518D03*
X1439371Y1103717D03*
X1451602Y26393D03*
Y30393D03*
X1451318Y39193D03*
X1452247Y84140D03*
Y76140D03*
Y80140D03*
X1462958Y72587D03*
Y76587D03*
X1456501Y141247D03*
X1453224Y356861D03*
X1458713Y928177D03*
X1461865Y932887D03*
X1455493Y1021048D03*
X1462788Y1021177D03*
X1466163Y145768D03*
X1473099Y168665D03*
Y176665D03*
Y172665D03*
Y180665D03*
Y184665D03*
Y188665D03*
X1473194Y200864D03*
Y208864D03*
Y212864D03*
Y216864D03*
Y221864D03*
X1473191Y225719D03*
X1480063Y327200D03*
Y322700D03*
Y340700D03*
Y331700D03*
Y345200D03*
Y358700D03*
Y354200D03*
Y349700D03*
X1482017Y681630D03*
Y677630D03*
Y697630D03*
Y689630D03*
Y693630D03*
Y706500D03*
Y750500D03*
X1466717Y939543D03*
X1466681Y943496D03*
X1471017Y972000D03*
X1479035Y1026933D03*
X1493139Y19043D03*
Y15043D03*
Y23043D03*
Y31043D03*
Y27043D03*
Y35043D03*
X1492982Y138838D03*
Y134838D03*
X1483459Y248371D03*
X1490063Y322700D03*
Y327200D03*
Y331700D03*
Y340700D03*
Y349700D03*
Y345200D03*
X1490030Y368576D03*
X1490017Y706500D03*
X1482517Y731500D03*
Y723500D03*
Y735500D03*
Y743500D03*
Y739500D03*
X1490017Y750500D03*
X1502737Y97667D03*
X1498553Y102495D03*
X1504466Y241681D03*
X1499517Y765000D03*
Y781000D03*
Y773000D03*
Y777000D03*
X1507017Y792000D03*
X1499017D03*
X1499517Y785000D03*
Y809000D03*
Y817000D03*
Y825000D03*
Y821000D03*
Y829000D03*
X1507017Y836000D03*
X1499017D03*
X1504300Y907240D03*
X1522377Y378600D03*
Y459600D03*
X1522465Y554555D03*
Y558555D03*
X1522497Y562567D03*
X1521777Y631421D03*
X1538225Y352053D03*
X1554609Y84140D03*
Y76140D03*
Y80140D03*
X1547914Y147540D03*
X1558863Y141247D03*
X1551884D03*
X1548396Y352363D03*
X1551231Y956600D03*
X1565320Y72587D03*
Y76587D03*
X1568525Y145768D03*
X1575461Y168665D03*
Y176665D03*
Y172665D03*
Y180665D03*
Y184665D03*
Y188665D03*
X1575556Y200864D03*
Y208864D03*
Y212864D03*
Y216864D03*
Y221864D03*
X1575553Y225719D03*
X1571717Y336200D03*
X1572233Y660402D03*
X1576254Y689694D03*
X1595344Y134838D03*
Y138838D03*
X1585821Y248371D03*
X1589577Y462800D03*
X1589777Y549800D03*
Y558800D03*
Y562800D03*
X1590177Y621400D03*
Y625400D03*
X1590799Y1446488D03*
X1605099Y97667D03*
X1600915Y102495D03*
X1606828Y241681D03*
X1602041Y388718D03*
X1598377Y549700D03*
X1601629Y1471973D03*
X1603620Y1539334D03*
X1603608Y1543373D03*
X1616814Y344252D03*
Y340252D03*
X1620477Y445873D03*
Y449873D03*
Y462859D03*
X1619662Y546712D03*
X1620042Y675889D03*
X1656971Y84140D03*
Y80140D03*
Y76140D03*
X1654246Y141247D03*
X1650276Y147540D03*
X1658292Y317873D03*
X1667682Y72587D03*
Y76587D03*
X1661225Y141247D03*
X1670887Y145768D03*
X1670499Y196620D03*
X1677823Y168665D03*
Y176665D03*
Y172665D03*
Y180665D03*
Y188665D03*
Y184665D03*
X1677918Y200864D03*
Y208864D03*
Y212864D03*
Y216864D03*
Y221864D03*
X1677915Y225719D03*
X1688183Y248371D03*
X1688685Y350850D03*
X1686862Y541912D03*
Y622912D03*
X1707461Y97667D03*
X1703277Y102495D03*
X1697706Y134838D03*
Y138838D03*
X1709190Y241681D03*
X1718802Y454334D03*
X1722133Y1171120D03*
X1732753Y406532D03*
X1733097Y447357D03*
X1741801Y458309D03*
Y454309D03*
Y462309D03*
X1758191Y401923D03*
X1750125Y884649D03*
X1749359Y915451D03*
X1754217Y931100D03*
X1759333Y80140D03*
Y76140D03*
Y84140D03*
X1770044Y72587D03*
Y76587D03*
X1772861Y196620D03*
X1759445Y466409D03*
X1771078Y467560D03*
X1759445Y474382D03*
Y487382D03*
Y482382D03*
X1771078Y475560D03*
X1759445Y478382D03*
X1761024Y824383D03*
Y820883D03*
X1780185Y168665D03*
Y176665D03*
Y172665D03*
Y180665D03*
Y184665D03*
Y188665D03*
X1789705Y196531D03*
X1780280Y200864D03*
Y208864D03*
Y212864D03*
Y216864D03*
Y221864D03*
X1780277Y225719D03*
X1778485Y924546D03*
X1789580Y985060D03*
X1789894Y1087861D03*
X1783147Y1462700D03*
X1800588Y1201739D03*
X1793549Y1202756D03*
X1803075Y1223198D03*
X1800038Y1444543D03*
X1799915Y1476733D03*
X1811950Y435101D03*
Y439101D03*
Y443101D03*
Y447101D03*
Y452601D03*
X1819248Y1077145D03*
Y1081145D03*
Y1089145D03*
Y1085145D03*
Y1093145D03*
Y1097145D03*
X1810327Y1134412D03*
X1809949Y1219209D03*
G54D141*
X422988Y326886D03*
X424563D03*
X421413D03*
X419839D03*
X437161D03*
X435587D03*
X427713D03*
X429287D03*
X430862D03*
X434012D03*
X432437D03*
X426138D03*
X1330298Y329978D03*
X1331872D03*
X1325573D03*
X1333447D03*
X1335022D03*
X1328723D03*
X1327148D03*
X1323998D03*
X1322424D03*
X1339746D03*
X1338172D03*
X1336597D03*
G54D132*
X410968Y1064305D03*
Y1078675D03*
X434336Y691514D03*
Y705884D03*
X499098Y1064305D03*
Y1078675D03*
X1325142Y1064305D03*
Y1078675D03*
X1413272Y1064305D03*
Y1078675D03*
G54D133*
X411109Y1116611D03*
X443237D03*
X476696D03*
X508824D03*
X1325283D03*
X1357411D03*
X1390870D03*
X1422998D03*
G54D31*
X19075Y281129D03*
Y287035D03*
X26161D03*
Y281129D03*
X42690Y454376D03*
X48596D03*
X42690Y461462D03*
X48596D03*
X108643Y136742D03*
X115729Y142648D03*
Y136742D03*
X108643Y142648D03*
X211005Y136742D03*
Y142648D03*
X218091D03*
Y136742D03*
X243078Y633786D03*
Y640872D03*
X248984Y633786D03*
Y640872D03*
X313367Y136742D03*
X320453Y142648D03*
Y136742D03*
X313367Y142648D03*
X463368Y136742D03*
X470454Y142648D03*
Y136742D03*
X463368Y142648D03*
X482532Y421374D03*
X488438D03*
X482532Y428460D03*
X488438D03*
X497776Y451376D03*
Y458462D03*
X503682D03*
Y451376D03*
X565730Y136742D03*
Y142648D03*
X572816D03*
Y136742D03*
X668092D03*
Y142648D03*
X675178D03*
Y136742D03*
X700164Y633786D03*
Y640872D03*
X706070Y633786D03*
Y640872D03*
X770454Y136742D03*
X777540Y142648D03*
Y136742D03*
X770454Y142648D03*
X920454Y136742D03*
X927540Y142648D03*
Y136742D03*
X920454Y142648D03*
X946064Y242721D03*
X940158D03*
X946064Y249807D03*
X940158D03*
X956863Y454376D03*
Y461462D03*
X962769Y454376D03*
Y461462D03*
X1022816Y136742D03*
Y142648D03*
X1029902D03*
Y136742D03*
X1125178D03*
X1132264Y142648D03*
Y136742D03*
X1125178Y142648D03*
X1157251Y633786D03*
Y640872D03*
X1163157Y633786D03*
Y640872D03*
X1227540Y136742D03*
X1234626Y142648D03*
Y136742D03*
X1227540Y142648D03*
X1295453Y938043D03*
Y930957D03*
X1289547D03*
Y938043D03*
X1377541Y136742D03*
X1384627Y142648D03*
Y136742D03*
X1377541Y142648D03*
X1411950Y451376D03*
Y458462D03*
X1417856D03*
Y451376D03*
X1432499Y1508327D03*
X1426593D03*
Y1515413D03*
X1432499D03*
X1479903Y136742D03*
Y142648D03*
X1486989D03*
Y136742D03*
X1582265D03*
X1589351Y142648D03*
Y136742D03*
X1582265Y142648D03*
X1603363Y1456276D03*
X1597457D03*
Y1463362D03*
X1603363D03*
X1620244Y633786D03*
X1614338D03*
X1620244Y640872D03*
X1614338D03*
X1684627Y136742D03*
X1691713Y142648D03*
Y136742D03*
X1684627Y142648D03*
G54D250*
X1439234Y938291D03*
Y940850D03*
Y943410D03*
Y945969D03*
X1453800Y943410D03*
Y940850D03*
Y938291D03*
Y945969D03*
G54D142*
X416886Y331413D03*
Y344012D03*
Y332988D03*
Y339287D03*
Y337713D03*
Y329839D03*
Y336138D03*
Y334563D03*
Y340862D03*
Y342437D03*
Y347161D03*
Y345587D03*
X1319471Y334505D03*
Y336080D03*
Y342379D03*
Y340805D03*
Y332931D03*
Y339230D03*
Y337655D03*
Y343954D03*
Y350253D03*
Y347104D03*
Y348679D03*
Y345529D03*
G54D232*
X976763Y311927D03*
Y320273D03*
X983063Y311927D03*
Y320273D03*
G54D124*
X392821Y34022D03*
Y25754D03*
X409947Y34022D03*
Y25754D03*
X1268294Y327801D03*
Y336069D03*
X1285420Y327801D03*
Y336069D03*
X1306994Y34022D03*
Y25754D03*
X1324120Y34022D03*
Y25754D03*
X1582437Y335455D03*
Y343723D03*
X1599563Y335455D03*
Y343723D03*
G54D214*
X934878Y1555045D03*
X971690D03*
G54D40*
X17644Y1480986D03*
X10952D03*
X17644Y1489648D03*
X10952D03*
G54D115*
X307313Y316731D03*
Y319290D03*
X299833Y316731D03*
Y321849D03*
Y319290D03*
X307313Y321849D03*
X764399Y316731D03*
Y319290D03*
X756919Y316731D03*
Y321849D03*
Y319290D03*
X764399Y321849D03*
X877801Y710611D03*
Y713170D03*
X870321Y710611D03*
Y715729D03*
Y713170D03*
X877801Y715729D03*
X1221486Y316731D03*
Y319290D03*
X1214006Y316731D03*
Y321849D03*
Y319290D03*
X1221486Y321849D03*
X1671093Y316731D03*
Y321849D03*
Y319290D03*
X1678573Y316731D03*
Y319290D03*
Y321849D03*
G54D160*
X466046Y1010216D03*
Y1022815D03*
Y1013366D03*
Y1011791D03*
Y1016516D03*
Y1018090D03*
Y1024390D03*
Y1014941D03*
Y1021240D03*
Y1019665D03*
X484944Y1010216D03*
Y1021240D03*
Y1019665D03*
Y1018090D03*
Y1011791D03*
Y1014941D03*
Y1022815D03*
Y1016516D03*
Y1024390D03*
Y1013366D03*
X1380220Y1010216D03*
Y1022815D03*
Y1013366D03*
Y1011791D03*
Y1016516D03*
Y1018090D03*
Y1024390D03*
Y1014941D03*
Y1021240D03*
Y1019665D03*
X1399118Y1010216D03*
Y1021240D03*
Y1019665D03*
Y1018090D03*
Y1011791D03*
Y1014941D03*
Y1022815D03*
Y1016516D03*
Y1024390D03*
Y1013366D03*
G54D151*
X423215Y1122634D03*
X455343D03*
X488802D03*
X520930D03*
X1337389D03*
X1369517D03*
X1402976D03*
X1435104D03*
G54D223*
X944110Y1444139D03*
X939110D03*
X934110D03*
X949110D03*
X960268Y1444392D03*
X975268D03*
X970268D03*
X965268D03*
X993334D03*
X988334D03*
X983334D03*
X998334D03*
X1011366Y1444492D03*
X1006366D03*
X1021366D03*
X1016366D03*
X1039252Y1444608D03*
X1034252D03*
X1029252D03*
X1044252D03*
G54D205*
X899988Y579293D03*
G54D106*
X109882Y1453504D03*
Y1468859D03*
Y1484213D03*
Y1499567D03*
Y1514922D03*
Y1555867D03*
Y1571221D03*
Y1586575D03*
Y1601930D03*
Y1617284D03*
X127205Y1453504D03*
X118543Y1457835D03*
X127205Y1468859D03*
X118543Y1473189D03*
X127205Y1484213D03*
X118543Y1488544D03*
X127205Y1499567D03*
Y1514922D03*
X118543Y1503898D03*
Y1519252D03*
X127205Y1555867D03*
X118543Y1560197D03*
X127205Y1571221D03*
X118543Y1575552D03*
X127205Y1586575D03*
X118543Y1590906D03*
X127205Y1601930D03*
X118543Y1606260D03*
X127205Y1617284D03*
X118543Y1621615D03*
X144528Y1453504D03*
X135866Y1457835D03*
X144528Y1468859D03*
X135866Y1473189D03*
X144528Y1484213D03*
X135866Y1488544D03*
X144528Y1499567D03*
Y1514922D03*
X135866Y1503898D03*
Y1519252D03*
X144528Y1555867D03*
X135866Y1560197D03*
X144528Y1571221D03*
X135866Y1575552D03*
X144528Y1586575D03*
X135866Y1590906D03*
X144528Y1601930D03*
X135866Y1606260D03*
X144528Y1617284D03*
X135866Y1621615D03*
X161850Y1453504D03*
X153189Y1457835D03*
X161850Y1468859D03*
X153189Y1473189D03*
X161850Y1484213D03*
X153189Y1488544D03*
X161850Y1499567D03*
Y1514922D03*
X153189Y1503898D03*
Y1519252D03*
X161850Y1555867D03*
X153189Y1560197D03*
X161850Y1571221D03*
X153189Y1575552D03*
X161850Y1586575D03*
X153189Y1590906D03*
X161850Y1601930D03*
X153189Y1606260D03*
X161850Y1617284D03*
X153189Y1621615D03*
X179173Y1453504D03*
X170512Y1457835D03*
X179173Y1468859D03*
X170512Y1473189D03*
X179173Y1484213D03*
X170512Y1488544D03*
X179173Y1499567D03*
Y1514922D03*
X170512Y1503898D03*
Y1519252D03*
X179173Y1555867D03*
X170512Y1560197D03*
X179173Y1571221D03*
X170512Y1575552D03*
X179173Y1586575D03*
X170512Y1590906D03*
X179173Y1601930D03*
X170512Y1606260D03*
X179173Y1617284D03*
X170512Y1621615D03*
X187835Y1457835D03*
Y1473189D03*
Y1488544D03*
Y1503898D03*
Y1519252D03*
Y1560197D03*
Y1575552D03*
Y1590906D03*
Y1606260D03*
Y1621615D03*
X283110Y1453504D03*
X291771Y1457835D03*
X283110Y1468859D03*
X291771Y1473189D03*
X283110Y1484213D03*
X291771Y1488544D03*
X283110Y1499567D03*
X291771Y1503898D03*
X283110Y1514922D03*
X291771Y1519252D03*
X283110Y1555867D03*
X291771Y1560197D03*
X283110Y1571221D03*
X291771Y1575552D03*
X283110Y1586575D03*
X291771Y1590906D03*
X283110Y1601930D03*
X291771Y1606260D03*
X283110Y1617284D03*
X291771Y1621615D03*
X300433Y1453504D03*
X309094Y1457835D03*
X300433Y1468859D03*
X309094Y1473189D03*
X300433Y1484213D03*
X309094Y1488544D03*
X300433Y1499567D03*
X309094Y1503898D03*
X300433Y1514922D03*
X309094Y1519252D03*
X300433Y1555867D03*
X309094Y1560197D03*
X300433Y1571221D03*
X309094Y1575552D03*
X300433Y1586575D03*
X309094Y1590906D03*
X300433Y1601930D03*
X309094Y1606260D03*
X300433Y1617284D03*
X309094Y1621615D03*
X317756Y1453504D03*
X326417Y1457835D03*
X317756Y1468859D03*
X326417Y1473189D03*
X317756Y1484213D03*
X326417Y1488544D03*
X317756Y1499567D03*
X326417Y1503898D03*
X317756Y1514922D03*
X326417Y1519252D03*
X317756Y1555867D03*
X326417Y1560197D03*
X317756Y1571221D03*
X326417Y1575552D03*
X317756Y1586575D03*
X326417Y1590906D03*
X317756Y1601930D03*
X326417Y1606260D03*
X317756Y1617284D03*
X326417Y1621615D03*
X335078Y1453504D03*
X343740Y1457835D03*
X335078Y1468859D03*
X343740Y1473189D03*
X335078Y1484213D03*
X343740Y1488544D03*
X335078Y1499567D03*
X343740Y1503898D03*
X335078Y1514922D03*
X343740Y1519252D03*
X335078Y1555867D03*
X343740Y1560197D03*
X335078Y1571221D03*
X343740Y1575552D03*
X335078Y1586575D03*
X343740Y1590906D03*
X335078Y1601930D03*
X343740Y1606260D03*
X335078Y1617284D03*
X343740Y1621615D03*
X352401Y1453504D03*
X361063Y1457835D03*
X352401Y1468859D03*
X361063Y1473189D03*
X352401Y1484213D03*
X361063Y1488544D03*
X352401Y1499567D03*
X361063Y1503898D03*
X352401Y1514922D03*
X361063Y1519252D03*
X352401Y1555867D03*
X361063Y1560197D03*
X352401Y1571221D03*
X361063Y1575552D03*
X352401Y1586575D03*
X361063Y1590906D03*
X352401Y1601930D03*
X361063Y1606260D03*
X352401Y1617284D03*
X361063Y1621615D03*
X456339Y1453504D03*
Y1468859D03*
Y1484213D03*
Y1499567D03*
Y1514922D03*
Y1555867D03*
Y1571221D03*
Y1586575D03*
Y1601930D03*
Y1617284D03*
X473662Y1453504D03*
X465000Y1457835D03*
X473662Y1468859D03*
X465000Y1473189D03*
X473662Y1484213D03*
X465000Y1488544D03*
X473662Y1499567D03*
Y1514922D03*
X465000Y1503898D03*
Y1519252D03*
X473662Y1555867D03*
X465000Y1560197D03*
X473662Y1571221D03*
X465000Y1575552D03*
X473662Y1586575D03*
X465000Y1590906D03*
X473662Y1601930D03*
X465000Y1606260D03*
X473662Y1617284D03*
X465000Y1621615D03*
X490985Y1453504D03*
X482323Y1457835D03*
X490985Y1468859D03*
X482323Y1473189D03*
X490985Y1484213D03*
X482323Y1488544D03*
X490985Y1499567D03*
Y1514922D03*
X482323Y1503898D03*
Y1519252D03*
X490985Y1555867D03*
X482323Y1560197D03*
X490985Y1571221D03*
X482323Y1575552D03*
X490985Y1586575D03*
X482323Y1590906D03*
X490985Y1601930D03*
X482323Y1606260D03*
X490985Y1617284D03*
X482323Y1621615D03*
X508307Y1453504D03*
X499646Y1457835D03*
X508307Y1468859D03*
X499646Y1473189D03*
X508307Y1484213D03*
X499646Y1488544D03*
X508307Y1499567D03*
Y1514922D03*
X499646Y1503898D03*
Y1519252D03*
X508307Y1555867D03*
X499646Y1560197D03*
X508307Y1571221D03*
X499646Y1575552D03*
X508307Y1586575D03*
X499646Y1590906D03*
X508307Y1601930D03*
X499646Y1606260D03*
X508307Y1617284D03*
X499646Y1621615D03*
X516969Y1457835D03*
Y1473189D03*
Y1488544D03*
Y1503898D03*
Y1519252D03*
Y1560197D03*
Y1575552D03*
Y1590906D03*
Y1606260D03*
Y1621615D03*
X525630Y1453504D03*
X534292Y1457835D03*
X525630Y1468859D03*
X534292Y1473189D03*
X525630Y1484213D03*
X534292Y1488544D03*
X525630Y1499567D03*
X534292Y1503898D03*
X525630Y1514922D03*
X534292Y1519252D03*
X525630Y1555867D03*
X534292Y1560197D03*
X525630Y1571221D03*
X534292Y1575552D03*
X525630Y1586575D03*
X534292Y1590906D03*
X525630Y1601930D03*
X534292Y1606260D03*
X525630Y1617284D03*
X534292Y1621615D03*
X629567Y1453504D03*
X638228Y1457835D03*
X629567Y1468859D03*
X638228Y1473189D03*
X629567Y1484213D03*
X638228Y1488544D03*
X629567Y1499567D03*
X638228Y1503898D03*
X629567Y1514922D03*
X638228Y1519252D03*
X629567Y1555867D03*
X638228Y1560197D03*
X629567Y1571221D03*
X638228Y1575552D03*
X629567Y1586575D03*
X638228Y1590906D03*
X629567Y1601930D03*
X638228Y1606260D03*
X629567Y1617284D03*
X638228Y1621615D03*
X646890Y1453504D03*
Y1468859D03*
Y1484213D03*
Y1499567D03*
Y1514922D03*
Y1555867D03*
Y1571221D03*
Y1586575D03*
Y1601930D03*
Y1617284D03*
X664213Y1453504D03*
X655551Y1457835D03*
X664213Y1468859D03*
X655551Y1473189D03*
X664213Y1484213D03*
X655551Y1488544D03*
X664213Y1499567D03*
Y1514922D03*
X655551Y1503898D03*
Y1519252D03*
X664213Y1555867D03*
X655551Y1560197D03*
X664213Y1571221D03*
X655551Y1575552D03*
X664213Y1586575D03*
X655551Y1590906D03*
X664213Y1601930D03*
X655551Y1606260D03*
X664213Y1617284D03*
X655551Y1621615D03*
X681535Y1453504D03*
X672874Y1457835D03*
X681535Y1468859D03*
X672874Y1473189D03*
X681535Y1484213D03*
X672874Y1488544D03*
X681535Y1499567D03*
Y1514922D03*
X672874Y1503898D03*
Y1519252D03*
X681535Y1555867D03*
X672874Y1560197D03*
X681535Y1571221D03*
X672874Y1575552D03*
X681535Y1586575D03*
X672874Y1590906D03*
X681535Y1601930D03*
X672874Y1606260D03*
X681535Y1617284D03*
X672874Y1621615D03*
X698858Y1453504D03*
X690197Y1457835D03*
X698858Y1468859D03*
X690197Y1473189D03*
X698858Y1484213D03*
X690197Y1488544D03*
X698858Y1499567D03*
Y1514922D03*
X690197Y1503898D03*
Y1519252D03*
X698858Y1555867D03*
X690197Y1560197D03*
X698858Y1571221D03*
X690197Y1575552D03*
X698858Y1586575D03*
X690197Y1590906D03*
X698858Y1601930D03*
X690197Y1606260D03*
X698858Y1617284D03*
X690197Y1621615D03*
X707520Y1457835D03*
Y1473189D03*
Y1488544D03*
Y1503898D03*
Y1519252D03*
Y1560197D03*
Y1575552D03*
Y1590906D03*
Y1606260D03*
Y1621615D03*
X1131850Y1453504D03*
X1140511Y1457835D03*
X1131850Y1468859D03*
X1140511Y1473189D03*
X1131850Y1484213D03*
X1140511Y1488544D03*
X1131850Y1499567D03*
X1140511Y1503898D03*
X1131850Y1514922D03*
X1140511Y1519252D03*
X1131850Y1555867D03*
X1140511Y1560197D03*
X1131850Y1571221D03*
X1140511Y1575552D03*
X1131850Y1586575D03*
X1140511Y1590906D03*
X1131850Y1601930D03*
X1140511Y1606260D03*
X1131850Y1617284D03*
X1140511Y1621615D03*
X1149173Y1453504D03*
X1157834Y1457835D03*
X1149173Y1468859D03*
X1157834Y1473189D03*
X1149173Y1484213D03*
X1157834Y1488544D03*
X1149173Y1499567D03*
X1157834Y1503898D03*
X1149173Y1514922D03*
X1157834Y1519252D03*
X1149173Y1555867D03*
X1157834Y1560197D03*
X1149173Y1571221D03*
X1157834Y1575552D03*
X1149173Y1586575D03*
X1157834Y1590906D03*
X1149173Y1601930D03*
X1157834Y1606260D03*
X1149173Y1617284D03*
X1157834Y1621615D03*
X1166496Y1453504D03*
Y1468859D03*
Y1484213D03*
Y1499567D03*
Y1514922D03*
Y1555867D03*
Y1571221D03*
Y1586575D03*
Y1601930D03*
Y1617284D03*
X1183818Y1453504D03*
X1175157Y1457835D03*
X1183818Y1468859D03*
X1175157Y1473189D03*
X1183818Y1484213D03*
X1175157Y1488544D03*
X1183818Y1499567D03*
Y1514922D03*
X1175157Y1503898D03*
Y1519252D03*
X1183818Y1555867D03*
X1175157Y1560197D03*
X1183818Y1571221D03*
X1175157Y1575552D03*
X1183818Y1586575D03*
X1175157Y1590906D03*
X1183818Y1601930D03*
X1175157Y1606260D03*
X1183818Y1617284D03*
X1175157Y1621615D03*
X1201141Y1453504D03*
X1192480Y1457835D03*
X1201141Y1468859D03*
X1192480Y1473189D03*
X1201141Y1484213D03*
X1192480Y1488544D03*
X1201141Y1499567D03*
Y1514922D03*
X1192480Y1503898D03*
Y1519252D03*
X1201141Y1555867D03*
X1192480Y1560197D03*
X1201141Y1571221D03*
X1192480Y1575552D03*
X1201141Y1586575D03*
X1192480Y1590906D03*
X1201141Y1601930D03*
X1192480Y1606260D03*
X1201141Y1617284D03*
X1192480Y1621615D03*
X1209803Y1457835D03*
Y1473189D03*
Y1488544D03*
Y1503898D03*
Y1519252D03*
Y1560197D03*
Y1575552D03*
Y1590906D03*
Y1606260D03*
Y1621615D03*
X1305079Y1453504D03*
X1313740Y1457835D03*
X1305079Y1468859D03*
X1313740Y1473189D03*
X1305079Y1484213D03*
X1313740Y1488544D03*
X1305079Y1499567D03*
X1313740Y1503898D03*
X1305079Y1514922D03*
X1313740Y1519252D03*
X1305079Y1555867D03*
X1313740Y1560197D03*
X1305079Y1571221D03*
X1313740Y1575552D03*
X1305079Y1586575D03*
X1313740Y1590906D03*
X1305079Y1601930D03*
X1313740Y1606260D03*
X1305079Y1617284D03*
X1313740Y1621615D03*
X1322402Y1453504D03*
X1331063Y1457835D03*
X1322402Y1468859D03*
X1331063Y1473189D03*
X1322402Y1484213D03*
X1331063Y1488544D03*
X1322402Y1499567D03*
X1331063Y1503898D03*
X1322402Y1514922D03*
X1331063Y1519252D03*
X1322402Y1555867D03*
X1331063Y1560197D03*
X1322402Y1571221D03*
X1331063Y1575552D03*
X1322402Y1586575D03*
X1331063Y1590906D03*
X1322402Y1601930D03*
X1331063Y1606260D03*
X1322402Y1617284D03*
X1331063Y1621615D03*
X1339725Y1453504D03*
X1348386Y1457835D03*
X1339725Y1468859D03*
X1348386Y1473189D03*
X1339725Y1484213D03*
X1348386Y1488544D03*
X1339725Y1499567D03*
X1348386Y1503898D03*
X1339725Y1514922D03*
X1348386Y1519252D03*
X1339725Y1555867D03*
X1348386Y1560197D03*
X1339725Y1571221D03*
X1348386Y1575552D03*
X1339725Y1586575D03*
X1348386Y1590906D03*
X1339725Y1601930D03*
X1348386Y1606260D03*
X1339725Y1617284D03*
X1348386Y1621615D03*
X1357047Y1453504D03*
X1365709Y1457835D03*
X1357047Y1468859D03*
X1365709Y1473189D03*
X1357047Y1484213D03*
X1365709Y1488544D03*
X1357047Y1499567D03*
X1365709Y1503898D03*
X1357047Y1514922D03*
X1365709Y1519252D03*
X1357047Y1555867D03*
X1365709Y1560197D03*
X1357047Y1571221D03*
X1365709Y1575552D03*
X1357047Y1586575D03*
X1365709Y1590906D03*
X1357047Y1601930D03*
X1365709Y1606260D03*
X1357047Y1617284D03*
X1365709Y1621615D03*
X1374370Y1453504D03*
X1383032Y1457835D03*
X1374370Y1468859D03*
X1383032Y1473189D03*
X1374370Y1484213D03*
X1383032Y1488544D03*
X1374370Y1499567D03*
X1383032Y1503898D03*
X1374370Y1514922D03*
X1383032Y1519252D03*
X1374370Y1555867D03*
X1383032Y1560197D03*
X1374370Y1571221D03*
X1383032Y1575552D03*
X1374370Y1586575D03*
X1383032Y1590906D03*
X1374370Y1601930D03*
X1383032Y1606260D03*
X1374370Y1617284D03*
X1383032Y1621615D03*
X1478307Y1453504D03*
Y1468859D03*
Y1484213D03*
Y1499567D03*
Y1514922D03*
Y1555867D03*
Y1571221D03*
Y1586575D03*
Y1601930D03*
Y1617284D03*
X1495630Y1453504D03*
X1486968Y1457835D03*
X1495630Y1468859D03*
X1486968Y1473189D03*
X1495630Y1484213D03*
X1486968Y1488544D03*
X1495630Y1499567D03*
Y1514922D03*
X1486968Y1503898D03*
Y1519252D03*
X1495630Y1555867D03*
X1486968Y1560197D03*
X1495630Y1571221D03*
X1486968Y1575552D03*
X1495630Y1586575D03*
X1486968Y1590906D03*
X1495630Y1601930D03*
X1486968Y1606260D03*
X1495630Y1617284D03*
X1486968Y1621615D03*
X1512953Y1453504D03*
X1504291Y1457835D03*
X1512953Y1468859D03*
X1504291Y1473189D03*
X1512953Y1484213D03*
X1504291Y1488544D03*
X1512953Y1499567D03*
Y1514922D03*
X1504291Y1503898D03*
Y1519252D03*
X1512953Y1555867D03*
X1504291Y1560197D03*
X1512953Y1571221D03*
X1504291Y1575552D03*
X1512953Y1586575D03*
X1504291Y1590906D03*
X1512953Y1601930D03*
X1504291Y1606260D03*
X1512953Y1617284D03*
X1504291Y1621615D03*
X1530275Y1453504D03*
X1521614Y1457835D03*
X1530275Y1468859D03*
X1521614Y1473189D03*
X1530275Y1484213D03*
X1521614Y1488544D03*
X1530275Y1499567D03*
Y1514922D03*
X1521614Y1503898D03*
Y1519252D03*
X1530275Y1555867D03*
X1521614Y1560197D03*
X1530275Y1571221D03*
X1521614Y1575552D03*
X1530275Y1586575D03*
X1521614Y1590906D03*
X1530275Y1601930D03*
X1521614Y1606260D03*
X1530275Y1617284D03*
X1521614Y1621615D03*
X1547598Y1453504D03*
X1538937Y1457835D03*
X1547598Y1468859D03*
X1538937Y1473189D03*
X1547598Y1484213D03*
X1538937Y1488544D03*
X1547598Y1499567D03*
Y1514922D03*
X1538937Y1503898D03*
Y1519252D03*
X1547598Y1555867D03*
X1538937Y1560197D03*
X1547598Y1571221D03*
X1538937Y1575552D03*
X1547598Y1586575D03*
X1538937Y1590906D03*
X1547598Y1601930D03*
X1538937Y1606260D03*
X1547598Y1617284D03*
X1538937Y1621615D03*
X1556260Y1457835D03*
Y1473189D03*
Y1488544D03*
Y1503898D03*
Y1519252D03*
Y1560197D03*
Y1575552D03*
Y1590906D03*
Y1606260D03*
Y1621615D03*
X1651535Y1453504D03*
X1660196Y1457835D03*
X1651535Y1468859D03*
X1660196Y1473189D03*
X1651535Y1484213D03*
X1660196Y1488544D03*
X1651535Y1499567D03*
X1660196Y1503898D03*
X1651535Y1514922D03*
X1660196Y1519252D03*
X1651535Y1555867D03*
X1660196Y1560197D03*
X1651535Y1571221D03*
X1660196Y1575552D03*
X1651535Y1586575D03*
X1660196Y1590906D03*
X1651535Y1601930D03*
X1660196Y1606260D03*
X1651535Y1617284D03*
X1660196Y1621615D03*
X1668858Y1453504D03*
X1677519Y1457835D03*
X1668858Y1468859D03*
X1677519Y1473189D03*
X1668858Y1484213D03*
X1677519Y1488544D03*
X1668858Y1499567D03*
X1677519Y1503898D03*
X1668858Y1514922D03*
X1677519Y1519252D03*
X1668858Y1555867D03*
X1677519Y1560197D03*
X1668858Y1571221D03*
X1677519Y1575552D03*
X1668858Y1586575D03*
X1677519Y1590906D03*
X1668858Y1601930D03*
X1677519Y1606260D03*
X1668858Y1617284D03*
X1677519Y1621615D03*
X1686181Y1453504D03*
Y1468859D03*
Y1484213D03*
Y1499567D03*
Y1514922D03*
Y1555867D03*
Y1571221D03*
Y1586575D03*
Y1601930D03*
Y1617284D03*
X1703503Y1453504D03*
X1694842Y1457835D03*
X1703503Y1468859D03*
X1694842Y1473189D03*
X1703503Y1484213D03*
X1694842Y1488544D03*
X1703503Y1499567D03*
Y1514922D03*
X1694842Y1503898D03*
Y1519252D03*
X1703503Y1555867D03*
X1694842Y1560197D03*
X1703503Y1571221D03*
X1694842Y1575552D03*
X1703503Y1586575D03*
X1694842Y1590906D03*
X1703503Y1601930D03*
X1694842Y1606260D03*
X1703503Y1617284D03*
X1694842Y1621615D03*
X1720826Y1453504D03*
X1712165Y1457835D03*
X1720826Y1468859D03*
X1712165Y1473189D03*
X1720826Y1484213D03*
X1712165Y1488544D03*
X1720826Y1499567D03*
Y1514922D03*
X1712165Y1503898D03*
Y1519252D03*
X1720826Y1555867D03*
X1712165Y1560197D03*
X1720826Y1571221D03*
X1712165Y1575552D03*
X1720826Y1586575D03*
X1712165Y1590906D03*
X1720826Y1601930D03*
X1712165Y1606260D03*
X1720826Y1617284D03*
X1712165Y1621615D03*
X1729488Y1457835D03*
Y1473189D03*
Y1488544D03*
Y1503898D03*
Y1519252D03*
Y1560197D03*
Y1575552D03*
Y1590906D03*
Y1606260D03*
Y1621615D03*
G54D13*
X12786Y82445D03*
X10292Y96728D03*
X14292D03*
X15948Y135809D03*
X11999Y135881D03*
X19855Y135904D03*
X12709Y170319D03*
X18826Y232994D03*
X11781Y1529404D03*
X10852Y1538639D03*
X6560Y1547628D03*
X18434Y1548699D03*
X20709Y170319D03*
X36201Y233076D03*
X24091Y233063D03*
X27966Y233051D03*
X29127Y1198716D03*
X27222Y1438644D03*
X48643Y445436D03*
X41643Y467436D03*
X46192Y636328D03*
X42192D03*
X50192D03*
X36692D03*
X40700Y1086663D03*
X58224Y467576D03*
X66224D03*
X53643Y467436D03*
X67684Y599742D03*
X54192Y636328D03*
X63988Y625184D03*
X57553Y1202752D03*
X53056Y1206881D03*
X54339Y1487989D03*
X60013Y1550212D03*
X66291Y1628319D03*
X73381Y88546D03*
X69381D03*
X77711Y173090D03*
X73711D03*
X77938Y184347D03*
X76877Y216699D03*
X80766Y259627D03*
X75819Y285000D03*
X79819D03*
X83819D03*
X83684Y599742D03*
X79684D03*
X71684D03*
X75684D03*
X73968Y662609D03*
X75049Y828235D03*
Y835649D03*
X70941Y1586782D03*
X74291Y1628319D03*
X78291D03*
X82291D03*
X70291D03*
X89845Y275318D03*
X87684Y599742D03*
X91057Y1025319D03*
X86291Y1628319D03*
X107607Y127840D03*
X117607D03*
X106796Y147846D03*
X121661Y127845D03*
X121840Y142954D03*
X120926Y232951D03*
X126453Y233063D03*
X130328Y233051D03*
X127235Y452598D03*
X138563Y233076D03*
X146400Y452317D03*
X175743Y88546D03*
X171743D03*
X179743D03*
X180073Y173090D03*
X176073D03*
X180300Y184347D03*
X179239Y216699D03*
X178181Y285000D03*
X182181D03*
X183752Y88546D03*
X183128Y259627D03*
X192207Y275318D03*
X186181Y285000D03*
X210482Y88821D03*
X214389Y88916D03*
X206533Y88893D03*
X211969Y127840D03*
X209158Y147846D03*
X219969Y127840D03*
X224023Y127845D03*
X224202Y142954D03*
X223288Y232951D03*
X228815Y233063D03*
X217939Y611981D03*
X221809Y611993D03*
X221084Y1479997D03*
X229753Y1534232D03*
X240925Y233076D03*
X232690Y233051D03*
X243278Y620880D03*
X247278D03*
X236498Y1475657D03*
X237753Y1534232D03*
X251278Y620880D03*
X278105Y88546D03*
X274105D03*
X278435Y173090D03*
X282105Y88546D03*
X286114D03*
X282435Y173090D03*
X282662Y184347D03*
X281601Y216699D03*
X285490Y259627D03*
X294569Y275318D03*
X280543Y285000D03*
X284543D03*
X288543D03*
X280500Y855731D03*
Y865831D03*
X286300Y890931D03*
Y901231D03*
X282300Y926431D03*
X282400Y936531D03*
X308895Y88893D03*
X312331Y127840D03*
X311520Y147867D03*
X312263Y311832D03*
X304543Y328959D03*
X316751Y88916D03*
X312844Y88821D03*
X322331Y127840D03*
X326385Y127845D03*
X326564Y142954D03*
X325650Y232951D03*
X331177Y233063D03*
X343287Y233076D03*
X335052Y233051D03*
X342285Y562229D03*
X341748Y1137221D03*
X341455Y1182062D03*
X342152Y1203535D03*
X338322Y1190987D03*
X347591Y394025D03*
X357748Y1137221D03*
X353748D03*
X349748D03*
X345471Y1181992D03*
X346387Y1203497D03*
X350402Y1203535D03*
X354402D03*
X358402D03*
X350400Y1195511D03*
X354400D03*
X358400D03*
X376467Y88546D03*
X377237Y373772D03*
X366486Y379665D03*
X370486D03*
X368587Y403558D03*
X364326Y481975D03*
X361748Y1137221D03*
X366157Y1147029D03*
X366133Y1165309D03*
X366400Y1195511D03*
X366402Y1203535D03*
X362402D03*
X362400Y1195511D03*
X386112Y30710D03*
X380467Y88546D03*
X388476D03*
X384467D03*
X384797Y173090D03*
X380797D03*
X385024Y184347D03*
X383963Y216699D03*
X387852Y259627D03*
X382905Y285000D03*
X386905D03*
X390905D03*
X379800Y772117D03*
X378472Y790286D03*
X391614Y933168D03*
X408680Y40035D03*
X396680D03*
X396931Y275318D03*
X398237Y373573D03*
X394553Y392919D03*
X401165Y445554D03*
X395390Y872787D03*
X399052Y881290D03*
X402966Y881391D03*
X403159Y1119914D03*
X409461Y1563526D03*
X405461D03*
X415677Y312778D03*
X423551D03*
X419277D03*
X424479Y362174D03*
X416318Y362166D03*
X421459Y625843D03*
X420400Y795631D03*
X412100D03*
X413461Y1563526D03*
X435025Y312778D03*
X431425D03*
X427151D03*
X435574Y439056D03*
X429673Y456118D03*
X433673D03*
X438157Y503126D03*
X431285Y1120913D03*
X435287Y1119914D03*
X444779Y633973D03*
X455619Y1252512D03*
X472332Y127840D03*
X464332D03*
X461521Y147846D03*
X461091Y1024783D03*
X463413Y1120913D03*
X468746Y1119914D03*
X460574Y1252513D03*
X476386Y127845D03*
X476565Y142954D03*
X481178Y233063D03*
X475651Y232951D03*
X485053Y233051D03*
X488485Y412434D03*
X481485Y434434D03*
X488745Y677434D03*
X488091Y992283D03*
X493288Y233076D03*
X493485Y434434D03*
X503729Y442436D03*
X496729Y464436D03*
X503278Y636328D03*
X499278D03*
X507278D03*
X493778D03*
X491373Y654714D03*
X493914Y677452D03*
X505464Y670170D03*
X492091Y992283D03*
X500874Y1119914D03*
X496872Y1120913D03*
X521310Y464576D03*
X513310D03*
X508729Y464436D03*
X511278Y636328D03*
X521074Y625184D03*
X517464Y670170D03*
X513464D03*
X509464D03*
X517412Y758924D03*
X514576Y786320D03*
X519763Y786247D03*
X538477Y88546D03*
X530468D03*
X534468D03*
X526468D03*
X534798Y173090D03*
X530798D03*
X535025Y184347D03*
X533964Y216699D03*
X537853Y259627D03*
X532906Y285000D03*
X536906D03*
X528770Y599742D03*
X532770D03*
X536770D03*
X524770D03*
X537964Y670170D03*
X533964D03*
X529964D03*
X525964D03*
X529000Y1120913D03*
X546932Y275318D03*
X540906Y285000D03*
X544770Y599742D03*
X540770D03*
X542400Y844831D03*
X548144Y1025319D03*
X569114Y88916D03*
X565207Y88821D03*
X561258Y88893D03*
X564694Y127840D03*
X563883Y147846D03*
X567958Y1532332D03*
X574694Y127840D03*
X578748Y127845D03*
X578927Y142954D03*
X578013Y232951D03*
X583540Y233063D03*
X587415Y233051D03*
X584321Y452598D03*
X574504Y750401D03*
X587858Y1520832D03*
X579758Y1520732D03*
X575809Y1535518D03*
X583809D03*
X595650Y233076D03*
X603486Y452317D03*
X592103Y942324D03*
Y949738D03*
X591858Y1526932D03*
X595809Y1535518D03*
X632830Y88546D03*
X636830D03*
X628830D03*
X637160Y173090D03*
X633160D03*
X637387Y184347D03*
X636326Y216699D03*
X635268Y285000D03*
X640839Y88546D03*
X640215Y259627D03*
X649294Y275318D03*
X639268Y285000D03*
X643268D03*
X663620Y88893D03*
X667569Y88821D03*
X669056Y127840D03*
X666245Y147846D03*
X658064Y653253D03*
X662064D03*
X671476Y88916D03*
X677056Y127840D03*
X681110Y127845D03*
X681289Y142954D03*
X680375Y232951D03*
X685902Y233063D03*
X698012Y233076D03*
X689777Y233051D03*
X700364Y620880D03*
X693163Y697165D03*
X704364Y620880D03*
X708364D03*
X731192Y88546D03*
X720260Y696639D03*
X732170Y1622107D03*
X743201Y88546D03*
X739192D03*
X735192D03*
X739522Y173090D03*
X735522D03*
X739749Y184347D03*
X738688Y216699D03*
X742577Y259627D03*
X737630Y285000D03*
X741630D03*
X745630D03*
X751140Y1583827D03*
X735392Y1599282D03*
X744924Y1611885D03*
X743331Y1630736D03*
X765982Y88893D03*
X751656Y275318D03*
X761629Y328959D03*
X755187Y1583841D03*
X759452Y1613859D03*
X773838Y88916D03*
X769931Y88821D03*
X769418Y127840D03*
X779418D03*
X783472Y127845D03*
X783651Y142954D03*
X768607Y147846D03*
X782737Y232951D03*
X769349Y311832D03*
X774844Y1619487D03*
X778358Y1630218D03*
X788264Y233063D03*
X792139Y233051D03*
X799371Y562229D03*
X798835Y1137221D03*
X798542Y1182062D03*
X795159Y1188708D03*
X795418Y1203435D03*
X796972Y1394695D03*
X800374Y233076D03*
X813821Y735388D03*
X816027Y867772D03*
X806835Y1137221D03*
X814835D03*
X810835D03*
X802558Y1181992D03*
X815487Y1195511D03*
X811487D03*
X807487D03*
X815489Y1203535D03*
X811489D03*
X807489D03*
X803604Y1203492D03*
X802333Y1195028D03*
X806148Y1377700D03*
X810148D03*
X805009Y1469602D03*
X821412Y476975D03*
X830484Y741243D03*
X826484D03*
X822831Y836758D03*
X818831D03*
X820027Y867772D03*
X819629Y892647D03*
X828909Y908560D03*
X830913Y926694D03*
X818835Y1137221D03*
X823244Y1147029D03*
X823220Y1165309D03*
X823489Y1203535D03*
X819487Y1195511D03*
X823487D03*
X819489Y1203535D03*
X833554Y88546D03*
X837554D03*
X845563D03*
X841554D03*
X841884Y173090D03*
X837884D03*
X842111Y184347D03*
X841050Y216699D03*
X844939Y259627D03*
X839992Y285000D03*
X843992D03*
X847992D03*
X846098Y411754D03*
X834484Y741243D03*
X846484D03*
X838484D03*
X842484D03*
X833112Y826730D03*
X832726Y840571D03*
X836311Y874105D03*
X844946Y908560D03*
X840909D03*
X836909D03*
X832909D03*
X838829Y926694D03*
X834829D03*
X845395D03*
X836423Y959211D03*
X832423D03*
X854018Y275318D03*
X863086Y377017D03*
X849680Y689131D03*
X854484Y741243D03*
X850484D03*
X852628Y909606D03*
X860628D03*
X849544Y1451276D03*
X872293Y88821D03*
X876200Y88916D03*
X868344Y88893D03*
X878500Y197442D03*
X879740Y257226D03*
X868086Y377017D03*
X876736Y385797D03*
X867586Y387517D03*
X869342Y411559D03*
X875916Y803407D03*
X879916Y813557D03*
X876628Y909606D03*
X868628D03*
X872817Y1207719D03*
X889879Y409260D03*
X896491Y461895D03*
X896431Y536585D03*
X891933Y612685D03*
X884045Y747252D03*
X887916Y803407D03*
X883916D03*
Y813557D03*
X887916D03*
X891916Y803407D03*
X884628Y909606D03*
X887390Y1095666D03*
X896746Y1215884D03*
X891844Y1452176D03*
X897736Y385797D03*
X903431Y536585D03*
X911416Y803407D03*
X910900Y909517D03*
X906128Y956107D03*
X901243Y1211755D03*
X908852Y1225025D03*
X912726D03*
X929418Y127840D03*
X921418D03*
X918607Y147846D03*
X927072Y381424D03*
X923072D03*
X919072D03*
X924999Y472459D03*
X928999D03*
X917250Y551637D03*
X927916Y803407D03*
X923790D03*
X919664D03*
X915716D03*
X914500Y909517D03*
X918100D03*
X924628Y909606D03*
X928628D03*
X925697Y1454343D03*
X921868Y1454373D03*
X933472Y127845D03*
X933651Y142954D03*
X938930Y218234D03*
X942805Y218222D03*
X938657Y364728D03*
X930900Y455397D03*
X931916Y811557D03*
X943916D03*
X945035Y830274D03*
X943735Y844674D03*
X936616Y895121D03*
X932716D03*
X936628Y909606D03*
X944628D03*
X940628D03*
X932628D03*
X936794Y1207719D03*
X951040Y218247D03*
X955816Y467436D03*
X960365Y636328D03*
X956365D03*
X950865D03*
X947556Y702142D03*
X955950Y728555D03*
X948935Y830274D03*
X950335Y823374D03*
X958682Y831445D03*
X958200Y838617D03*
X950100Y850517D03*
X954000D03*
X954124Y880087D03*
X954567Y930336D03*
X957671Y985760D03*
X951367Y1095666D03*
X960723Y1215884D03*
X962816Y445436D03*
X972397Y467496D03*
X967816Y467436D03*
X968365Y636328D03*
X978161Y625184D03*
X964365Y636328D03*
X973712Y716606D03*
X965220Y1211755D03*
X983554Y88546D03*
X987554D03*
X991554D03*
X991884Y173090D03*
X987884D03*
X992111Y184347D03*
X991050Y216699D03*
X989992Y285000D03*
X993992D03*
X990405Y318267D03*
X984045Y361101D03*
X980045D03*
X980397Y467576D03*
X981857Y599742D03*
X989857D03*
X993857D03*
X985857D03*
X991990Y768491D03*
X987990D03*
X990051Y813860D03*
X995563Y88546D03*
X994939Y259627D03*
X1004018Y275318D03*
X997992Y285000D03*
X1004635Y302768D03*
X1008635D03*
X997857Y599742D03*
X1001857D03*
X1003990Y768491D03*
X999990D03*
X1005230Y1025319D03*
X1018344Y88893D03*
X1022293Y88821D03*
X1026200Y88916D03*
X1021780Y127840D03*
X1020969Y147846D03*
X1021259Y1313539D03*
X1024115Y1330906D03*
X1031780Y127840D03*
X1035834Y127845D03*
X1036013Y142954D03*
X1035099Y232951D03*
X1040626Y233063D03*
X1033786Y302768D03*
X1037386D03*
X1041496D03*
X1041408Y452598D03*
X1033719Y939339D03*
Y946753D03*
X1052736Y233076D03*
X1044501Y233051D03*
X1060573Y452317D03*
X1066260Y1442483D03*
X1085916Y88546D03*
X1089916D03*
X1090246Y173090D03*
X1086904Y1593298D03*
X1090469Y1582502D03*
X1083735Y1603715D03*
Y1611651D03*
X1085474Y1631942D03*
X1093916Y88546D03*
X1097925D03*
X1094246Y173090D03*
X1094473Y184347D03*
X1093412Y216699D03*
X1097301Y259627D03*
X1106380Y275318D03*
X1092354Y285000D03*
X1096354D03*
X1100354D03*
X1098376Y1554275D03*
X1093376D03*
X1098904Y1593298D03*
X1094904D03*
X1100233Y1582525D03*
X1104612Y1603694D03*
X1097474Y1631942D03*
X1124655Y88821D03*
X1120706Y88893D03*
X1123331Y147846D03*
X1115151Y653253D03*
X1119151D03*
X1128562Y88916D03*
X1134142Y127840D03*
X1126142D03*
X1138196Y127845D03*
X1138375Y142954D03*
X1137461Y232951D03*
X1142988Y233063D03*
X1155098Y233076D03*
X1146863Y233051D03*
X1152485Y767659D03*
X1157451Y620880D03*
X1161451D03*
X1165451D03*
X1168485Y767527D03*
X1160485Y767659D03*
X1164485D03*
X1188278Y88546D03*
X1180715Y778985D03*
X1196278Y88546D03*
X1200287D03*
X1192278D03*
X1196608Y173090D03*
X1192608D03*
X1196835Y184347D03*
X1195774Y216699D03*
X1199663Y259627D03*
X1194716Y285000D03*
X1198716D03*
X1202716D03*
X1208742Y275318D03*
X1218716Y328959D03*
X1227017Y88821D03*
X1230924Y88916D03*
X1223068Y88893D03*
X1236504Y127840D03*
X1226504D03*
X1225693Y147846D03*
X1226436Y311832D03*
X1240558Y127845D03*
X1240737Y142954D03*
X1239823Y232951D03*
X1245350Y233063D03*
X1249225Y233051D03*
X1251302Y1198942D03*
X1257460Y233076D03*
X1261764Y394025D03*
X1256458Y562229D03*
X1263921Y1137221D03*
X1267921D03*
X1255921D03*
X1255628Y1182062D03*
X1259644Y1181992D03*
X1264575Y1203535D03*
X1268575D03*
X1264573Y1195511D03*
X1268573D03*
X1260535Y1203540D03*
X1260771Y1193837D03*
X1280659Y379665D03*
X1284659D03*
X1282760Y403558D03*
X1278499Y481975D03*
X1284655Y895017D03*
X1275493Y924010D03*
X1279493D03*
X1283493D03*
X1271493D03*
X1275921Y1137221D03*
X1271921D03*
X1280330Y1147029D03*
X1280306Y1165309D03*
X1276575Y1203535D03*
X1280573Y1195511D03*
X1276573D03*
X1280575Y1203535D03*
X1272575D03*
X1272573Y1195511D03*
X1300285Y30710D03*
X1298640Y88546D03*
X1294640D03*
X1302649D03*
X1290640D03*
X1298970Y173090D03*
X1294970D03*
X1299197Y184347D03*
X1298136Y216699D03*
X1302025Y259627D03*
X1297078Y285000D03*
X1301078D03*
X1291500Y321517D03*
X1291410Y373772D03*
X1292000Y895017D03*
X1289500Y944017D03*
X1296500Y964017D03*
X1310853Y40035D03*
X1311104Y275318D03*
X1305078Y285000D03*
X1318262Y315870D03*
X1312410Y373573D03*
X1308726Y392919D03*
X1315338Y445554D03*
X1318500Y920017D03*
X1314500D03*
X1317000Y931017D03*
X1318500Y962017D03*
X1311000Y964017D03*
X1315000D03*
X1317333Y1119914D03*
X1322853Y40035D03*
X1329736Y315870D03*
X1334010D03*
X1321862D03*
X1326136D03*
X1320903Y365258D03*
X1329064Y365266D03*
X1327584Y779122D03*
X1330500Y920017D03*
X1334500D03*
X1326500Y931017D03*
X1337610Y315870D03*
X1349747Y439056D03*
X1343846Y456118D03*
X1347846D03*
X1345000Y790517D03*
X1348917D03*
X1342500Y920017D03*
X1338500D03*
X1345948Y946120D03*
X1349948D03*
X1336000Y931017D03*
X1345459Y1120913D03*
X1349461Y1119914D03*
X1352817Y790517D03*
X1365000Y806517D03*
X1361000D03*
X1357000D03*
X1365948Y946120D03*
X1357948D03*
X1353948D03*
X1378505Y127840D03*
X1375694Y147846D03*
X1380500Y590517D03*
Y637017D03*
Y681517D03*
Y728517D03*
X1373000Y806517D03*
X1381000D03*
X1369000D03*
X1377017Y806515D03*
X1369948Y946120D03*
X1382560Y934338D03*
X1378503Y934337D03*
X1375265Y1024783D03*
X1377587Y1120913D03*
X1382920Y1119914D03*
X1386505Y127840D03*
X1390559Y127845D03*
X1390738Y142954D03*
X1389824Y232951D03*
X1395351Y233063D03*
X1399226Y233051D03*
X1394537Y806196D03*
X1398517Y806234D03*
X1407461Y233076D03*
X1410903Y464436D03*
X1413452Y636328D03*
X1407952D03*
X1402517Y806234D03*
X1406483D03*
X1402265Y992283D03*
X1406265D03*
X1411046Y1120913D03*
X1415048Y1119914D03*
X1407747Y1543477D03*
X1407255Y1566155D03*
X1417903Y442436D03*
X1427484Y464576D03*
X1422903Y464436D03*
X1425452Y636328D03*
X1417452D03*
X1421452D03*
X1432258Y1407832D03*
X1444641Y88546D03*
X1440641D03*
X1448641D03*
X1448971Y173090D03*
X1444971D03*
X1449198Y184347D03*
X1448137Y216699D03*
X1447079Y285000D03*
X1435484Y464576D03*
X1442944Y599742D03*
X1438944D03*
X1446944D03*
X1435248Y625184D03*
X1437980Y1028464D03*
X1443174Y1120913D03*
X1436258Y1407832D03*
X1437293Y1540507D03*
X1436801Y1563185D03*
X1452650Y88546D03*
X1452026Y259627D03*
X1461105Y275318D03*
X1451079Y285000D03*
X1455079D03*
X1454944Y599742D03*
X1458944D03*
X1450944D03*
X1462317Y1025319D03*
X1479380Y88821D03*
X1475431Y88893D03*
X1478867Y127840D03*
X1478056Y147846D03*
X1471500Y713017D03*
Y757017D03*
X1483287Y88916D03*
X1488867Y127840D03*
X1492921Y127845D03*
X1493100Y142954D03*
X1492186Y232951D03*
X1497713Y233063D03*
X1488500Y798517D03*
Y842517D03*
X1509823Y233076D03*
X1501588Y233051D03*
X1498495Y452598D03*
X1517660Y452317D03*
X1547003Y88546D03*
X1543003D03*
X1555012D03*
X1551003D03*
X1551333Y173090D03*
X1547333D03*
X1551560Y184347D03*
X1550499Y216699D03*
X1554388Y259627D03*
X1549441Y285000D03*
X1553441D03*
X1557441D03*
X1577793Y88893D03*
X1563467Y275318D03*
X1572238Y653253D03*
X1576238D03*
X1585649Y88916D03*
X1581742Y88821D03*
X1591229Y127840D03*
X1583229D03*
X1595283Y127845D03*
X1595462Y142954D03*
X1580418Y147846D03*
X1594548Y232951D03*
X1587746Y1457649D03*
X1594264Y1470032D03*
X1600075Y233063D03*
X1603950Y233051D03*
X1601500Y1509017D03*
X1598000D03*
X1608500D03*
X1610858Y1520332D03*
X1612185Y233076D03*
X1614538Y620880D03*
X1618538D03*
X1622538D03*
X1653365Y88546D03*
X1657374D03*
X1645365D03*
X1649365D03*
X1653695Y173090D03*
X1649695D03*
X1653922Y184347D03*
X1652861Y216699D03*
X1656750Y259627D03*
X1651803Y285000D03*
X1655803D03*
X1659803D03*
X1665829Y275318D03*
X1675803Y328959D03*
X1680155Y88893D03*
X1684104Y88821D03*
X1688011Y88916D03*
X1683591Y127840D03*
X1682780Y147846D03*
X1683523Y311832D03*
X1693591Y127840D03*
X1697645Y127845D03*
X1697824Y142954D03*
X1702437Y233063D03*
X1696910Y232951D03*
X1706312Y233051D03*
X1714547Y233076D03*
X1718851Y394025D03*
X1713545Y562229D03*
X1721008Y1137221D03*
X1725008D03*
X1713008D03*
X1712715Y1182062D03*
X1716731Y1181992D03*
X1721662Y1203535D03*
X1725662D03*
X1721660Y1195511D03*
X1725660D03*
X1709820Y1196607D03*
X1717568Y1203335D03*
X1741746Y379665D03*
X1737746D03*
X1739847Y403558D03*
X1735586Y481975D03*
X1733008Y1137221D03*
X1729008D03*
X1737417Y1147029D03*
X1737393Y1165309D03*
X1729662Y1203535D03*
X1733662D03*
X1737660Y1195511D03*
X1729660D03*
X1733660D03*
X1737662Y1203535D03*
X1751727Y88546D03*
X1755727D03*
X1747727D03*
X1756057Y173090D03*
X1752057D03*
X1756284Y184347D03*
X1755223Y216699D03*
X1754165Y285000D03*
X1758165D03*
X1748497Y373772D03*
X1750900Y904917D03*
X1756422Y1634821D03*
X1759736Y88546D03*
X1759112Y259627D03*
X1768191Y275318D03*
X1762165Y285000D03*
X1769497Y373573D03*
X1765813Y392919D03*
X1772425Y445554D03*
X1761072Y1593284D03*
X1765072D03*
X1772422Y1634821D03*
X1768422D03*
X1760422D03*
X1764422D03*
X1782517Y88893D03*
X1786466Y88821D03*
X1790373Y88916D03*
X1776071Y833411D03*
X1789537Y924594D03*
X1780774Y1208205D03*
X1778227Y1440625D03*
X1778104Y1472815D03*
X1776422Y1634821D03*
X1806834Y439056D03*
X1800933Y456118D03*
X1804933D03*
X1797374Y924466D03*
X1795347Y1096152D03*
X1804703Y1216370D03*
X1800046Y1437663D03*
X1799923Y1469853D03*
X1809700Y907117D03*
X1808363Y970177D03*
Y977591D03*
X1809200Y1212241D03*
G54D241*
X1028012Y1622787D03*
G54D22*
X19478Y160100D03*
X65713Y455494D03*
X115876Y117621D03*
X218238D03*
X320600D03*
X470601D03*
X520799Y452494D03*
X572963Y117621D03*
X675325D03*
X777687D03*
X927687D03*
X979886Y455494D03*
X1030049Y117621D03*
X1132411D03*
X1234773D03*
X1384774D03*
X1434973Y452494D03*
X1487136Y117621D03*
X1589498D03*
X1691860D03*
G54D14*
X8786Y82444D03*
X6298Y96682D03*
X18298D03*
X6499Y135880D03*
X15184Y147319D03*
X19184D03*
X8264Y156046D03*
X16709Y170318D03*
X17822Y209922D03*
X6811Y1002637D03*
X10701D03*
X14645D03*
X11768Y1522289D03*
X14375Y1547589D03*
X10367Y1547596D03*
X31971Y103502D03*
X23184Y147319D03*
X32201Y233075D03*
X26192Y613827D03*
X30192D03*
X33992D03*
X27556Y1002637D03*
X33659D03*
X21506D03*
X25674Y1488807D03*
X35850Y1550246D03*
X26231Y1548675D03*
X22381Y1548693D03*
X45643Y467435D03*
X49643D03*
X39549Y1002637D03*
X45858D03*
X51946D03*
X40951Y1550246D03*
X47074Y1550237D03*
X52048Y1550212D03*
X65759Y440010D03*
X61759D03*
X57759D03*
X54936Y451854D03*
X62224Y467575D03*
X66345Y487180D03*
X56514Y533924D03*
X64408Y575848D03*
X63684Y599741D03*
X61192Y636327D03*
X57692D03*
X64692D03*
X56149Y821324D03*
X65774Y1002637D03*
X61779D03*
X57834D03*
X57702Y1195761D03*
X61380Y1202487D03*
X53737Y1196921D03*
X54351Y1480899D03*
X56114Y1550211D03*
X64747Y1550204D03*
X63090Y1612093D03*
X70577Y98642D03*
X84808Y100544D03*
X80660Y98289D03*
X76660D03*
X76766Y259626D03*
X84766D03*
X78106Y659507D03*
X74910Y684528D03*
X84699Y1001482D03*
X87652Y575653D03*
X93456Y652341D03*
X95836Y983047D03*
X99836Y992047D03*
X95836D03*
X99836Y983047D03*
X97609Y1010913D03*
X104662Y113567D03*
X115582Y104840D03*
X111582D03*
X113607Y127839D03*
X106796Y154956D03*
X111836Y983047D03*
X103836D03*
X115836D03*
X107836D03*
X111836Y992047D03*
X103836D03*
X115836D03*
X107836D03*
X109601Y1223542D03*
X105601D03*
X119582Y104840D03*
X128251Y143853D03*
X120184Y209922D03*
X127235Y445597D03*
X119836Y983047D03*
X123836D03*
X127836D03*
X119836Y992047D03*
X123836D03*
X127836D03*
X131836Y983047D03*
Y992047D03*
X127604Y1102624D03*
Y1115224D03*
Y1140424D03*
Y1127824D03*
Y1153024D03*
Y1165624D03*
Y1178224D03*
X134333Y103502D03*
X134563Y233075D03*
X138971Y538907D03*
X142961Y538866D03*
X143836Y983047D03*
X147836D03*
X139836D03*
X143836Y992047D03*
X147836D03*
X139836D03*
X135836Y983047D03*
Y992047D03*
X139250Y1009887D03*
Y1022487D03*
X159836Y983047D03*
Y992047D03*
X155836D03*
X151836Y983047D03*
Y992047D03*
X172939Y98642D03*
X179022Y98289D03*
X179128Y259626D03*
X183022Y98289D03*
X188526Y97566D03*
Y105178D03*
X187128Y259626D03*
X201033Y88892D03*
X207024Y113567D03*
X213944Y104840D03*
X209158Y154956D03*
X221944Y104840D03*
X217944D03*
X215969Y127839D03*
X230613Y143853D03*
X222546Y209922D03*
X229942Y1546401D03*
X221942Y1534401D03*
X225753Y1534231D03*
X236695Y103502D03*
X236925Y233075D03*
X242102Y650762D03*
X246102D03*
X240842Y1527401D03*
X237942Y1546401D03*
X244942D03*
X233942D03*
X233753Y1534231D03*
X250102Y650762D03*
X248042Y1527401D03*
X275301Y98642D03*
X281384Y98289D03*
X290888Y97566D03*
X285384Y98289D03*
X290888Y105178D03*
X289490Y259626D03*
X281490D03*
X303395Y88892D03*
X309386Y113567D03*
X311520Y154956D03*
X312263Y318831D03*
X324306Y104840D03*
X320306D03*
X316306D03*
X318222Y127730D03*
X324908Y209922D03*
X317416Y342410D03*
X321416D03*
X323285Y550228D03*
X339057Y103502D03*
X332975Y143853D03*
X339287Y233075D03*
X342486Y379664D03*
X342285Y555228D03*
X336755Y1137220D03*
X337629Y1175841D03*
X342298Y1190932D03*
X346486Y379664D03*
X358486D03*
X350486D03*
X354486D03*
X353202Y409018D03*
X345748Y1137220D03*
X350414Y1175181D03*
X358443Y1174202D03*
X354414Y1175181D03*
X359761Y1182142D03*
X354442Y1182146D03*
X350442D03*
X346136Y1191067D03*
X370931Y364380D03*
X362486Y379664D03*
X374714Y790285D03*
X365748Y1137220D03*
X362282Y1174865D03*
X363729Y1182179D03*
X377663Y98642D03*
X393250Y97566D03*
X387746Y98289D03*
X383746D03*
X393250Y105178D03*
X383852Y259626D03*
X391852D03*
X389237Y373570D03*
X381237D03*
X385237D03*
X404686Y39989D03*
X400686D03*
X394237Y373572D03*
X403478Y872784D03*
X399369D03*
X399816Y953163D03*
X400043Y964420D03*
X404043D03*
X403263Y1155275D03*
X397461Y1563525D03*
X401461D03*
X420422Y362173D03*
X412318Y362165D03*
X411847Y429353D03*
X425673Y456117D03*
X426000Y786316D03*
X416200Y795616D03*
X417682Y1054729D03*
X410668Y1102646D03*
X414455D03*
X422532Y1098858D03*
X421461Y1563525D03*
X417461D03*
X431424Y362034D03*
X435024D03*
X427566Y880949D03*
X427913Y1098858D03*
X431285Y1110412D03*
X449745Y625576D03*
X445745D03*
X442796Y1102646D03*
X446583D03*
X454660Y1098858D03*
X456025Y1218004D03*
X459387Y113567D03*
X474307Y104840D03*
X470307D03*
X466307D03*
X468332Y127839D03*
X461521Y154956D03*
X474909Y209922D03*
X468836Y540113D03*
X460041Y1098858D03*
X463413Y1110412D03*
X468850Y1155275D03*
X462687D03*
X461319Y1218004D03*
X489058Y103502D03*
X482976Y143853D03*
X489288Y233075D03*
X485485Y434433D03*
X489485D03*
X491078Y613827D03*
X483278D03*
X487278D03*
X476255Y1102646D03*
X480042D03*
X488119Y1098858D03*
X500729Y464435D03*
X504729D03*
X501082Y989697D03*
X505958Y1055022D03*
X493500Y1098858D03*
X496872Y1110412D03*
X520845Y437010D03*
X516845D03*
X512845D03*
X510022Y448854D03*
X517310Y464575D03*
X523431Y487180D03*
X513600Y533924D03*
X521494Y575848D03*
X520770Y599741D03*
X516770D03*
X518278Y636327D03*
X514778D03*
X521778D03*
X519285Y725512D03*
X515285D03*
X511285D03*
X523285D03*
X509096Y755806D03*
X513504Y758923D03*
X508383Y1102646D03*
X512170D03*
X520247Y1098858D03*
X527664Y98642D03*
X537747Y98289D03*
X533747D03*
X533853Y259626D03*
X539285Y725512D03*
X535285D03*
X531285D03*
X527285D03*
X524319Y758897D03*
X536715Y1006337D03*
X529000Y1110412D03*
X528274Y1155275D03*
X555758Y88892D03*
X543251Y97566D03*
Y105178D03*
X541853Y259626D03*
X544738Y575653D03*
X552923Y983047D03*
Y992047D03*
X554696Y1010913D03*
X561749Y113567D03*
X568669Y104840D03*
X570694Y127839D03*
X563883Y154956D03*
X568464Y754990D03*
X560256Y776190D03*
X556923Y983047D03*
Y992047D03*
X568923Y983047D03*
X560923D03*
X564923D03*
X568923Y992047D03*
X560923D03*
X564923D03*
X562688Y1223542D03*
X566688D03*
X564242Y1525201D03*
X571942Y1544301D03*
X571809Y1535517D03*
X562786Y1534625D03*
X558786D03*
X576669Y104840D03*
X572669D03*
X585338Y143853D03*
X577271Y209922D03*
X584321Y445597D03*
X573203Y935413D03*
X576923Y983047D03*
X580923D03*
X584923D03*
X576923Y992047D03*
X580923D03*
X584923D03*
X572923Y983047D03*
Y992047D03*
X584691Y1102624D03*
Y1115224D03*
Y1140424D03*
Y1127824D03*
Y1153024D03*
Y1165624D03*
Y1178224D03*
X583742Y1544801D03*
X587809Y1535517D03*
X579809D03*
X591420Y103502D03*
X591650Y233075D03*
X600047Y538866D03*
X596057Y538907D03*
X600923Y983047D03*
X604923D03*
X592923D03*
X596923D03*
X600923Y992047D03*
X604923D03*
X592923D03*
X596923D03*
X588923Y983047D03*
Y992047D03*
X596337Y1009887D03*
Y1022487D03*
X600242Y1538601D03*
X591809Y1535517D03*
X608923Y992047D03*
X616923D03*
X612923D03*
X608923Y983047D03*
X616923D03*
X630026Y98642D03*
X636109Y98289D03*
X636215Y259626D03*
X645613Y97566D03*
X640109Y98289D03*
X645613Y105178D03*
X644215Y259626D03*
X658120Y88892D03*
X664111Y113567D03*
X666245Y154956D03*
X679031Y104840D03*
X671031D03*
X675031D03*
X673056Y127839D03*
X679633Y209922D03*
X693782Y103502D03*
X687700Y143853D03*
X694012Y233075D03*
X699188Y650762D03*
X688728Y700450D03*
X703188Y650762D03*
X707188D03*
X713382Y702253D03*
X732388Y98642D03*
X723811Y739072D03*
X742471Y98289D03*
X747975Y97566D03*
X738471Y98289D03*
X747975Y105178D03*
X738577Y259626D03*
X746577D03*
X747140Y1583826D03*
X748924Y1611884D03*
X748997Y1621426D03*
X747590Y1630725D03*
X760482Y88892D03*
X766473Y113567D03*
X763145Y1583804D03*
X759169Y1583851D03*
X763452Y1613858D03*
X752150Y1630750D03*
X781393Y104840D03*
X773393D03*
X777393D03*
X775418Y127839D03*
X768607Y154956D03*
X781995Y209922D03*
X769349Y318831D03*
X774502Y342410D03*
X778502D03*
X780371Y550228D03*
X767512Y1446718D03*
X783215Y1449666D03*
X777033Y1589513D03*
X781110D03*
X767452Y1613858D03*
X773822Y1630241D03*
X796144Y103502D03*
X790062Y143853D03*
X796374Y233075D03*
X799371Y555228D03*
X793842Y1137220D03*
X794716Y1175841D03*
X799230Y1203547D03*
X798324Y1195125D03*
X799901Y1469617D03*
X791610Y1596529D03*
X787447Y1596552D03*
X802835Y1137220D03*
X811529Y1182146D03*
X811501Y1175181D03*
X807501D03*
X807529Y1182146D03*
X814148Y1377699D03*
X832284Y713530D03*
X827284Y706580D03*
Y713530D03*
X828880Y867380D03*
X828643Y893105D03*
X826987Y926721D03*
X831409Y919309D03*
X827409D03*
X828423Y959210D03*
X822835Y1137220D03*
X816848Y1182142D03*
X820826Y1175229D03*
X820816Y1182179D03*
X816826Y1175229D03*
X834750Y98642D03*
X840833Y98289D03*
X844833D03*
X840939Y259626D03*
X848284Y713530D03*
X839290Y706560D03*
X843284Y706580D03*
X839290Y713510D03*
X843284Y713530D03*
X833112Y833606D03*
X836405Y860508D03*
X832880Y867380D03*
X832643Y893105D03*
X842000Y898516D03*
X848628Y909605D03*
X846000Y898516D03*
X841064Y919109D03*
X837235D03*
X840423Y959210D03*
X862844Y88892D03*
X850337Y97566D03*
Y105178D03*
X848939Y259626D03*
X858586Y377016D03*
X854086D03*
X858586Y387516D03*
X854086D03*
X863086D03*
X852284Y706580D03*
Y713530D03*
X856628Y909605D03*
X864628D03*
X849205Y926725D03*
X852488Y1014169D03*
X857884D03*
X864007D03*
X874531Y197441D03*
X880736Y385796D03*
X875916Y813556D03*
X872628Y909605D03*
X880628D03*
X879740Y941217D03*
X870401Y1014169D03*
X875954D03*
X893736Y385796D03*
X888736D03*
X884736D03*
X892931Y536584D03*
X885931D03*
X889431D03*
X895933Y612684D03*
X892728Y789792D03*
X895916Y813556D03*
X888628Y909605D03*
X892628D03*
X896628D03*
X881454Y1014169D03*
X885210D03*
X889089D03*
X893613Y1014312D03*
X904614Y340380D03*
X908114D03*
X911072Y381423D03*
X907173Y445694D03*
X899931Y536584D03*
X913208Y612535D03*
X909208D03*
X904376Y612455D03*
X900376D03*
X903916Y803406D03*
X899916Y813556D03*
Y803406D03*
X903916Y813556D03*
X909416D03*
X900200Y909616D03*
X907300D03*
X903700D03*
X912628Y922642D03*
X904057Y937629D03*
X906255Y1015797D03*
X898046Y1014256D03*
X902225Y1015744D03*
X901392Y1204764D03*
X897427Y1205924D03*
X905070Y1211490D03*
X916473Y113567D03*
X927393Y104840D03*
X923393D03*
X925418Y127839D03*
X918607Y154956D03*
X915072Y381423D03*
X920999Y472458D03*
X925418Y677886D03*
X921418D03*
X921061Y709861D03*
X925061D03*
X927916Y811556D03*
X921790Y813556D03*
X920628Y922642D03*
X924628D03*
X928628D03*
X916628D03*
X927984Y1014169D03*
X916465D03*
X921861D03*
X931393Y104840D03*
X940062Y143853D03*
X932661Y195093D03*
X938125Y233760D03*
X942757Y254705D03*
X941685Y357769D03*
X942437Y364721D03*
X931072Y381423D03*
X940365Y613827D03*
X944365D03*
X932412Y677886D03*
X938526Y727541D03*
X935916Y811556D03*
X939916D03*
X941535Y823573D03*
X937635D03*
X940516Y895121D03*
X944628Y922642D03*
X936628D03*
X940628D03*
X932628D03*
X945671Y985759D03*
X939931Y1014169D03*
X945431D03*
X934378D03*
X946144Y103502D03*
X947040Y218246D03*
X951278Y238064D03*
Y245043D03*
X959816Y467435D03*
X948165Y613827D03*
X961503Y701348D03*
X953551D03*
X957551D03*
X959950Y728554D03*
X952783Y830299D03*
X951100Y838616D03*
X947200D03*
X957900Y850516D03*
X958567Y930335D03*
X950567D03*
X953671Y985759D03*
X961671D03*
X949671D03*
X950987Y1014169D03*
X954866D03*
X961404Y1205924D03*
X975932Y440010D03*
X971932D03*
X969109Y451854D03*
X963816Y467435D03*
X976397Y467575D03*
X970687Y533924D03*
X978581Y575848D03*
X977857Y599741D03*
X973857D03*
X975365Y636327D03*
X971865D03*
X963950Y728554D03*
X966746Y930308D03*
X962567Y930335D03*
X965671Y985759D03*
X967625Y1014400D03*
X971760Y1014420D03*
X963823Y1014256D03*
X975659Y1014441D03*
X965369Y1204764D03*
X969047Y1211490D03*
X984750Y98642D03*
X990833Y98289D03*
X994833D03*
X990939Y259626D03*
X990405Y311033D03*
X988045Y361100D03*
X992045D03*
X979932Y440010D03*
X980518Y487180D03*
X978865Y636327D03*
X983712Y716605D03*
X994051Y813859D03*
X1000337Y97566D03*
Y105178D03*
X998939Y259626D03*
X1000698Y302767D03*
X996045Y361100D03*
X1001825Y575653D03*
X1007990Y768490D03*
X995990D03*
X1006699Y813916D03*
X1002699D03*
X1010699D03*
X1010009Y983047D03*
Y992047D03*
X998872Y1001482D03*
X1000248Y1021427D03*
X1012844Y88892D03*
X1018835Y113567D03*
X1025755Y104840D03*
X1020969Y154956D03*
X1016635Y302767D03*
X1020635D03*
X1025749D03*
X1012635D03*
X1018922Y802831D03*
X1014819Y932428D03*
X1026009Y983047D03*
X1018009D03*
X1022009D03*
X1014009D03*
X1026009Y992047D03*
X1018009D03*
X1022009D03*
X1014009D03*
X1011782Y1010913D03*
X1019774Y1223542D03*
X1023774D03*
X1017329Y1313528D03*
X1020049Y1330852D03*
X1019671Y1345015D03*
X1019257Y1363489D03*
X1033755Y104840D03*
X1029755D03*
X1027780Y127839D03*
X1042424Y143853D03*
X1034357Y209922D03*
X1029639Y302767D03*
X1041408Y445597D03*
X1030009Y983047D03*
X1038009D03*
X1042009D03*
X1034009Y992047D03*
X1030009D03*
X1038009D03*
X1042009D03*
X1034009Y983047D03*
X1041777Y1102624D03*
Y1115224D03*
Y1140424D03*
Y1127824D03*
Y1153024D03*
Y1165624D03*
Y1178224D03*
X1038996Y1368583D03*
X1048506Y103502D03*
X1048736Y233075D03*
X1045650Y302767D03*
X1057134Y538866D03*
X1053144Y538907D03*
X1046009Y983047D03*
X1050009D03*
X1054009D03*
X1046009Y992047D03*
X1050009D03*
X1054009D03*
X1058009D03*
Y983047D03*
X1053423Y1009887D03*
Y1022487D03*
X1074009Y992047D03*
Y983047D03*
X1066009Y992047D03*
X1062009D03*
X1070009D03*
X1066009Y983047D03*
X1062009D03*
X1087112Y98642D03*
X1086108Y1523524D03*
X1090904Y1593297D03*
X1086469Y1582501D03*
X1089474Y1631941D03*
X1093195Y98289D03*
X1097195D03*
X1102699Y97566D03*
Y105178D03*
X1093301Y259626D03*
X1101301D03*
X1096233Y1582524D03*
X1102904Y1593297D03*
X1104233Y1582524D03*
X1093474Y1631941D03*
X1101474D03*
X1105474D03*
X1115206Y88892D03*
X1121197Y113567D03*
X1123331Y154956D03*
X1136117Y104840D03*
X1132117D03*
X1128117D03*
X1130142Y127839D03*
X1136719Y209922D03*
X1150868Y103502D03*
X1144786Y143853D03*
X1151098Y233075D03*
X1156275Y650762D03*
X1156485Y767658D03*
X1155485Y839158D03*
X1160275Y650762D03*
X1164275D03*
X1167485Y825658D03*
X1159485D03*
X1171485Y839158D03*
X1163485D03*
X1167485D03*
X1159485D03*
X1189474Y98642D03*
X1183485Y825658D03*
X1175485D03*
X1183485Y839158D03*
X1179485D03*
X1175485D03*
X1195557Y98289D03*
X1199557D03*
X1205061Y97566D03*
Y105178D03*
X1195663Y259626D03*
X1203663D03*
X1217568Y88892D03*
X1238479Y104840D03*
X1223559Y113567D03*
X1234479Y104840D03*
X1230479D03*
X1232504Y127839D03*
X1225693Y154956D03*
X1226436Y318831D03*
X1231589Y342410D03*
X1235589D03*
X1237458Y550228D03*
X1253230Y103502D03*
X1247148Y143853D03*
X1239081Y209922D03*
X1253460Y233075D03*
X1250928Y1137220D03*
X1251802Y1175841D03*
X1249230Y1189437D03*
X1256659Y379664D03*
X1268659D03*
X1260659D03*
X1264659D03*
X1267375Y409018D03*
X1256458Y555228D03*
X1261622Y898533D03*
X1259921Y1137220D03*
X1264587Y1175181D03*
X1268587D03*
X1268615Y1182146D03*
X1264615D03*
X1255485Y1198941D03*
X1275660Y342726D03*
X1279655Y342667D03*
X1276659Y379664D03*
X1272659D03*
X1280042Y902164D03*
X1279921Y1137220D03*
X1277912Y1175229D03*
X1273912D03*
X1273934Y1182142D03*
X1277902Y1182179D03*
X1291836Y98642D03*
X1297919Y98289D03*
X1301919D03*
X1298025Y259626D03*
X1303410Y373570D03*
X1287437Y372695D03*
X1295410Y373570D03*
X1299410D03*
X1292566Y804337D03*
X1298909Y815608D03*
X1288155Y895016D03*
X1302000Y920016D03*
X1298000D03*
X1300882Y931080D03*
X1300500Y964016D03*
X1314859Y39989D03*
X1318859D03*
X1307423Y97566D03*
Y105178D03*
X1306025Y259626D03*
X1308410Y373572D03*
X1316903Y365257D03*
X1317000Y790516D03*
X1313000D03*
Y806516D03*
X1317000D03*
X1313152Y931080D03*
X1309103D03*
X1317000Y938016D03*
X1304949Y931080D03*
X1307000Y964016D03*
X1317437Y1155275D03*
X1325007Y365265D03*
X1334009Y365126D03*
X1326020Y429353D03*
X1333000Y790516D03*
X1329000D03*
X1325000D03*
X1321000D03*
X1333000Y806516D03*
X1325000D03*
X1329000D03*
X1321000D03*
X1322500Y920016D03*
X1326500D03*
Y938016D03*
X1327000Y964016D03*
X1332000D03*
X1331856Y1054729D03*
X1324842Y1102646D03*
X1328629D03*
X1337609Y365126D03*
X1339846Y456117D03*
X1341000Y790516D03*
X1337000D03*
X1341000Y806516D03*
X1345000D03*
X1349000D03*
X1337000D03*
X1350500Y920016D03*
X1336000Y938016D03*
X1337691Y948659D03*
X1342087Y1098858D03*
X1336706D03*
X1345459Y1110412D03*
X1353000Y806516D03*
X1354500Y920016D03*
X1358500D03*
X1362500D03*
X1366500D03*
X1361948Y946119D03*
X1356970Y1102646D03*
X1360757D03*
X1373560Y113567D03*
X1384480Y104840D03*
X1380480D03*
X1382505Y127839D03*
X1375694Y154956D03*
X1370500Y920016D03*
X1378500D03*
X1374500D03*
X1382500D03*
X1373948Y946119D03*
X1374215Y1098858D03*
X1368834D03*
X1377587Y1110412D03*
X1376861Y1155275D03*
X1383024D03*
X1388480Y104840D03*
X1397149Y143853D03*
X1389082Y209922D03*
X1397452Y613827D03*
X1390537Y806195D03*
X1386335Y806220D03*
X1388346Y924161D03*
X1390429Y1102646D03*
X1394216D03*
X1403231Y103502D03*
X1403461Y233075D03*
X1414903Y464435D03*
X1405252Y613827D03*
X1401452D03*
X1401000Y920016D03*
X1407674Y1098858D03*
X1402293D03*
X1411046Y1110412D03*
X1416684Y1511665D03*
X1411586Y1543470D03*
X1411094Y1566148D03*
X1431019Y437010D03*
X1427019D03*
X1424196Y448854D03*
X1431484Y464575D03*
X1418903Y464435D03*
X1427774Y533924D03*
X1430944Y599741D03*
X1432452Y636327D03*
X1428952D03*
X1420132Y1055022D03*
X1422557Y1102646D03*
X1426344D03*
X1426253Y1407793D03*
X1430374Y1495586D03*
X1433405Y1540508D03*
X1432913Y1563186D03*
X1441837Y98642D03*
X1447920Y98289D03*
X1448026Y259626D03*
X1435019Y437010D03*
X1437605Y487180D03*
X1435668Y575848D03*
X1434944Y599741D03*
X1435952Y636327D03*
X1443459Y1034427D03*
X1434421Y1098858D03*
X1443174Y1110412D03*
X1442448Y1155275D03*
X1436792Y1555457D03*
X1457424Y97566D03*
X1451920Y98289D03*
X1457424Y105178D03*
X1456026Y259626D03*
X1458912Y575653D03*
X1455959Y1001482D03*
X1469931Y88892D03*
X1475922Y113567D03*
X1478056Y154956D03*
X1475096Y983047D03*
X1479096D03*
X1471096D03*
X1475096Y992047D03*
X1479096D03*
X1471096D03*
X1467096Y983047D03*
Y992047D03*
X1468869Y1010913D03*
X1480861Y1223542D03*
X1476861D03*
X1490842Y104840D03*
X1482842D03*
X1486842D03*
X1484867Y127839D03*
X1491444Y209922D03*
X1491096Y983047D03*
X1487096D03*
X1495096D03*
X1491096Y992047D03*
X1487096D03*
X1495096D03*
X1483096Y983047D03*
Y992047D03*
X1505593Y103502D03*
X1499511Y143853D03*
X1505823Y233075D03*
X1498495Y445597D03*
X1514221Y538866D03*
X1510231Y538907D03*
X1503096Y983047D03*
X1507096D03*
X1511096D03*
X1503096Y992047D03*
X1507096D03*
X1511096D03*
X1499096D03*
Y983047D03*
X1510510Y1009887D03*
Y1022487D03*
X1498864Y1102624D03*
Y1115224D03*
Y1127824D03*
Y1140424D03*
Y1153024D03*
Y1165624D03*
Y1178224D03*
X1525015Y903541D03*
X1523096Y983047D03*
X1519096D03*
X1523096Y992047D03*
X1519096D03*
X1527096D03*
X1515096Y983047D03*
Y992047D03*
X1544199Y98642D03*
X1531096Y983047D03*
Y992047D03*
X1554282Y98289D03*
X1559786Y97566D03*
X1550282Y98289D03*
X1559786Y105178D03*
X1550388Y259626D03*
X1558388D03*
X1572293Y88892D03*
X1578284Y113567D03*
X1593204Y104840D03*
X1589204D03*
X1585204D03*
X1587229Y127839D03*
X1580418Y154956D03*
X1593806Y209922D03*
X1594307Y1502071D03*
X1594500Y1509016D03*
X1607955Y103502D03*
X1601873Y143853D03*
X1608185Y233075D03*
X1608483Y780418D03*
X1608383Y795218D03*
X1608283Y809218D03*
X1600333Y1443501D03*
X1605000Y1509016D03*
X1598142Y1527401D03*
X1613362Y650762D03*
X1617362D03*
X1621362D03*
X1616683Y747518D03*
X1616583Y761518D03*
X1634083Y774718D03*
X1632583Y787418D03*
X1631383Y801518D03*
X1646561Y98642D03*
X1652644Y98289D03*
X1656644D03*
X1652750Y259626D03*
X1660750D03*
X1674655Y88892D03*
X1662148Y97566D03*
Y105178D03*
X1680646Y113567D03*
X1691566Y104840D03*
X1687566D03*
X1689591Y127839D03*
X1682780Y154956D03*
X1683523Y318831D03*
X1688676Y342410D03*
X1692676D03*
X1695566Y104840D03*
X1704235Y143853D03*
X1696168Y209922D03*
X1694545Y550228D03*
X1708015Y1137220D03*
X1708889Y1175841D03*
X1708745Y1224216D03*
X1710317Y103502D03*
X1710547Y233075D03*
X1713746Y379664D03*
X1717746D03*
X1725746D03*
X1721746D03*
X1724462Y409018D03*
X1713545Y555228D03*
X1717008Y1137220D03*
X1725674Y1175181D03*
X1721674D03*
X1725702Y1182146D03*
X1721702D03*
X1713721Y1203402D03*
X1709827Y1203356D03*
X1712966Y1224207D03*
X1733746Y379664D03*
X1729746D03*
X1737008Y1137220D03*
X1734999Y1175229D03*
X1730999D03*
X1731021Y1182142D03*
X1734989Y1182179D03*
X1748923Y98642D03*
X1755006Y98289D03*
X1755112Y259626D03*
X1752497Y373570D03*
X1756497D03*
X1756297Y1015568D03*
X1753221Y1618595D03*
X1764510Y97566D03*
X1759006Y98289D03*
X1764510Y105178D03*
X1763112Y259626D03*
X1765497Y373572D03*
X1760497Y373570D03*
X1765131Y1015568D03*
X1760487D03*
X1771992D03*
X1774339Y1440626D03*
X1774216Y1472816D03*
X1763000Y1582016D03*
X1777017Y88892D03*
X1783107Y429353D03*
X1789463Y963266D03*
X1784145Y1015568D03*
X1790035D03*
X1778042D03*
X1796933Y456117D03*
X1793474Y924502D03*
X1796344Y1015568D03*
X1802432D03*
X1805384Y1206410D03*
X1803885Y1437656D03*
X1803762Y1469846D03*
X1808320Y1015568D03*
X1812265D03*
X1816260D03*
X1809349Y1205250D03*
X1813027Y1211976D03*
X1828272Y1106087D03*
Y1099048D03*
G54D41*
X23622Y1604724D03*
X62205Y765197D03*
X74016Y333464D03*
X102224Y70866D03*
X409488Y1604724D03*
X433130Y70866D03*
X463387Y286221D03*
X463386Y765197D03*
X661674Y23622D03*
X785039Y1547638D03*
X890217Y23622D03*
X920473Y765196D03*
X1055905Y1547637D03*
X1118760Y23622D03*
X1347303Y70866D03*
X1377559Y286220D03*
Y765197D03*
X1431457Y1604724D03*
X1575846Y23622D03*
X1766929Y333464D03*
X1778740Y765197D03*
X1795010Y23622D03*
X1817323Y1604724D03*
G54D143*
X428500Y338500D03*
X1331085Y341592D03*
G54D50*
X40079Y1521641D03*
G54D170*
X553958Y744599D03*
Y747158D03*
Y749717D03*
X561832D03*
Y747158D03*
Y744599D03*
X699789Y697094D03*
Y699653D03*
Y702212D03*
X707663Y699653D03*
Y697094D03*
Y702212D03*
G54D116*
X310628Y328844D03*
Y336324D03*
X320274Y328844D03*
Y336324D03*
Y332584D03*
X767714Y328844D03*
Y336324D03*
X777360Y328844D03*
Y336324D03*
Y332584D03*
X859838Y685230D03*
Y692710D03*
Y688970D03*
X869484Y685230D03*
Y692710D03*
X896074Y940895D03*
X886428D03*
Y944635D03*
X896074Y948375D03*
X886428D03*
X1224801Y328844D03*
X1234447D03*
X1224801Y336324D03*
X1234447D03*
Y332584D03*
X1681888Y328844D03*
X1691534D03*
X1681888Y336324D03*
X1691534D03*
Y332584D03*
G54D32*
X8788Y992319D03*
Y986519D03*
X14513Y992319D03*
Y986519D03*
X20006Y992319D03*
Y986519D03*
X30903Y992319D03*
Y986519D03*
X36293Y992319D03*
Y986519D03*
X25462Y992319D03*
Y986519D03*
X41792Y992319D03*
Y986519D03*
X47234Y992319D03*
Y986519D03*
X47425Y1242619D03*
Y1248419D03*
X117670Y1011465D03*
X110258Y1014862D03*
Y1020662D03*
X117670Y1017265D03*
Y1024065D03*
Y1029865D03*
X106024Y1104202D03*
Y1110002D03*
Y1116802D03*
Y1122602D03*
Y1129402D03*
Y1135202D03*
Y1142002D03*
Y1147802D03*
Y1154602D03*
Y1160402D03*
Y1167202D03*
Y1173002D03*
Y1179802D03*
Y1185602D03*
X374800Y770700D03*
Y776500D03*
X389627Y881760D03*
Y875860D03*
X406173Y455001D03*
Y449201D03*
X400711Y1217592D03*
Y1211792D03*
X411673Y449201D03*
Y455001D03*
X412040Y840629D03*
Y834829D03*
X426822Y1217735D03*
Y1211935D03*
X456091Y1029816D03*
Y1035716D03*
X455968Y1206277D03*
Y1212077D03*
X455592Y1260171D03*
Y1265971D03*
X461319Y1206276D03*
Y1212076D03*
X461101Y1260171D03*
Y1265971D03*
X499598Y1217351D03*
Y1211551D03*
X526120Y1218053D03*
Y1212253D03*
X567345Y1014862D03*
Y1020662D03*
X563111Y1104202D03*
Y1110002D03*
Y1116802D03*
Y1122602D03*
Y1129402D03*
Y1135202D03*
Y1142002D03*
Y1147802D03*
Y1154602D03*
Y1160402D03*
Y1167202D03*
Y1173002D03*
Y1179802D03*
Y1185602D03*
X574757Y1011465D03*
Y1024065D03*
Y1017265D03*
Y1029865D03*
X866448Y1003630D03*
Y997830D03*
X871389Y1003630D03*
Y997830D03*
X876279Y1003630D03*
Y997830D03*
X881278Y1003630D03*
Y997830D03*
X886220Y1003630D03*
Y997830D03*
X891068Y1003630D03*
Y997830D03*
X895989Y1003630D03*
Y997830D03*
X891115Y1251622D03*
Y1257422D03*
X901499Y471342D03*
Y465542D03*
X906999D03*
Y471342D03*
X900721Y1003630D03*
Y997830D03*
X913751Y1004630D03*
Y998830D03*
X925969Y1003630D03*
Y997830D03*
X920476Y1003630D03*
Y997830D03*
X936866Y1003630D03*
Y997830D03*
X942256Y1003630D03*
Y997830D03*
X931425Y1003630D03*
Y997830D03*
X961110Y1003283D03*
Y997483D03*
X955092Y1251622D03*
Y1257422D03*
X973080Y1003456D03*
Y997656D03*
X1002052Y1397662D03*
Y1403462D03*
X1024431Y1014862D03*
Y1020662D03*
X1020197Y1104202D03*
Y1116802D03*
Y1122602D03*
Y1110002D03*
Y1129402D03*
Y1135202D03*
Y1142002D03*
Y1147802D03*
Y1154602D03*
Y1160402D03*
Y1167202D03*
Y1173002D03*
Y1179802D03*
Y1185602D03*
X1031843Y1011465D03*
Y1017265D03*
Y1024065D03*
Y1029865D03*
X1053227Y811659D03*
Y817459D03*
X1314823Y1217928D03*
Y1212128D03*
X1320346Y455001D03*
Y449201D03*
X1325846D03*
Y455001D03*
X1341454Y1217562D03*
Y1211762D03*
X1370265Y1029816D03*
Y1035716D03*
X1414947Y1217224D03*
Y1211424D03*
X1440660Y1217062D03*
Y1211262D03*
X1481518Y1014862D03*
Y1020662D03*
X1477284Y1104202D03*
Y1116802D03*
Y1122602D03*
Y1110002D03*
Y1129402D03*
Y1135202D03*
Y1142002D03*
Y1147802D03*
Y1154602D03*
Y1167202D03*
Y1173002D03*
Y1160402D03*
Y1179802D03*
Y1185602D03*
X1488930Y1011465D03*
Y1024065D03*
Y1017265D03*
Y1029865D03*
X1746267Y903414D03*
Y909214D03*
X1770492Y1005250D03*
Y999450D03*
X1759274Y1005250D03*
Y999450D03*
X1764999Y1005250D03*
Y999450D03*
X1777433Y455001D03*
Y449201D03*
X1782933D03*
Y455001D03*
X1786779Y1005250D03*
Y999450D03*
X1775948Y1005250D03*
Y999450D03*
X1781389Y1005250D03*
Y999450D03*
X1792278Y1005250D03*
Y999450D03*
X1797720Y1005250D03*
Y999450D03*
X1799072Y1252108D03*
Y1257908D03*
G54D152*
X419061Y1143544D03*
Y1167756D03*
X446889Y1143544D03*
Y1167756D03*
X484648Y1143544D03*
Y1167756D03*
X512476Y1143544D03*
Y1167756D03*
X1333235Y1143544D03*
Y1167756D03*
X1361063Y1143544D03*
Y1167756D03*
X1398822Y1143544D03*
Y1167756D03*
X1426650Y1143544D03*
Y1167756D03*
G54D215*
X938526Y719903D03*
X946086Y712147D03*
Y719903D03*
G54D224*
X941610Y1459592D03*
X967768Y1459845D03*
X990834D03*
X1013866Y1459945D03*
X1036752Y1460061D03*
G54D161*
X468408Y1007854D03*
X473133D03*
X471558D03*
X469983D03*
Y1026752D03*
X471558D03*
X473133D03*
X468408D03*
X479432Y1007854D03*
X477857D03*
X476282D03*
X474708D03*
X481007D03*
X482582D03*
Y1026752D03*
X481007D03*
X479432D03*
X477857D03*
X476282D03*
X474708D03*
X1382582Y1007854D03*
Y1026752D03*
X1393606Y1007854D03*
X1392031D03*
X1390456D03*
X1388882D03*
X1395181D03*
X1396756D03*
X1387307D03*
X1385732D03*
X1384157D03*
X1396756Y1026752D03*
X1395181D03*
X1384157D03*
X1385732D03*
X1387307D03*
X1393606D03*
X1392031D03*
X1390456D03*
X1388882D03*
G54D251*
X1776778Y818696D03*
G54D23*
X18887Y156163D03*
X16919D03*
X14951D03*
X18887Y164037D03*
X16919D03*
X14951D03*
X65122Y451557D03*
X63154D03*
X61186D03*
X65122Y459431D03*
X63154D03*
X61186D03*
X79038Y277477D03*
X81006D03*
X82974D03*
X79038Y269603D03*
X81006D03*
X82974D03*
X115285Y113684D03*
X113317D03*
X111349D03*
Y121558D03*
X113317D03*
X115285D03*
X181400Y277477D03*
Y269603D03*
X183368Y277477D03*
X185336D03*
X183368Y269603D03*
X185336D03*
X213711Y113684D03*
Y121558D03*
X217647Y113684D03*
X215679D03*
X217647Y121558D03*
X215679D03*
X283762Y277477D03*
X285730D03*
X287698D03*
X283762Y269603D03*
X285730D03*
X287698D03*
X320009Y113684D03*
X318041D03*
X316073D03*
X320009Y121558D03*
X318041D03*
X316073D03*
X386124Y277477D03*
X388092D03*
X390060D03*
X386124Y269603D03*
X388092D03*
X390060D03*
X470010Y113684D03*
X468042D03*
X466074D03*
X470010Y121558D03*
X468042D03*
X466074D03*
X520208Y448557D03*
X518240D03*
X516272D03*
X520208Y456431D03*
X518240D03*
X516272D03*
X536125Y277477D03*
X538093D03*
X536125Y269603D03*
X538093D03*
X540061Y277477D03*
Y269603D03*
X570404Y113684D03*
X568436D03*
X570404Y121558D03*
X568436D03*
X572372Y113684D03*
Y121558D03*
X638487Y277477D03*
X640455D03*
X642423D03*
X638487Y269603D03*
X640455D03*
X642423D03*
X674734Y113684D03*
X672766D03*
X670798D03*
X674734Y121558D03*
X672766D03*
X670798D03*
X740849Y277477D03*
X742817D03*
X744785D03*
X740849Y269603D03*
X742817D03*
X744785D03*
X777096Y113684D03*
X775128D03*
X773160D03*
X777096Y121558D03*
X775128D03*
X773160D03*
X843211Y277477D03*
X845179D03*
X847147D03*
X843211Y269603D03*
X845179D03*
X847147D03*
X927096Y113684D03*
X925128D03*
X923160D03*
X927096Y121558D03*
X925128D03*
X923160D03*
X977327Y451557D03*
X975359D03*
X977327Y459431D03*
X975359D03*
X993211Y277477D03*
Y269603D03*
X979295Y451557D03*
Y459431D03*
X995179Y277477D03*
X997147D03*
X995179Y269603D03*
X997147D03*
X1025522Y113684D03*
Y121558D03*
X1029458Y113684D03*
X1027490D03*
X1029458Y121558D03*
X1027490D03*
X1095573Y277477D03*
X1097541D03*
X1099509D03*
X1095573Y269603D03*
X1097541D03*
X1099509D03*
X1131820Y113684D03*
X1129852D03*
X1127884D03*
X1131820Y121558D03*
X1129852D03*
X1127884D03*
X1197935Y277477D03*
X1199903D03*
X1201871D03*
X1197935Y269603D03*
X1199903D03*
X1201871D03*
X1234182Y113684D03*
X1232214D03*
X1230246D03*
X1234182Y121558D03*
X1232214D03*
X1230246D03*
X1300297Y277477D03*
X1302265D03*
X1300297Y269603D03*
X1302265D03*
X1304233Y277477D03*
Y269603D03*
X1384183Y113684D03*
X1382215D03*
X1380247D03*
X1384183Y121558D03*
X1382215D03*
X1380247D03*
X1432414Y448557D03*
X1430446D03*
X1432414Y456431D03*
X1430446D03*
X1434382Y448557D03*
Y456431D03*
X1450298Y277477D03*
X1452266D03*
X1454234D03*
X1450298Y269603D03*
X1452266D03*
X1454234D03*
X1486545Y113684D03*
X1484577D03*
X1482609D03*
X1486545Y121558D03*
X1484577D03*
X1482609D03*
X1552660Y277477D03*
X1554628D03*
X1556596D03*
X1552660Y269603D03*
X1554628D03*
X1556596D03*
X1588907Y113684D03*
X1586939D03*
X1584971D03*
X1588907Y121558D03*
X1586939D03*
X1584971D03*
X1655022Y277477D03*
X1656990D03*
X1658958D03*
X1655022Y269603D03*
X1656990D03*
X1658958D03*
X1691269Y113684D03*
X1689301D03*
X1687333D03*
X1691269Y121558D03*
X1689301D03*
X1687333D03*
X1757384Y277477D03*
Y269603D03*
X1759352Y277477D03*
X1761320D03*
X1759352Y269603D03*
X1761320D03*
G54D206*
X887193Y564037D03*
X889161D03*
X891130D03*
X893098D03*
X895067D03*
Y594549D03*
X893098D03*
X891130D03*
X889161D03*
X887193D03*
X910815Y564037D03*
X908846D03*
X906878D03*
X904909D03*
X899004D03*
X897035D03*
X902941D03*
X900972D03*
X912783D03*
Y594549D03*
X910815D03*
X900972D03*
X899004D03*
X897035D03*
X908846D03*
X906878D03*
X904909D03*
X902941D03*
X1009555Y316659D03*
Y347171D03*
X1011523Y316659D03*
X1013492D03*
X1015460D03*
X1017429D03*
X1019397D03*
X1021366D03*
X1023334D03*
X1025303D03*
X1015460Y347171D03*
X1013492D03*
X1025303D03*
X1023334D03*
X1021366D03*
X1019397D03*
X1017429D03*
X1011523D03*
X1031208Y316659D03*
X1027271D03*
X1029240D03*
X1033177D03*
X1035145D03*
Y347171D03*
X1033177D03*
X1031208D03*
X1029240D03*
X1027271D03*
G54D125*
X392821Y28608D03*
Y31168D03*
X409947Y28608D03*
Y31168D03*
X1268294Y333215D03*
Y330655D03*
X1285420Y333215D03*
Y330655D03*
X1306994Y28608D03*
Y31168D03*
X1324120Y28608D03*
Y31168D03*
X1582437Y340869D03*
Y338309D03*
X1599563Y340869D03*
Y338309D03*
G54D134*
X417211Y1126178D03*
X449339D03*
X482798D03*
X514926D03*
X1331385D03*
X1363513D03*
X1396972D03*
X1429100D03*
G54D242*
X1030635Y754546D03*
Y764546D03*
Y774546D03*
Y784546D03*
Y794546D03*
Y804546D03*
Y814546D03*
G54D107*
X109882Y1458622D03*
Y1463741D03*
Y1473977D03*
Y1479095D03*
Y1489331D03*
Y1494449D03*
Y1504685D03*
Y1509804D03*
Y1560985D03*
Y1566103D03*
Y1576339D03*
Y1581457D03*
Y1591693D03*
Y1596811D03*
Y1607048D03*
Y1612166D03*
X127205Y1458622D03*
Y1463741D03*
X118543Y1452717D03*
Y1462953D03*
X127205Y1473977D03*
Y1479095D03*
X118543Y1468071D03*
Y1478308D03*
X127205Y1489331D03*
Y1494449D03*
X118543Y1483426D03*
Y1493662D03*
Y1498780D03*
X127205Y1504685D03*
Y1509804D03*
X118543Y1509016D03*
Y1514134D03*
X127205Y1560985D03*
Y1566103D03*
Y1576339D03*
X118543Y1565315D03*
Y1570434D03*
X127205Y1581457D03*
Y1591693D03*
X118543Y1580670D03*
Y1585788D03*
Y1596024D03*
X127205Y1596811D03*
Y1607048D03*
Y1612166D03*
X118543Y1601142D03*
Y1611378D03*
X127205Y1622402D03*
X118543Y1616496D03*
X144528Y1458622D03*
Y1463741D03*
X135866Y1452717D03*
Y1462953D03*
X144528Y1473977D03*
Y1479095D03*
X135866Y1468071D03*
Y1478308D03*
X144528Y1489331D03*
Y1494449D03*
X135866Y1483426D03*
Y1493662D03*
Y1498780D03*
X144528Y1504685D03*
Y1509804D03*
X135866Y1509016D03*
Y1514134D03*
X144528Y1560985D03*
Y1566103D03*
Y1576339D03*
X135866Y1565315D03*
Y1570434D03*
X144528Y1581457D03*
Y1591693D03*
X135866Y1580670D03*
Y1585788D03*
Y1596024D03*
X144528Y1596811D03*
Y1607048D03*
Y1612166D03*
X135866Y1601142D03*
Y1611378D03*
X144528Y1622402D03*
X135866Y1616496D03*
X161850Y1458622D03*
Y1463741D03*
X153189Y1452717D03*
Y1462953D03*
X161850Y1473977D03*
Y1479095D03*
X153189Y1468071D03*
Y1478308D03*
X161850Y1489331D03*
Y1494449D03*
X153189Y1483426D03*
Y1493662D03*
Y1498780D03*
X161850Y1504685D03*
Y1509804D03*
X153189Y1509016D03*
Y1514134D03*
X161850Y1560985D03*
Y1566103D03*
Y1576339D03*
X153189Y1565315D03*
Y1570434D03*
X161850Y1581457D03*
Y1591693D03*
X153189Y1580670D03*
Y1585788D03*
Y1596024D03*
X161850Y1596811D03*
Y1607048D03*
Y1612166D03*
X153189Y1601142D03*
Y1611378D03*
X161850Y1622402D03*
X153189Y1616496D03*
X179173Y1458622D03*
Y1463741D03*
X170512Y1452717D03*
Y1462953D03*
X179173Y1473977D03*
Y1479095D03*
X170512Y1468071D03*
Y1478308D03*
X179173Y1489331D03*
Y1494449D03*
X170512Y1483426D03*
Y1493662D03*
Y1498780D03*
X179173Y1504685D03*
Y1509804D03*
X170512Y1509016D03*
Y1514134D03*
X179173Y1560985D03*
Y1566103D03*
Y1576339D03*
X170512Y1565315D03*
Y1570434D03*
X179173Y1581457D03*
Y1591693D03*
X170512Y1580670D03*
Y1585788D03*
Y1596024D03*
X179173Y1596811D03*
Y1607048D03*
Y1612166D03*
X170512Y1601142D03*
Y1611378D03*
X179173Y1622402D03*
X170512Y1616496D03*
X187835Y1452717D03*
Y1462953D03*
Y1468071D03*
Y1478308D03*
Y1483426D03*
Y1493662D03*
Y1498780D03*
Y1509016D03*
Y1514134D03*
Y1565315D03*
Y1570434D03*
Y1580670D03*
Y1585788D03*
Y1596024D03*
Y1601142D03*
Y1611378D03*
Y1616496D03*
X291771Y1452717D03*
X283110Y1458622D03*
X291771Y1462953D03*
X283110Y1463741D03*
X291771Y1468071D03*
X283110Y1473977D03*
X291771Y1478308D03*
X283110Y1479095D03*
X291771Y1483426D03*
X283110Y1489331D03*
X291771Y1493662D03*
X283110Y1494449D03*
X291771Y1498780D03*
X283110Y1504685D03*
X291771Y1509016D03*
X283110Y1509804D03*
X291771Y1514134D03*
X283110Y1560985D03*
X291771Y1565315D03*
X283110Y1566103D03*
X291771Y1570434D03*
X283110Y1576339D03*
X291771Y1580670D03*
X283110Y1581457D03*
X291771Y1585788D03*
X283110Y1591693D03*
X291771Y1596024D03*
X283110Y1596811D03*
X291771Y1601142D03*
X283110Y1607048D03*
X291771Y1611378D03*
X283110Y1612166D03*
X291771Y1616496D03*
X309094Y1452717D03*
X300433Y1458622D03*
X309094Y1462953D03*
X300433Y1463741D03*
X309094Y1468071D03*
X300433Y1473977D03*
X309094Y1478308D03*
X300433Y1479095D03*
X309094Y1483426D03*
X300433Y1489331D03*
X309094Y1493662D03*
X300433Y1494449D03*
X309094Y1498780D03*
X300433Y1504685D03*
X309094Y1509016D03*
X300433Y1509804D03*
X309094Y1514134D03*
X300433Y1560985D03*
X309094Y1565315D03*
X300433Y1566103D03*
X309094Y1570434D03*
X300433Y1576339D03*
X309094Y1580670D03*
X300433Y1581457D03*
X309094Y1585788D03*
X300433Y1591693D03*
X309094Y1596024D03*
X300433Y1596811D03*
X309094Y1601142D03*
X300433Y1607048D03*
X309094Y1611378D03*
X300433Y1612166D03*
X309094Y1616496D03*
X300433Y1622402D03*
X326417Y1452717D03*
X317756Y1458622D03*
X326417Y1462953D03*
X317756Y1463741D03*
X326417Y1468071D03*
X317756Y1473977D03*
X326417Y1478308D03*
X317756Y1479095D03*
X326417Y1483426D03*
X317756Y1489331D03*
X326417Y1493662D03*
X317756Y1494449D03*
X326417Y1498780D03*
X317756Y1504685D03*
X326417Y1509016D03*
X317756Y1509804D03*
X326417Y1514134D03*
X317756Y1560985D03*
X326417Y1565315D03*
X317756Y1566103D03*
X326417Y1570434D03*
X317756Y1576339D03*
X326417Y1580670D03*
X317756Y1581457D03*
X326417Y1585788D03*
X317756Y1591693D03*
X326417Y1596024D03*
X317756Y1596811D03*
X326417Y1601142D03*
X317756Y1607048D03*
X326417Y1611378D03*
X317756Y1612166D03*
X326417Y1616496D03*
X317756Y1622402D03*
X343740Y1452717D03*
X335078Y1458622D03*
X343740Y1462953D03*
X335078Y1463741D03*
X343740Y1468071D03*
X335078Y1473977D03*
X343740Y1478308D03*
X335078Y1479095D03*
X343740Y1483426D03*
X335078Y1489331D03*
X343740Y1493662D03*
X335078Y1494449D03*
X343740Y1498780D03*
X335078Y1504685D03*
X343740Y1509016D03*
X335078Y1509804D03*
X343740Y1514134D03*
X335078Y1560985D03*
X343740Y1565315D03*
X335078Y1566103D03*
X343740Y1570434D03*
X335078Y1576339D03*
X343740Y1580670D03*
X335078Y1581457D03*
X343740Y1585788D03*
X335078Y1591693D03*
X343740Y1596024D03*
X335078Y1596811D03*
X343740Y1601142D03*
X335078Y1607048D03*
X343740Y1611378D03*
X335078Y1612166D03*
X343740Y1616496D03*
X335078Y1622402D03*
X361063Y1452717D03*
X352401Y1458622D03*
Y1463741D03*
X361063Y1462953D03*
Y1468071D03*
X352401Y1473977D03*
Y1479095D03*
X361063Y1478308D03*
Y1483426D03*
X352401Y1489331D03*
Y1494449D03*
X361063Y1493662D03*
Y1498780D03*
X352401Y1504685D03*
Y1509804D03*
X361063Y1509016D03*
Y1514134D03*
X352401Y1560985D03*
Y1566103D03*
X361063Y1565315D03*
Y1570434D03*
X352401Y1576339D03*
Y1581457D03*
X361063Y1580670D03*
Y1585788D03*
X352401Y1591693D03*
X361063Y1596024D03*
X352401Y1596811D03*
X361063Y1601142D03*
X352401Y1607048D03*
Y1612166D03*
X361063Y1611378D03*
Y1616496D03*
X352401Y1622402D03*
X456339Y1458622D03*
Y1463741D03*
Y1473977D03*
Y1479095D03*
Y1489331D03*
Y1494449D03*
Y1504685D03*
Y1509804D03*
Y1560985D03*
Y1566103D03*
Y1576339D03*
Y1581457D03*
Y1591693D03*
Y1596811D03*
Y1607048D03*
Y1612166D03*
X473662Y1458622D03*
Y1463741D03*
X465000Y1452717D03*
Y1462953D03*
X473662Y1473977D03*
Y1479095D03*
X465000Y1468071D03*
Y1478308D03*
X473662Y1489331D03*
Y1494449D03*
X465000Y1483426D03*
Y1493662D03*
Y1498780D03*
X473662Y1504685D03*
Y1509804D03*
X465000Y1509016D03*
Y1514134D03*
X473662Y1560985D03*
Y1566103D03*
Y1576339D03*
X465000Y1565315D03*
Y1570434D03*
X473662Y1581457D03*
Y1591693D03*
X465000Y1580670D03*
Y1585788D03*
Y1596024D03*
X473662Y1596811D03*
Y1607048D03*
Y1612166D03*
X465000Y1601142D03*
Y1611378D03*
X473662Y1622402D03*
X465000Y1616496D03*
X490985Y1458622D03*
Y1463741D03*
X482323Y1452717D03*
Y1462953D03*
X490985Y1473977D03*
Y1479095D03*
X482323Y1468071D03*
Y1478308D03*
X490985Y1489331D03*
Y1494449D03*
X482323Y1483426D03*
Y1493662D03*
Y1498780D03*
X490985Y1504685D03*
Y1509804D03*
X482323Y1509016D03*
Y1514134D03*
X490985Y1560985D03*
Y1566103D03*
Y1576339D03*
X482323Y1565315D03*
Y1570434D03*
X490985Y1581457D03*
Y1591693D03*
X482323Y1580670D03*
Y1585788D03*
Y1596024D03*
X490985Y1596811D03*
Y1607048D03*
Y1612166D03*
X482323Y1601142D03*
Y1611378D03*
X490985Y1622402D03*
X482323Y1616496D03*
X499646Y1452717D03*
Y1462953D03*
Y1468071D03*
Y1478308D03*
Y1483426D03*
Y1493662D03*
Y1498780D03*
Y1509016D03*
Y1514134D03*
Y1565315D03*
Y1570434D03*
Y1580670D03*
Y1585788D03*
Y1596024D03*
Y1601142D03*
Y1611378D03*
Y1616496D03*
X516969Y1452717D03*
X508307Y1458622D03*
X516969Y1462953D03*
X508307Y1463741D03*
X516969Y1468071D03*
X508307Y1473977D03*
X516969Y1478308D03*
X508307Y1479095D03*
X516969Y1483426D03*
X508307Y1489331D03*
X516969Y1493662D03*
X508307Y1494449D03*
X516969Y1498780D03*
X508307Y1504685D03*
X516969Y1509016D03*
X508307Y1509804D03*
X516969Y1514134D03*
X508307Y1560985D03*
X516969Y1565315D03*
X508307Y1566103D03*
X516969Y1570434D03*
X508307Y1576339D03*
X516969Y1580670D03*
X508307Y1581457D03*
X516969Y1585788D03*
X508307Y1591693D03*
X516969Y1596024D03*
X508307Y1596811D03*
X516969Y1601142D03*
X508307Y1607048D03*
X516969Y1611378D03*
X508307Y1612166D03*
X516969Y1616496D03*
X508307Y1622402D03*
X534292Y1452717D03*
X525630Y1458622D03*
Y1463741D03*
X534292Y1462953D03*
Y1468071D03*
X525630Y1473977D03*
Y1479095D03*
X534292Y1478308D03*
Y1483426D03*
X525630Y1489331D03*
Y1494449D03*
X534292Y1493662D03*
Y1498780D03*
X525630Y1504685D03*
Y1509804D03*
X534292Y1509016D03*
Y1514134D03*
X525630Y1560985D03*
Y1566103D03*
X534292Y1565315D03*
Y1570434D03*
X525630Y1576339D03*
Y1581457D03*
X534292Y1580670D03*
Y1585788D03*
X525630Y1591693D03*
X534292Y1596024D03*
X525630Y1596811D03*
X534292Y1601142D03*
X525630Y1607048D03*
Y1612166D03*
X534292Y1611378D03*
Y1616496D03*
X525630Y1622402D03*
X629567Y1458622D03*
Y1463741D03*
Y1473977D03*
Y1479095D03*
Y1489331D03*
Y1494449D03*
Y1504685D03*
Y1509804D03*
Y1560985D03*
Y1566103D03*
Y1576339D03*
Y1581457D03*
Y1591693D03*
Y1596811D03*
Y1607048D03*
Y1612166D03*
X646890Y1458622D03*
Y1463741D03*
X638228Y1452717D03*
Y1462953D03*
X646890Y1473977D03*
Y1479095D03*
X638228Y1468071D03*
Y1478308D03*
X646890Y1489331D03*
Y1494449D03*
X638228Y1483426D03*
Y1493662D03*
Y1498780D03*
X646890Y1504685D03*
Y1509804D03*
X638228Y1509016D03*
Y1514134D03*
X646890Y1560985D03*
Y1566103D03*
Y1576339D03*
X638228Y1565315D03*
Y1570434D03*
X646890Y1581457D03*
Y1591693D03*
X638228Y1580670D03*
Y1585788D03*
Y1596024D03*
X646890Y1596811D03*
Y1607048D03*
Y1612166D03*
X638228Y1601142D03*
Y1611378D03*
X646890Y1622402D03*
X638228Y1616496D03*
X664213Y1458622D03*
Y1463741D03*
X655551Y1452717D03*
Y1462953D03*
X664213Y1473977D03*
Y1479095D03*
X655551Y1468071D03*
Y1478308D03*
X664213Y1489331D03*
Y1494449D03*
X655551Y1483426D03*
Y1493662D03*
Y1498780D03*
X664213Y1504685D03*
Y1509804D03*
X655551Y1509016D03*
Y1514134D03*
X664213Y1560985D03*
Y1566103D03*
Y1576339D03*
X655551Y1565315D03*
Y1570434D03*
X664213Y1581457D03*
Y1591693D03*
X655551Y1580670D03*
Y1585788D03*
Y1596024D03*
X664213Y1596811D03*
Y1607048D03*
Y1612166D03*
X655551Y1601142D03*
Y1611378D03*
X664213Y1622402D03*
X655551Y1616496D03*
X681535Y1458622D03*
Y1463741D03*
X672874Y1452717D03*
Y1462953D03*
X681535Y1473977D03*
Y1479095D03*
X672874Y1468071D03*
Y1478308D03*
X681535Y1489331D03*
Y1494449D03*
X672874Y1483426D03*
Y1493662D03*
Y1498780D03*
X681535Y1504685D03*
Y1509804D03*
X672874Y1509016D03*
Y1514134D03*
X681535Y1560985D03*
Y1566103D03*
Y1576339D03*
X672874Y1565315D03*
Y1570434D03*
X681535Y1581457D03*
Y1591693D03*
X672874Y1580670D03*
Y1585788D03*
Y1596024D03*
X681535Y1596811D03*
Y1607048D03*
Y1612166D03*
X672874Y1601142D03*
Y1611378D03*
X681535Y1622402D03*
X672874Y1616496D03*
X698858Y1458622D03*
Y1463741D03*
X690197Y1452717D03*
Y1462953D03*
X698858Y1473977D03*
Y1479095D03*
X690197Y1468071D03*
Y1478308D03*
X698858Y1489331D03*
Y1494449D03*
X690197Y1483426D03*
Y1493662D03*
Y1498780D03*
X698858Y1504685D03*
Y1509804D03*
X690197Y1509016D03*
Y1514134D03*
X698858Y1560985D03*
Y1566103D03*
Y1576339D03*
X690197Y1565315D03*
Y1570434D03*
X698858Y1581457D03*
Y1591693D03*
X690197Y1580670D03*
Y1585788D03*
Y1596024D03*
X698858Y1596811D03*
Y1607048D03*
Y1612166D03*
X690197Y1601142D03*
Y1611378D03*
X698858Y1622402D03*
X690197Y1616496D03*
X707520Y1452717D03*
Y1462953D03*
Y1468071D03*
Y1478308D03*
Y1483426D03*
Y1493662D03*
Y1498780D03*
Y1509016D03*
Y1514134D03*
Y1565315D03*
Y1570434D03*
Y1580670D03*
Y1585788D03*
Y1596024D03*
Y1601142D03*
Y1611378D03*
Y1616496D03*
X1140511Y1452717D03*
X1131850Y1458622D03*
X1140511Y1462953D03*
X1131850Y1463741D03*
X1140511Y1468071D03*
X1131850Y1473977D03*
X1140511Y1478308D03*
X1131850Y1479095D03*
X1140511Y1483426D03*
X1131850Y1489331D03*
X1140511Y1493662D03*
X1131850Y1494449D03*
X1140511Y1498780D03*
X1131850Y1504685D03*
X1140511Y1509016D03*
X1131850Y1509804D03*
X1140511Y1514134D03*
X1131850Y1560985D03*
X1140511Y1565315D03*
X1131850Y1566103D03*
X1140511Y1570434D03*
X1131850Y1576339D03*
X1140511Y1580670D03*
X1131850Y1581457D03*
X1140511Y1585788D03*
X1131850Y1591693D03*
X1140511Y1596024D03*
X1131850Y1596811D03*
X1140511Y1601142D03*
X1131850Y1607048D03*
X1140511Y1611378D03*
X1131850Y1612166D03*
X1140511Y1616496D03*
X1149173Y1458622D03*
Y1463741D03*
Y1473977D03*
Y1479095D03*
Y1489331D03*
Y1494449D03*
Y1504685D03*
Y1509804D03*
Y1560985D03*
Y1566103D03*
Y1576339D03*
Y1581457D03*
Y1591693D03*
Y1596811D03*
Y1607048D03*
Y1612166D03*
Y1622402D03*
X1166496Y1458622D03*
Y1463741D03*
X1157834Y1452717D03*
Y1462953D03*
X1166496Y1473977D03*
Y1479095D03*
X1157834Y1468071D03*
Y1478308D03*
X1166496Y1489331D03*
Y1494449D03*
X1157834Y1483426D03*
Y1493662D03*
Y1498780D03*
X1166496Y1504685D03*
Y1509804D03*
X1157834Y1509016D03*
Y1514134D03*
X1166496Y1560985D03*
Y1566103D03*
Y1576339D03*
X1157834Y1565315D03*
Y1570434D03*
X1166496Y1581457D03*
Y1591693D03*
X1157834Y1580670D03*
Y1585788D03*
Y1596024D03*
X1166496Y1596811D03*
Y1607048D03*
Y1612166D03*
X1157834Y1601142D03*
Y1611378D03*
X1166496Y1622402D03*
X1157834Y1616496D03*
X1183818Y1458622D03*
Y1463741D03*
X1175157Y1452717D03*
Y1462953D03*
X1183818Y1473977D03*
Y1479095D03*
X1175157Y1468071D03*
Y1478308D03*
X1183818Y1489331D03*
Y1494449D03*
X1175157Y1483426D03*
Y1493662D03*
Y1498780D03*
X1183818Y1504685D03*
Y1509804D03*
X1175157Y1509016D03*
Y1514134D03*
X1183818Y1560985D03*
Y1566103D03*
Y1576339D03*
X1175157Y1565315D03*
Y1570434D03*
X1183818Y1581457D03*
Y1591693D03*
X1175157Y1580670D03*
Y1585788D03*
Y1596024D03*
X1183818Y1596811D03*
Y1607048D03*
Y1612166D03*
X1175157Y1601142D03*
Y1611378D03*
X1183818Y1622402D03*
X1175157Y1616496D03*
X1201141Y1458622D03*
Y1463741D03*
X1192480Y1452717D03*
Y1462953D03*
X1201141Y1473977D03*
Y1479095D03*
X1192480Y1468071D03*
Y1478308D03*
X1201141Y1489331D03*
Y1494449D03*
X1192480Y1483426D03*
Y1493662D03*
Y1498780D03*
X1201141Y1504685D03*
Y1509804D03*
X1192480Y1509016D03*
Y1514134D03*
X1201141Y1560985D03*
Y1566103D03*
Y1576339D03*
X1192480Y1565315D03*
Y1570434D03*
X1201141Y1581457D03*
Y1591693D03*
X1192480Y1580670D03*
Y1585788D03*
Y1596024D03*
X1201141Y1596811D03*
Y1607048D03*
Y1612166D03*
X1192480Y1601142D03*
Y1611378D03*
X1201141Y1622402D03*
X1192480Y1616496D03*
X1209803Y1452717D03*
Y1462953D03*
Y1468071D03*
Y1478308D03*
Y1483426D03*
Y1493662D03*
Y1498780D03*
Y1509016D03*
Y1514134D03*
Y1565315D03*
Y1570434D03*
Y1580670D03*
Y1585788D03*
Y1596024D03*
Y1601142D03*
Y1611378D03*
Y1616496D03*
X1313740Y1452717D03*
X1305079Y1458622D03*
X1313740Y1462953D03*
X1305079Y1463741D03*
X1313740Y1468071D03*
X1305079Y1473977D03*
X1313740Y1478308D03*
X1305079Y1479095D03*
X1313740Y1483426D03*
X1305079Y1489331D03*
X1313740Y1493662D03*
X1305079Y1494449D03*
X1313740Y1498780D03*
X1305079Y1504685D03*
X1313740Y1509016D03*
X1305079Y1509804D03*
X1313740Y1514134D03*
X1305079Y1560985D03*
X1313740Y1565315D03*
X1305079Y1566103D03*
X1313740Y1570434D03*
X1305079Y1576339D03*
X1313740Y1580670D03*
X1305079Y1581457D03*
X1313740Y1585788D03*
X1305079Y1591693D03*
X1313740Y1596024D03*
X1305079Y1596811D03*
X1313740Y1601142D03*
X1305079Y1607048D03*
X1313740Y1611378D03*
X1305079Y1612166D03*
X1313740Y1616496D03*
X1331063Y1452717D03*
X1322402Y1458622D03*
X1331063Y1462953D03*
X1322402Y1463741D03*
X1331063Y1468071D03*
X1322402Y1473977D03*
X1331063Y1478308D03*
X1322402Y1479095D03*
X1331063Y1483426D03*
X1322402Y1489331D03*
X1331063Y1493662D03*
X1322402Y1494449D03*
X1331063Y1498780D03*
X1322402Y1504685D03*
X1331063Y1509016D03*
X1322402Y1509804D03*
X1331063Y1514134D03*
X1322402Y1560985D03*
X1331063Y1565315D03*
X1322402Y1566103D03*
X1331063Y1570434D03*
X1322402Y1576339D03*
X1331063Y1580670D03*
X1322402Y1581457D03*
X1331063Y1585788D03*
X1322402Y1591693D03*
X1331063Y1596024D03*
X1322402Y1596811D03*
X1331063Y1601142D03*
X1322402Y1607048D03*
X1331063Y1611378D03*
X1322402Y1612166D03*
X1331063Y1616496D03*
X1322402Y1622402D03*
X1348386Y1452717D03*
X1339725Y1458622D03*
X1348386Y1462953D03*
X1339725Y1463741D03*
X1348386Y1468071D03*
X1339725Y1473977D03*
X1348386Y1478308D03*
X1339725Y1479095D03*
X1348386Y1483426D03*
X1339725Y1489331D03*
X1348386Y1493662D03*
X1339725Y1494449D03*
X1348386Y1498780D03*
X1339725Y1504685D03*
X1348386Y1509016D03*
X1339725Y1509804D03*
X1348386Y1514134D03*
X1339725Y1560985D03*
X1348386Y1565315D03*
X1339725Y1566103D03*
X1348386Y1570434D03*
X1339725Y1576339D03*
X1348386Y1580670D03*
X1339725Y1581457D03*
X1348386Y1585788D03*
X1339725Y1591693D03*
X1348386Y1596024D03*
X1339725Y1596811D03*
X1348386Y1601142D03*
X1339725Y1607048D03*
X1348386Y1611378D03*
X1339725Y1612166D03*
X1348386Y1616496D03*
X1339725Y1622402D03*
X1365709Y1452717D03*
X1357047Y1458622D03*
X1365709Y1462953D03*
X1357047Y1463741D03*
X1365709Y1468071D03*
X1357047Y1473977D03*
X1365709Y1478308D03*
X1357047Y1479095D03*
X1365709Y1483426D03*
X1357047Y1489331D03*
X1365709Y1493662D03*
X1357047Y1494449D03*
X1365709Y1498780D03*
X1357047Y1504685D03*
X1365709Y1509016D03*
X1357047Y1509804D03*
X1365709Y1514134D03*
X1357047Y1560985D03*
X1365709Y1565315D03*
X1357047Y1566103D03*
X1365709Y1570434D03*
X1357047Y1576339D03*
X1365709Y1580670D03*
X1357047Y1581457D03*
X1365709Y1585788D03*
X1357047Y1591693D03*
X1365709Y1596024D03*
X1357047Y1596811D03*
X1365709Y1601142D03*
X1357047Y1607048D03*
X1365709Y1611378D03*
X1357047Y1612166D03*
X1365709Y1616496D03*
X1357047Y1622402D03*
X1383032Y1452717D03*
X1374370Y1458622D03*
Y1463741D03*
X1383032Y1462953D03*
Y1468071D03*
X1374370Y1473977D03*
Y1479095D03*
X1383032Y1478308D03*
Y1483426D03*
X1374370Y1489331D03*
Y1494449D03*
X1383032Y1493662D03*
Y1498780D03*
X1374370Y1504685D03*
Y1509804D03*
X1383032Y1509016D03*
Y1514134D03*
X1374370Y1560985D03*
Y1566103D03*
X1383032Y1565315D03*
Y1570434D03*
X1374370Y1576339D03*
Y1581457D03*
X1383032Y1580670D03*
Y1585788D03*
X1374370Y1591693D03*
X1383032Y1596024D03*
X1374370Y1596811D03*
X1383032Y1601142D03*
X1374370Y1607048D03*
Y1612166D03*
X1383032Y1611378D03*
Y1616496D03*
X1374370Y1622402D03*
X1478307Y1458622D03*
Y1463741D03*
Y1473977D03*
Y1479095D03*
Y1489331D03*
Y1494449D03*
Y1504685D03*
Y1509804D03*
Y1560985D03*
Y1566103D03*
Y1576339D03*
Y1581457D03*
Y1591693D03*
Y1596811D03*
Y1607048D03*
Y1612166D03*
X1495630Y1458622D03*
Y1463741D03*
X1486968Y1452717D03*
Y1462953D03*
X1495630Y1473977D03*
Y1479095D03*
X1486968Y1468071D03*
Y1478308D03*
X1495630Y1489331D03*
Y1494449D03*
X1486968Y1483426D03*
Y1493662D03*
Y1498780D03*
X1495630Y1504685D03*
Y1509804D03*
X1486968Y1509016D03*
Y1514134D03*
X1495630Y1560985D03*
Y1566103D03*
Y1576339D03*
X1486968Y1565315D03*
Y1570434D03*
X1495630Y1581457D03*
Y1591693D03*
X1486968Y1580670D03*
Y1585788D03*
Y1596024D03*
X1495630Y1596811D03*
Y1607048D03*
Y1612166D03*
X1486968Y1601142D03*
Y1611378D03*
X1495630Y1622402D03*
X1486968Y1616496D03*
X1512953Y1458622D03*
Y1463741D03*
X1504291Y1452717D03*
Y1462953D03*
X1512953Y1473977D03*
Y1479095D03*
X1504291Y1468071D03*
Y1478308D03*
X1512953Y1489331D03*
Y1494449D03*
X1504291Y1483426D03*
Y1493662D03*
Y1498780D03*
X1512953Y1504685D03*
Y1509804D03*
X1504291Y1509016D03*
Y1514134D03*
X1512953Y1560985D03*
Y1566103D03*
Y1576339D03*
X1504291Y1565315D03*
Y1570434D03*
X1512953Y1581457D03*
Y1591693D03*
X1504291Y1580670D03*
Y1585788D03*
Y1596024D03*
X1512953Y1596811D03*
Y1607048D03*
Y1612166D03*
X1504291Y1601142D03*
Y1611378D03*
X1512953Y1622402D03*
X1504291Y1616496D03*
X1530275Y1458622D03*
Y1463741D03*
X1521614Y1452717D03*
Y1462953D03*
X1530275Y1473977D03*
Y1479095D03*
X1521614Y1468071D03*
Y1478308D03*
X1530275Y1489331D03*
Y1494449D03*
X1521614Y1483426D03*
Y1493662D03*
Y1498780D03*
X1530275Y1504685D03*
Y1509804D03*
X1521614Y1509016D03*
Y1514134D03*
X1530275Y1560985D03*
Y1566103D03*
Y1576339D03*
X1521614Y1565315D03*
Y1570434D03*
X1530275Y1581457D03*
Y1591693D03*
X1521614Y1580670D03*
Y1585788D03*
Y1596024D03*
X1530275Y1596811D03*
Y1607048D03*
Y1612166D03*
X1521614Y1601142D03*
Y1611378D03*
X1530275Y1622402D03*
X1521614Y1616496D03*
X1538937Y1452717D03*
Y1462953D03*
Y1468071D03*
Y1478308D03*
Y1483426D03*
Y1493662D03*
Y1498780D03*
Y1509016D03*
Y1514134D03*
Y1565315D03*
Y1570434D03*
Y1580670D03*
Y1585788D03*
Y1596024D03*
Y1601142D03*
Y1611378D03*
Y1616496D03*
X1556260Y1452717D03*
X1547598Y1458622D03*
Y1463741D03*
X1556260Y1462953D03*
Y1468071D03*
X1547598Y1473977D03*
Y1479095D03*
X1556260Y1478308D03*
Y1483426D03*
X1547598Y1489331D03*
Y1494449D03*
X1556260Y1493662D03*
Y1498780D03*
X1547598Y1504685D03*
Y1509804D03*
X1556260Y1509016D03*
Y1514134D03*
X1547598Y1560985D03*
Y1566103D03*
X1556260Y1565315D03*
Y1570434D03*
X1547598Y1576339D03*
Y1581457D03*
X1556260Y1580670D03*
Y1585788D03*
X1547598Y1591693D03*
X1556260Y1596024D03*
X1547598Y1596811D03*
X1556260Y1601142D03*
X1547598Y1607048D03*
Y1612166D03*
X1556260Y1611378D03*
Y1616496D03*
X1547598Y1622402D03*
X1660196Y1452717D03*
X1651535Y1458622D03*
X1660196Y1462953D03*
X1651535Y1463741D03*
X1660196Y1468071D03*
X1651535Y1473977D03*
X1660196Y1478308D03*
X1651535Y1479095D03*
X1660196Y1483426D03*
X1651535Y1489331D03*
X1660196Y1493662D03*
X1651535Y1494449D03*
X1660196Y1498780D03*
X1651535Y1504685D03*
X1660196Y1509016D03*
X1651535Y1509804D03*
X1660196Y1514134D03*
X1651535Y1560985D03*
X1660196Y1565315D03*
X1651535Y1566103D03*
X1660196Y1570434D03*
X1651535Y1576339D03*
X1660196Y1580670D03*
X1651535Y1581457D03*
X1660196Y1585788D03*
X1651535Y1591693D03*
X1660196Y1596024D03*
X1651535Y1596811D03*
X1660196Y1601142D03*
X1651535Y1607048D03*
X1660196Y1611378D03*
X1651535Y1612166D03*
X1660196Y1616496D03*
X1668858Y1458622D03*
Y1463741D03*
Y1473977D03*
Y1479095D03*
Y1489331D03*
Y1494449D03*
Y1504685D03*
Y1509804D03*
Y1560985D03*
Y1566103D03*
Y1576339D03*
Y1581457D03*
Y1591693D03*
Y1596811D03*
Y1607048D03*
Y1612166D03*
Y1622402D03*
X1686181Y1458622D03*
Y1463741D03*
X1677519Y1452717D03*
Y1462953D03*
X1686181Y1473977D03*
Y1479095D03*
X1677519Y1468071D03*
Y1478308D03*
X1686181Y1489331D03*
Y1494449D03*
X1677519Y1483426D03*
Y1493662D03*
Y1498780D03*
X1686181Y1504685D03*
Y1509804D03*
X1677519Y1509016D03*
Y1514134D03*
X1686181Y1560985D03*
Y1566103D03*
Y1576339D03*
X1677519Y1565315D03*
Y1570434D03*
X1686181Y1581457D03*
Y1591693D03*
X1677519Y1580670D03*
Y1585788D03*
Y1596024D03*
X1686181Y1596811D03*
Y1607048D03*
Y1612166D03*
X1677519Y1601142D03*
Y1611378D03*
X1686181Y1622402D03*
X1677519Y1616496D03*
X1703503Y1458622D03*
Y1463741D03*
X1694842Y1452717D03*
Y1462953D03*
X1703503Y1473977D03*
Y1479095D03*
X1694842Y1468071D03*
Y1478308D03*
X1703503Y1489331D03*
Y1494449D03*
X1694842Y1483426D03*
Y1493662D03*
Y1498780D03*
X1703503Y1504685D03*
Y1509804D03*
X1694842Y1509016D03*
Y1514134D03*
X1703503Y1560985D03*
Y1566103D03*
Y1576339D03*
X1694842Y1565315D03*
Y1570434D03*
X1703503Y1581457D03*
Y1591693D03*
X1694842Y1580670D03*
Y1585788D03*
Y1596024D03*
X1703503Y1596811D03*
Y1607048D03*
Y1612166D03*
X1694842Y1601142D03*
Y1611378D03*
X1703503Y1622402D03*
X1694842Y1616496D03*
X1720826Y1458622D03*
Y1463741D03*
X1712165Y1452717D03*
Y1462953D03*
X1720826Y1473977D03*
Y1479095D03*
X1712165Y1468071D03*
Y1478308D03*
X1720826Y1489331D03*
Y1494449D03*
X1712165Y1483426D03*
Y1493662D03*
Y1498780D03*
X1720826Y1504685D03*
Y1509804D03*
X1712165Y1509016D03*
Y1514134D03*
X1720826Y1560985D03*
Y1566103D03*
Y1576339D03*
X1712165Y1565315D03*
Y1570434D03*
X1720826Y1581457D03*
Y1591693D03*
X1712165Y1580670D03*
Y1585788D03*
Y1596024D03*
X1720826Y1596811D03*
Y1607048D03*
Y1612166D03*
X1712165Y1601142D03*
Y1611378D03*
X1720826Y1622402D03*
X1712165Y1616496D03*
X1729488Y1452717D03*
Y1462953D03*
Y1468071D03*
Y1478308D03*
Y1483426D03*
Y1493662D03*
Y1498780D03*
Y1509016D03*
Y1514134D03*
Y1565315D03*
Y1570434D03*
Y1580670D03*
Y1585788D03*
Y1596024D03*
Y1601142D03*
Y1611378D03*
Y1616496D03*
G54D233*
X970071Y1365652D03*
Y1409152D03*
G54D60*
X42408Y511021D03*
X71691Y242569D03*
X61700Y511021D03*
X90983Y242569D03*
X174053D03*
X193345D03*
X276415D03*
X295707D03*
X378777D03*
X398069D03*
X411729Y414384D03*
X431021D03*
X499494Y511021D03*
X518786D03*
X528778Y242569D03*
X548070D03*
X631140D03*
X650432D03*
X733502D03*
X752794D03*
X835864D03*
X855156D03*
X905055Y430725D03*
X924347D03*
X956581Y511021D03*
X975873D03*
X985864Y242569D03*
X1005156D03*
X1088226D03*
X1107518D03*
X1190588D03*
X1209880D03*
X1292950D03*
X1312242D03*
X1325902Y414384D03*
X1345194D03*
X1413668Y511021D03*
X1432960D03*
X1442951Y242569D03*
X1462243D03*
X1545313D03*
X1564605D03*
X1647675D03*
X1666967D03*
X1750037D03*
X1769329D03*
X1782989Y414384D03*
X1802281D03*
G54D162*
X475495Y1017303D03*
X1389669D03*
G54D252*
X1795453Y812874D03*
Y834922D03*
G54D171*
X650958Y672360D03*
Y682006D03*
X658438Y672360D03*
Y682006D03*
X654698D03*
X767282Y1595014D03*
X763542D03*
X759802D03*
Y1604660D03*
X767282D03*
X806318Y1387865D03*
X813798D03*
Y1397511D03*
X806318D03*
X810058D03*
X924932Y687237D03*
Y696883D03*
X928672D03*
X932412Y687237D03*
Y696883D03*
X954023Y711157D03*
X961503D03*
X954023Y720803D03*
X961503D03*
X957763D03*
X1108045Y672360D03*
Y682006D03*
X1115525Y672360D03*
Y682006D03*
X1111785D03*
X1565132Y672360D03*
X1572612D03*
X1565132Y682006D03*
X1572612D03*
X1568872D03*
G54D207*
X888691Y684403D03*
X897291D03*
X918361Y720570D03*
X926961D03*
G54D33*
X15916Y1041679D03*
X28318D03*
X50051Y1041371D03*
X37649D03*
X438119Y1234726D03*
X450521D03*
X476828D03*
X489230D03*
X862606Y1050682D03*
X875008D03*
X896741Y1050374D03*
X884339D03*
X926583Y1050682D03*
X938985D03*
X960718Y1050374D03*
X948316D03*
X1352293Y1234726D03*
X1364695D03*
X1391002D03*
X1403404D03*
X1770563Y1051168D03*
X1782965D03*
X1804698Y1050860D03*
X1792296D03*
G54D180*
X733058Y1614451D03*
X739358Y1611892D03*
Y1617010D03*
G54D144*
X419839Y350114D03*
X421413D03*
X422988D03*
X424563D03*
X430862D03*
X437161D03*
X426138D03*
X429287D03*
X435587D03*
X427713D03*
X432437D03*
X434012D03*
X1322424Y353206D03*
X1323998D03*
X1333447D03*
X1328723D03*
X1331872D03*
X1325573D03*
X1327148D03*
X1330298D03*
X1335022D03*
X1339746D03*
X1338172D03*
X1336597D03*
G54D225*
X942586Y1477022D03*
Y1498282D03*
G54D243*
X1045145Y812262D03*
Y825844D03*
G54D216*
X939314Y712147D03*
G54D234*
X980085Y1480881D03*
Y1498597D03*
X1017867Y1480881D03*
Y1498597D03*
G54D153*
X414519Y1253318D03*
Y1261804D03*
X512830Y1253318D03*
Y1261804D03*
X980085Y1486681D03*
Y1492797D03*
X1017867Y1486681D03*
Y1492797D03*
X1328693Y1253318D03*
Y1261804D03*
X1427004Y1253318D03*
Y1261804D03*
G54D42*
X29212Y81575D03*
X72914Y61614D03*
X131574Y81575D03*
X175276Y61614D03*
X233936Y81575D03*
X277639Y61614D03*
X336299Y81575D03*
X380001Y61614D03*
X486279Y81595D03*
X530001Y61614D03*
X588641Y81594D03*
X632363Y61614D03*
X691004Y81595D03*
X734725Y61614D03*
X793366Y81595D03*
X837087Y61614D03*
X943366Y81595D03*
X987087Y61614D03*
X1045728Y81595D03*
X1089450Y61614D03*
X1148090Y81595D03*
X1191812Y61614D03*
X1250453Y81595D03*
X1294174Y61614D03*
X1400453Y81595D03*
X1444174Y61614D03*
X1502834Y81575D03*
X1546536Y61614D03*
X1605177Y81595D03*
X1648898Y61614D03*
X1707539Y81595D03*
X1751261Y61614D03*
G54D117*
X311947Y342319D03*
X303285D03*
Y344878D03*
X311947Y347437D03*
X303285D03*
X652595Y653161D03*
X643933D03*
X652595Y658279D03*
X643933D03*
Y655720D03*
X760371Y342319D03*
Y344878D03*
Y347437D03*
X769033Y342319D03*
Y347437D03*
X1101020Y653161D03*
Y658279D03*
Y655720D03*
X1109682Y653161D03*
Y658279D03*
X1217458Y342319D03*
Y344878D03*
Y347437D03*
X1226120Y342319D03*
Y347437D03*
X1558107Y653161D03*
Y658279D03*
Y655720D03*
X1566769Y653161D03*
Y658279D03*
X1674545Y342319D03*
Y344878D03*
Y347437D03*
X1683207Y342319D03*
Y347437D03*
G54D15*
X12786Y85412D03*
X10292Y99695D03*
X14292D03*
X15948Y138776D03*
X11999Y138848D03*
X19855Y138871D03*
X12709Y173286D03*
X18826Y235961D03*
X10852Y1541606D03*
X11781Y1532371D03*
X6560Y1550595D03*
X18434Y1551666D03*
X20709Y173286D03*
X36201Y236043D03*
X24091Y236030D03*
X27966Y236018D03*
X29127Y1201683D03*
X27222Y1441611D03*
X48643Y448403D03*
X41643Y470403D03*
X46192Y639295D03*
X42192D03*
X50192D03*
X36692D03*
X40700Y1089630D03*
X58224Y470543D03*
X66224D03*
X53643Y470403D03*
X67684Y602709D03*
X63988Y628151D03*
X54192Y639295D03*
X57553Y1205719D03*
X53056Y1209848D03*
X54339Y1490956D03*
X60013Y1553179D03*
X66291Y1631286D03*
X73381Y91513D03*
X69381D03*
X77711Y176057D03*
X73711D03*
X77938Y187314D03*
X76877Y219666D03*
X80766Y262594D03*
X75819Y287967D03*
X79819D03*
X83819D03*
X83684Y602709D03*
X79684D03*
X71684D03*
X75684D03*
X73968Y665576D03*
X75049Y831202D03*
Y838616D03*
X70941Y1589749D03*
X74291Y1631286D03*
X78291D03*
X82291D03*
X70291D03*
X89845Y278285D03*
X87684Y602709D03*
X91057Y1028286D03*
X86291Y1631286D03*
X107607Y130807D03*
X117607D03*
X106796Y150813D03*
X121661Y130812D03*
X121840Y145921D03*
X120926Y235918D03*
X126453Y236030D03*
X130328Y236018D03*
X127235Y455565D03*
X138563Y236043D03*
X146400Y455284D03*
X175743Y91513D03*
X171743D03*
X179743D03*
X180073Y176057D03*
X176073D03*
X180300Y187314D03*
X179239Y219666D03*
X178181Y287967D03*
X182181D03*
X183752Y91513D03*
X183128Y262594D03*
X192207Y278285D03*
X186181Y287967D03*
X210482Y91788D03*
X214389Y91883D03*
X206533Y91860D03*
X211969Y130807D03*
X209158Y150813D03*
X219969Y130807D03*
X224023Y130812D03*
X224202Y145921D03*
X223288Y235918D03*
X228815Y236030D03*
X217939Y614948D03*
X221809Y614960D03*
X221084Y1482964D03*
X229753Y1537199D03*
X240925Y236043D03*
X232690Y236018D03*
X243278Y623847D03*
X247278D03*
X236498Y1478624D03*
X237753Y1537199D03*
X251278Y623847D03*
X278105Y91513D03*
X274105D03*
X278435Y176057D03*
X282105Y91513D03*
X286114D03*
X282435Y176057D03*
X282662Y187314D03*
X281601Y219666D03*
X285490Y262594D03*
X294569Y278285D03*
X280543Y287967D03*
X284543D03*
X288543D03*
X280500Y858698D03*
Y868798D03*
X286300Y893898D03*
Y904198D03*
X282300Y929398D03*
X282400Y939498D03*
X308895Y91860D03*
X312331Y130807D03*
X311520Y150834D03*
X312263Y314799D03*
X304543Y331926D03*
X316751Y91883D03*
X312844Y91788D03*
X322331Y130807D03*
X326385Y130812D03*
X326564Y145921D03*
X325650Y235918D03*
X331177Y236030D03*
X343287Y236043D03*
X335052Y236018D03*
X342285Y565196D03*
X341748Y1140188D03*
X341455Y1185029D03*
X338322Y1193954D03*
X342152Y1206502D03*
X347591Y396992D03*
X357748Y1140188D03*
X353748D03*
X349748D03*
X345471Y1184959D03*
X350400Y1198478D03*
X354400D03*
X358400D03*
X346387Y1206464D03*
X350402Y1206502D03*
X354402D03*
X358402D03*
X376467Y91513D03*
X377237Y376739D03*
X366486Y382632D03*
X370486D03*
X368587Y406525D03*
X364326Y484942D03*
X361748Y1140188D03*
X366157Y1149996D03*
X366133Y1168276D03*
X366400Y1198478D03*
X362400D03*
X366402Y1206502D03*
X362402D03*
X386112Y33677D03*
X380467Y91513D03*
X388476D03*
X384467D03*
X384797Y176057D03*
X380797D03*
X385024Y187314D03*
X383963Y219666D03*
X387852Y262594D03*
X382905Y287967D03*
X386905D03*
X390905D03*
X379800Y775084D03*
X378472Y793253D03*
X391614Y936135D03*
X408680Y43002D03*
X396680D03*
X396931Y278285D03*
X398237Y376540D03*
X394553Y395886D03*
X401165Y448521D03*
X395390Y875754D03*
X399052Y884257D03*
X402966Y884358D03*
X403159Y1122881D03*
X409461Y1566493D03*
X405461D03*
X415677Y315745D03*
X423551D03*
X419277D03*
X424479Y365141D03*
X416318Y365133D03*
X421459Y628810D03*
X420400Y798598D03*
X412100D03*
X413461Y1566493D03*
X435025Y315745D03*
X431425D03*
X427151D03*
X435574Y442023D03*
X429673Y459085D03*
X433673D03*
X438157Y506093D03*
X431285Y1123880D03*
X435287Y1122881D03*
X444779Y636940D03*
X455619Y1255479D03*
X472332Y130807D03*
X464332D03*
X461521Y150813D03*
X461091Y1027750D03*
X463413Y1123880D03*
X468746Y1122881D03*
X460574Y1255480D03*
X476386Y130812D03*
X476565Y145921D03*
X481178Y236030D03*
X475651Y235918D03*
X485053Y236018D03*
X488485Y415401D03*
X481485Y437401D03*
X488745Y680401D03*
X488091Y995250D03*
X493288Y236043D03*
X493485Y437401D03*
X503729Y445403D03*
X496729Y467403D03*
X503278Y639295D03*
X499278D03*
X507278D03*
X493778D03*
X491373Y657681D03*
X493914Y680419D03*
X505464Y673137D03*
X492091Y995250D03*
X500874Y1122881D03*
X496872Y1123880D03*
X521310Y467543D03*
X513310D03*
X508729Y467403D03*
X521074Y628151D03*
X511278Y639295D03*
X517464Y673137D03*
X513464D03*
X509464D03*
X517412Y761891D03*
X514576Y789287D03*
X519763Y789214D03*
X538477Y91513D03*
X530468D03*
X534468D03*
X526468D03*
X534798Y176057D03*
X530798D03*
X535025Y187314D03*
X533964Y219666D03*
X537853Y262594D03*
X532906Y287967D03*
X536906D03*
X528770Y602709D03*
X532770D03*
X536770D03*
X524770D03*
X537964Y673137D03*
X533964D03*
X529964D03*
X525964D03*
X529000Y1123880D03*
X546932Y278285D03*
X540906Y287967D03*
X544770Y602709D03*
X540770D03*
X542400Y847798D03*
X548144Y1028286D03*
X569114Y91883D03*
X565207Y91788D03*
X561258Y91860D03*
X564694Y130807D03*
X563883Y150813D03*
X567958Y1535299D03*
X574694Y130807D03*
X578748Y130812D03*
X578927Y145921D03*
X578013Y235918D03*
X583540Y236030D03*
X587415Y236018D03*
X584321Y455565D03*
X574504Y753368D03*
X587858Y1523799D03*
X579758Y1523699D03*
X575809Y1538485D03*
X583809D03*
X595650Y236043D03*
X603486Y455284D03*
X592103Y945291D03*
Y952705D03*
X591858Y1529899D03*
X595809Y1538485D03*
X632830Y91513D03*
X636830D03*
X628830D03*
X637160Y176057D03*
X633160D03*
X637387Y187314D03*
X636326Y219666D03*
X635268Y287967D03*
X640839Y91513D03*
X640215Y262594D03*
X649294Y278285D03*
X639268Y287967D03*
X643268D03*
X663620Y91860D03*
X667569Y91788D03*
X669056Y130807D03*
X666245Y150813D03*
X658064Y656220D03*
X662064D03*
X671476Y91883D03*
X677056Y130807D03*
X681110Y130812D03*
X681289Y145921D03*
X680375Y235918D03*
X685902Y236030D03*
X698012Y236043D03*
X689777Y236018D03*
X700364Y623847D03*
X693163Y700132D03*
X704364Y623847D03*
X708364D03*
X731192Y91513D03*
X720260Y699606D03*
X732170Y1625074D03*
X743201Y91513D03*
X739192D03*
X735192D03*
X739522Y176057D03*
X735522D03*
X739749Y187314D03*
X738688Y219666D03*
X742577Y262594D03*
X737630Y287967D03*
X741630D03*
X745630D03*
X751140Y1586794D03*
X735392Y1602249D03*
X744924Y1614852D03*
X743331Y1633703D03*
X765982Y91860D03*
X751656Y278285D03*
X761629Y331926D03*
X755187Y1586808D03*
X759452Y1616826D03*
X773838Y91883D03*
X769931Y91788D03*
X769418Y130807D03*
X779418D03*
X783472Y130812D03*
X783651Y145921D03*
X768607Y150813D03*
X782737Y235918D03*
X769349Y314799D03*
X774844Y1622454D03*
X778358Y1633185D03*
X788264Y236030D03*
X792139Y236018D03*
X799371Y565196D03*
X798835Y1140188D03*
X798542Y1185029D03*
X795159Y1191675D03*
X795418Y1206402D03*
X796972Y1397662D03*
X800374Y236043D03*
X813821Y738355D03*
X816027Y870739D03*
X806835Y1140188D03*
X814835D03*
X810835D03*
X802558Y1184959D03*
X815487Y1198478D03*
X811487D03*
X807487D03*
X802333Y1197995D03*
X815489Y1206502D03*
X811489D03*
X807489D03*
X803604Y1206459D03*
X806148Y1380667D03*
X810148D03*
X805009Y1472569D03*
X821412Y479942D03*
X830484Y744210D03*
X826484D03*
X822831Y839725D03*
X818831D03*
X820027Y870739D03*
X819629Y895614D03*
X828909Y911527D03*
X830913Y929661D03*
X818835Y1140188D03*
X823244Y1149996D03*
X823220Y1168276D03*
X819487Y1198478D03*
X823487D03*
X823489Y1206502D03*
X819489D03*
X833554Y91513D03*
X837554D03*
X845563D03*
X841554D03*
X841884Y176057D03*
X837884D03*
X842111Y187314D03*
X841050Y219666D03*
X844939Y262594D03*
X839992Y287967D03*
X843992D03*
X847992D03*
X846098Y414721D03*
X834484Y744210D03*
X846484D03*
X838484D03*
X842484D03*
X833112Y829697D03*
X832726Y843538D03*
X836311Y877072D03*
X844946Y911527D03*
X840909D03*
X836909D03*
X832909D03*
X838829Y929661D03*
X834829D03*
X845395D03*
X836423Y962178D03*
X832423D03*
X854018Y278285D03*
X863086Y379984D03*
X849680Y692098D03*
X854484Y744210D03*
X850484D03*
X852628Y912573D03*
X860628D03*
X849544Y1454243D03*
X872293Y91788D03*
X876200Y91883D03*
X868344Y91860D03*
X878500Y200409D03*
X879740Y260193D03*
X868086Y379984D03*
X876736Y388764D03*
X867586Y390484D03*
X869342Y414526D03*
X875916Y806374D03*
X879916Y816524D03*
X876628Y912573D03*
X868628D03*
X872817Y1210686D03*
X889879Y412227D03*
X896491Y464862D03*
X896431Y539552D03*
X891933Y615652D03*
X884045Y750219D03*
X887916Y806374D03*
X883916D03*
X891916D03*
X883916Y816524D03*
X887916D03*
X884628Y912573D03*
X887390Y1098633D03*
X896746Y1218851D03*
X891844Y1455143D03*
X897736Y388764D03*
X903431Y539552D03*
X911416Y806374D03*
X910900Y912484D03*
X906128Y959074D03*
X901243Y1214722D03*
X908852Y1227992D03*
X912726D03*
X929418Y130807D03*
X921418D03*
X918607Y150813D03*
X927072Y384391D03*
X923072D03*
X919072D03*
X924999Y475426D03*
X928999D03*
X917250Y554604D03*
X927916Y806374D03*
X923790D03*
X919664D03*
X915716D03*
X914500Y912484D03*
X918100D03*
X924628Y912573D03*
X928628D03*
X925697Y1457310D03*
X921868Y1457340D03*
X933472Y130812D03*
X933651Y145921D03*
X938930Y221201D03*
X942805Y221189D03*
X938657Y367695D03*
X930900Y458364D03*
X931916Y814524D03*
X943916D03*
X943735Y847641D03*
X945035Y833241D03*
X936616Y898088D03*
X936628Y912573D03*
X944628D03*
X940628D03*
X932628D03*
X932716Y898088D03*
X936794Y1210686D03*
X951040Y221214D03*
X955816Y470403D03*
X960365Y639295D03*
X956365D03*
X950865D03*
X947556Y705109D03*
X955950Y731522D03*
X950335Y826341D03*
X948935Y833241D03*
X958682Y834412D03*
X958200Y841584D03*
X950100Y853484D03*
X954000D03*
X954124Y883054D03*
X954567Y933303D03*
X957671Y988727D03*
X951367Y1098633D03*
X960723Y1218851D03*
X962816Y448403D03*
X972397Y470463D03*
X967816Y470403D03*
X978161Y628151D03*
X968365Y639295D03*
X964365D03*
X973712Y719573D03*
X965220Y1214722D03*
X983554Y91513D03*
X987554D03*
X991554D03*
X991884Y176057D03*
X987884D03*
X992111Y187314D03*
X991050Y219666D03*
X989992Y287967D03*
X993992D03*
X990405Y321234D03*
X984045Y364068D03*
X980045D03*
X980397Y470543D03*
X981857Y602709D03*
X989857D03*
X993857D03*
X985857D03*
X991990Y771458D03*
X987990D03*
X990051Y816827D03*
X995563Y91513D03*
X994939Y262594D03*
X1004018Y278285D03*
X997992Y287967D03*
X1004635Y305735D03*
X1008635D03*
X997857Y602709D03*
X1001857D03*
X1003990Y771458D03*
X999990D03*
X1005230Y1028286D03*
X1018344Y91860D03*
X1022293Y91788D03*
X1026200Y91883D03*
X1021780Y130807D03*
X1020969Y150813D03*
X1021259Y1316506D03*
X1024115Y1333873D03*
X1031780Y130807D03*
X1035834Y130812D03*
X1036013Y145921D03*
X1035099Y235918D03*
X1040626Y236030D03*
X1033786Y305735D03*
X1037386D03*
X1041496D03*
X1041408Y455565D03*
X1033719Y942306D03*
Y949720D03*
X1052736Y236043D03*
X1044501Y236018D03*
X1060573Y455284D03*
X1066260Y1445450D03*
X1085916Y91513D03*
X1089916D03*
X1090246Y176057D03*
X1090469Y1585469D03*
X1086904Y1596265D03*
X1083735Y1606682D03*
Y1614618D03*
X1085474Y1634909D03*
X1093916Y91513D03*
X1097925D03*
X1094246Y176057D03*
X1094473Y187314D03*
X1093412Y219666D03*
X1097301Y262594D03*
X1106380Y278285D03*
X1092354Y287967D03*
X1096354D03*
X1100354D03*
X1098376Y1557242D03*
X1093376D03*
X1100233Y1585492D03*
X1104612Y1606661D03*
X1098904Y1596265D03*
X1094904D03*
X1097474Y1634909D03*
X1124655Y91788D03*
X1120706Y91860D03*
X1123331Y150813D03*
X1115151Y656220D03*
X1119151D03*
X1128562Y91883D03*
X1134142Y130807D03*
X1126142D03*
X1138196Y130812D03*
X1138375Y145921D03*
X1137461Y235918D03*
X1142988Y236030D03*
X1155098Y236043D03*
X1146863Y236018D03*
X1152485Y770626D03*
X1157451Y623847D03*
X1161451D03*
X1165451D03*
X1168485Y770494D03*
X1160485Y770626D03*
X1164485D03*
X1188278Y91513D03*
X1180715Y781952D03*
X1196278Y91513D03*
X1200287D03*
X1192278D03*
X1196608Y176057D03*
X1192608D03*
X1196835Y187314D03*
X1195774Y219666D03*
X1199663Y262594D03*
X1194716Y287967D03*
X1198716D03*
X1202716D03*
X1208742Y278285D03*
X1218716Y331926D03*
X1227017Y91788D03*
X1230924Y91883D03*
X1223068Y91860D03*
X1236504Y130807D03*
X1226504D03*
X1225693Y150813D03*
X1226436Y314799D03*
X1240558Y130812D03*
X1240737Y145921D03*
X1239823Y235918D03*
X1245350Y236030D03*
X1249225Y236018D03*
X1251302Y1201909D03*
X1257460Y236043D03*
X1261764Y396992D03*
X1256458Y565196D03*
X1263921Y1140188D03*
X1267921D03*
X1255921D03*
X1255628Y1185029D03*
X1259644Y1184959D03*
X1264573Y1198478D03*
X1268573D03*
X1260771Y1196804D03*
X1264575Y1206502D03*
X1268575D03*
X1260535Y1206507D03*
X1280659Y382632D03*
X1284659D03*
X1282760Y406525D03*
X1278499Y484942D03*
X1284655Y897984D03*
X1275493Y926977D03*
X1279493D03*
X1283493D03*
X1271493D03*
X1275921Y1140188D03*
X1271921D03*
X1280330Y1149996D03*
X1280306Y1168276D03*
X1280573Y1198478D03*
X1276573D03*
X1272573D03*
X1276575Y1206502D03*
X1280575D03*
X1272575D03*
X1300285Y33677D03*
X1298640Y91513D03*
X1294640D03*
X1302649D03*
X1290640D03*
X1298970Y176057D03*
X1294970D03*
X1299197Y187314D03*
X1298136Y219666D03*
X1302025Y262594D03*
X1297078Y287967D03*
X1301078D03*
X1291500Y324484D03*
X1291410Y376739D03*
X1292000Y897984D03*
X1289500Y946984D03*
X1296500Y966984D03*
X1310853Y43002D03*
X1311104Y278285D03*
X1305078Y287967D03*
X1318262Y318837D03*
X1312410Y376540D03*
X1308726Y395886D03*
X1315338Y448521D03*
X1318500Y922984D03*
X1314500D03*
X1317000Y933984D03*
X1318500Y964984D03*
X1311000Y966984D03*
X1315000D03*
X1317333Y1122881D03*
X1322853Y43002D03*
X1329736Y318837D03*
X1334010D03*
X1321862D03*
X1326136D03*
X1320903Y368225D03*
X1329064Y368233D03*
X1327584Y782089D03*
X1330500Y922984D03*
X1334500D03*
X1326500Y933984D03*
X1337610Y318837D03*
X1349747Y442023D03*
X1343846Y459085D03*
X1347846D03*
X1345000Y793484D03*
X1348917D03*
X1342500Y922984D03*
X1338500D03*
X1336000Y933984D03*
X1345948Y949087D03*
X1349948D03*
X1345459Y1123880D03*
X1349461Y1122881D03*
X1352817Y793484D03*
X1365000Y809484D03*
X1361000D03*
X1357000D03*
X1365948Y949087D03*
X1357948D03*
X1353948D03*
X1378505Y130807D03*
X1375694Y150813D03*
X1380500Y593484D03*
Y639984D03*
Y684484D03*
Y731484D03*
X1373000Y809484D03*
X1381000D03*
X1369000D03*
X1377017Y809482D03*
X1382560Y937305D03*
X1378503Y937304D03*
X1369948Y949087D03*
X1375265Y1027750D03*
X1377587Y1123880D03*
X1382920Y1122881D03*
X1386505Y130807D03*
X1390559Y130812D03*
X1390738Y145921D03*
X1389824Y235918D03*
X1395351Y236030D03*
X1399226Y236018D03*
X1394537Y809163D03*
X1398517Y809201D03*
X1407461Y236043D03*
X1410903Y467403D03*
X1413452Y639295D03*
X1407952D03*
X1402517Y809201D03*
X1406483D03*
X1402265Y995250D03*
X1406265D03*
X1411046Y1123880D03*
X1415048Y1122881D03*
X1407747Y1546444D03*
X1407255Y1569122D03*
X1417903Y445403D03*
X1427484Y467543D03*
X1422903Y467403D03*
X1425452Y639295D03*
X1417452D03*
X1421452D03*
X1432258Y1410799D03*
X1444641Y91513D03*
X1440641D03*
X1448641D03*
X1448971Y176057D03*
X1444971D03*
X1449198Y187314D03*
X1448137Y219666D03*
X1447079Y287967D03*
X1435484Y467543D03*
X1442944Y602709D03*
X1438944D03*
X1446944D03*
X1435248Y628151D03*
X1437980Y1031431D03*
X1443174Y1123880D03*
X1436258Y1410799D03*
X1437293Y1543474D03*
X1436801Y1566152D03*
X1452650Y91513D03*
X1452026Y262594D03*
X1461105Y278285D03*
X1451079Y287967D03*
X1455079D03*
X1454944Y602709D03*
X1458944D03*
X1450944D03*
X1462317Y1028286D03*
X1479380Y91788D03*
X1475431Y91860D03*
X1478867Y130807D03*
X1478056Y150813D03*
X1471500Y715984D03*
Y759984D03*
X1483287Y91883D03*
X1488867Y130807D03*
X1492921Y130812D03*
X1493100Y145921D03*
X1492186Y235918D03*
X1497713Y236030D03*
X1488500Y801484D03*
Y845484D03*
X1509823Y236043D03*
X1501588Y236018D03*
X1498495Y455565D03*
X1517660Y455284D03*
X1547003Y91513D03*
X1543003D03*
X1555012D03*
X1551003D03*
X1551333Y176057D03*
X1547333D03*
X1551560Y187314D03*
X1550499Y219666D03*
X1554388Y262594D03*
X1549441Y287967D03*
X1553441D03*
X1557441D03*
X1577793Y91860D03*
X1563467Y278285D03*
X1572238Y656220D03*
X1576238D03*
X1585649Y91883D03*
X1581742Y91788D03*
X1591229Y130807D03*
X1583229D03*
X1595283Y130812D03*
X1595462Y145921D03*
X1580418Y150813D03*
X1594548Y235918D03*
X1587746Y1460616D03*
X1594264Y1472999D03*
X1600075Y236030D03*
X1603950Y236018D03*
X1601500Y1511984D03*
X1598000D03*
X1608500D03*
X1610858Y1523299D03*
X1612185Y236043D03*
X1614538Y623847D03*
X1618538D03*
X1622538D03*
X1653365Y91513D03*
X1657374D03*
X1645365D03*
X1649365D03*
X1653695Y176057D03*
X1649695D03*
X1653922Y187314D03*
X1652861Y219666D03*
X1656750Y262594D03*
X1651803Y287967D03*
X1655803D03*
X1659803D03*
X1665829Y278285D03*
X1675803Y331926D03*
X1680155Y91860D03*
X1684104Y91788D03*
X1688011Y91883D03*
X1683591Y130807D03*
X1682780Y150813D03*
X1683523Y314799D03*
X1693591Y130807D03*
X1697645Y130812D03*
X1697824Y145921D03*
X1702437Y236030D03*
X1696910Y235918D03*
X1706312Y236018D03*
X1714547Y236043D03*
X1718851Y396992D03*
X1713545Y565196D03*
X1721008Y1140188D03*
X1725008D03*
X1713008D03*
X1712715Y1185029D03*
X1716731Y1184959D03*
X1721660Y1198478D03*
X1725660D03*
X1709820Y1199574D03*
X1721662Y1206502D03*
X1725662D03*
X1717568Y1206302D03*
X1741746Y382632D03*
X1737746D03*
X1739847Y406525D03*
X1735586Y484942D03*
X1733008Y1140188D03*
X1729008D03*
X1737417Y1149996D03*
X1737393Y1168276D03*
X1737660Y1198478D03*
X1729660D03*
X1733660D03*
X1729662Y1206502D03*
X1733662D03*
X1737662D03*
X1751727Y91513D03*
X1755727D03*
X1747727D03*
X1756057Y176057D03*
X1752057D03*
X1756284Y187314D03*
X1755223Y219666D03*
X1754165Y287967D03*
X1758165D03*
X1748497Y376739D03*
X1750900Y907884D03*
X1756422Y1637788D03*
X1759736Y91513D03*
X1759112Y262594D03*
X1768191Y278285D03*
X1762165Y287967D03*
X1769497Y376540D03*
X1765813Y395886D03*
X1772425Y448521D03*
X1761072Y1596251D03*
X1765072D03*
X1772422Y1637788D03*
X1768422D03*
X1760422D03*
X1764422D03*
X1782517Y91860D03*
X1786466Y91788D03*
X1790373Y91883D03*
X1776071Y836378D03*
X1789537Y927561D03*
X1780774Y1211172D03*
X1778227Y1443592D03*
X1778104Y1475782D03*
X1776422Y1637788D03*
X1806834Y442023D03*
X1800933Y459085D03*
X1804933D03*
X1797374Y927433D03*
X1795347Y1099119D03*
X1804703Y1219337D03*
X1800046Y1440630D03*
X1799923Y1472820D03*
X1809700Y910084D03*
X1808363Y973144D03*
Y980558D03*
X1809200Y1215208D03*
G54D108*
X109882Y1622402D03*
X283110D03*
X456339D03*
X629567D03*
X1131850D03*
X1305079D03*
X1478307D03*
X1651535D03*
G54D135*
X417211Y1133067D03*
X449339D03*
X482798D03*
X514926D03*
X1331385D03*
X1363513D03*
X1396972D03*
X1429100D03*
G54D24*
X14781Y189835D03*
X30529D03*
X32086Y586113D03*
X47834D03*
X117143Y189835D03*
X132891D03*
X235253D03*
X219505D03*
X321867D03*
X337615D03*
X381983Y418952D03*
X397731D03*
X471868Y189835D03*
X487616D03*
X489172Y586113D03*
X504920D03*
X574230Y189835D03*
X589978D03*
X676592D03*
X692340D03*
X778954D03*
X794702D03*
X877309Y432293D03*
X893057D03*
X929620Y175006D03*
X945368D03*
X946259Y586113D03*
X962007D03*
X1047064Y189835D03*
X1031316D03*
X1133678D03*
X1149426D03*
X1236040D03*
X1251788D03*
X1296156Y418952D03*
X1311904D03*
X1386041Y189835D03*
X1401789D03*
X1403346Y586113D03*
X1419094D03*
X1488403Y189835D03*
X1504151D03*
X1590765D03*
X1606513D03*
X1693127D03*
X1708875D03*
X1753243Y418952D03*
X1768991D03*
G54D126*
X390780Y748036D03*
Y750005D03*
Y751973D03*
Y753942D03*
Y755910D03*
Y757879D03*
Y759847D03*
Y761816D03*
Y763784D03*
Y765753D03*
Y767721D03*
Y769690D03*
Y771658D03*
Y773627D03*
Y775595D03*
Y777564D03*
X1763480Y880636D03*
Y882605D03*
Y884573D03*
Y886542D03*
Y888510D03*
Y890479D03*
Y892447D03*
Y894416D03*
Y896384D03*
Y898353D03*
Y900321D03*
Y902290D03*
Y904258D03*
Y906227D03*
Y908195D03*
Y910164D03*
G54D51*
X22756Y1506877D03*
Y1508846D03*
Y1510814D03*
Y1512783D03*
Y1514751D03*
Y1516720D03*
Y1518688D03*
Y1520657D03*
Y1522625D03*
Y1524594D03*
Y1526562D03*
Y1528531D03*
Y1530499D03*
Y1532468D03*
Y1534436D03*
Y1536405D03*
X57402Y1512783D03*
Y1510814D03*
Y1508846D03*
Y1506877D03*
Y1528531D03*
Y1526562D03*
Y1524594D03*
Y1522625D03*
Y1520657D03*
Y1518688D03*
Y1516720D03*
Y1514751D03*
Y1536405D03*
Y1534436D03*
Y1532468D03*
Y1530499D03*
G54D16*
X8786Y85411D03*
X6298Y99649D03*
X18298D03*
X6499Y138847D03*
X8264Y159013D03*
X15184Y150286D03*
X19184D03*
X16709Y173285D03*
X17822Y212889D03*
X6811Y1005604D03*
X10701D03*
X14645D03*
X11768Y1525256D03*
X14375Y1550556D03*
X10367Y1550563D03*
X31971Y106469D03*
X23184Y150286D03*
X32201Y236042D03*
X26192Y616794D03*
X30192D03*
X33992D03*
X27556Y1005604D03*
X33659D03*
X21506D03*
X25674Y1491774D03*
X35850Y1553213D03*
X26231Y1551642D03*
X22381Y1551660D03*
X45643Y470402D03*
X49643D03*
X39549Y1005604D03*
X45858D03*
X51946D03*
X40951Y1553213D03*
X47074Y1553204D03*
X52048Y1553179D03*
X65759Y442977D03*
X54936Y454821D03*
X61759Y442977D03*
X57759D03*
X62224Y470542D03*
X66345Y490147D03*
X56514Y536891D03*
X64408Y578815D03*
X63684Y602708D03*
X61192Y639294D03*
X57692D03*
X64692D03*
X56149Y824291D03*
X65774Y1005604D03*
X61779D03*
X57834D03*
X57702Y1198728D03*
X61380Y1205454D03*
X53737Y1199888D03*
X54351Y1483866D03*
X56114Y1553178D03*
X64747Y1553171D03*
X63090Y1615060D03*
X80660Y101256D03*
X76660D03*
X70577Y101609D03*
X84808Y103511D03*
X76766Y262593D03*
X84766D03*
X78106Y662474D03*
X74910Y687495D03*
X84699Y1004449D03*
X87652Y578620D03*
X93456Y655308D03*
X95836Y986014D03*
X99836D03*
Y995014D03*
X95836D03*
X97609Y1013880D03*
X104662Y116534D03*
X115582Y107807D03*
X111582D03*
X113607Y130806D03*
X106796Y157923D03*
X111836Y986014D03*
X103836D03*
X115836D03*
X107836D03*
X111836Y995014D03*
X103836D03*
X115836D03*
X107836D03*
X109601Y1226509D03*
X105601D03*
X119582Y107807D03*
X128251Y146820D03*
X120184Y212889D03*
X127235Y448564D03*
X119836Y986014D03*
X123836D03*
X127836D03*
X131836D03*
X119836Y995014D03*
X123836D03*
X127836D03*
X131836D03*
X127604Y1105591D03*
Y1118191D03*
Y1130791D03*
Y1143391D03*
Y1155991D03*
Y1168591D03*
Y1181191D03*
X134333Y106469D03*
X134563Y236042D03*
X138971Y541874D03*
X142961Y541833D03*
X143836Y986014D03*
X147836D03*
X139836D03*
X135836D03*
X143836Y995014D03*
X147836D03*
X139836D03*
X135836D03*
X139250Y1012854D03*
Y1025454D03*
X159836Y986014D03*
X151836D03*
X159836Y995014D03*
X155836D03*
X151836D03*
X179022Y101256D03*
X172939Y101609D03*
X179128Y262593D03*
X183022Y101256D03*
X188526Y100533D03*
Y108145D03*
X187128Y262593D03*
X201033Y91859D03*
X207024Y116534D03*
X213944Y107807D03*
X209158Y157923D03*
X221944Y107807D03*
X217944D03*
X215969Y130806D03*
X230613Y146820D03*
X222546Y212889D03*
X221942Y1537368D03*
X225753Y1537198D03*
X229942Y1549368D03*
X236695Y106469D03*
X236925Y236042D03*
X242102Y653729D03*
X246102D03*
X240842Y1530368D03*
X233753Y1537198D03*
X237942Y1549368D03*
X244942D03*
X233942D03*
X250102Y653729D03*
X248042Y1530368D03*
X275301Y101609D03*
X281384Y101256D03*
X290888Y100533D03*
X285384Y101256D03*
X290888Y108145D03*
X289490Y262593D03*
X281490D03*
X303395Y91859D03*
X309386Y116534D03*
X311520Y157923D03*
X312263Y321798D03*
X324306Y107807D03*
X320306D03*
X316306D03*
X318222Y130697D03*
X324908Y212889D03*
X317416Y345377D03*
X321416D03*
X323285Y553195D03*
X339057Y106469D03*
X332975Y146820D03*
X339287Y236042D03*
X342486Y382631D03*
X342285Y558195D03*
X336755Y1140187D03*
X337629Y1178808D03*
X342298Y1193899D03*
X346486Y382631D03*
X358486D03*
X350486D03*
X354486D03*
X353202Y411985D03*
X345748Y1140187D03*
X350414Y1178148D03*
X358443Y1177169D03*
X354414Y1178148D03*
X359761Y1185109D03*
X354442Y1185113D03*
X350442D03*
X346136Y1194034D03*
X370931Y367347D03*
X362486Y382631D03*
X374714Y793252D03*
X365748Y1140187D03*
X362282Y1177832D03*
X363729Y1185146D03*
X393250Y100533D03*
X387746Y101256D03*
X383746D03*
X377663Y101609D03*
X393250Y108145D03*
X383852Y262593D03*
X391852D03*
X389237Y376537D03*
X381237D03*
X385237D03*
X404686Y42956D03*
X400686D03*
X394237Y376539D03*
X403478Y875751D03*
X399369D03*
X399816Y956130D03*
X400043Y967387D03*
X404043D03*
X403263Y1158242D03*
X397461Y1566492D03*
X401461D03*
X420422Y365140D03*
X412318Y365132D03*
X411847Y432320D03*
X425673Y459084D03*
X426000Y789283D03*
X416200Y798583D03*
X417682Y1057696D03*
X410668Y1105613D03*
X414455D03*
X422532Y1101825D03*
X421461Y1566492D03*
X417461D03*
X431424Y365001D03*
X435024D03*
X427566Y883916D03*
X427913Y1101825D03*
X431285Y1113379D03*
X449745Y628543D03*
X445745D03*
X442796Y1105613D03*
X446583D03*
X454660Y1101825D03*
X456025Y1220971D03*
X459387Y116534D03*
X474307Y107807D03*
X470307D03*
X466307D03*
X468332Y130806D03*
X461521Y157923D03*
X474909Y212889D03*
X468836Y543080D03*
X460041Y1101825D03*
X463413Y1113379D03*
X468850Y1158242D03*
X462687D03*
X461319Y1220971D03*
X489058Y106469D03*
X482976Y146820D03*
X489288Y236042D03*
X485485Y437400D03*
X489485D03*
X491078Y616794D03*
X483278D03*
X487278D03*
X476255Y1105613D03*
X480042D03*
X488119Y1101825D03*
X500729Y467402D03*
X504729D03*
X501082Y992664D03*
X505958Y1057989D03*
X493500Y1101825D03*
X496872Y1113379D03*
X520845Y439977D03*
X516845D03*
X512845D03*
X510022Y451821D03*
X517310Y467542D03*
X523431Y490147D03*
X513600Y536891D03*
X521494Y578815D03*
X520770Y602708D03*
X516770D03*
X518278Y639294D03*
X514778D03*
X521778D03*
X519285Y728479D03*
X515285D03*
X511285D03*
X523285D03*
X509096Y758773D03*
X513504Y761890D03*
X508383Y1105613D03*
X512170D03*
X520247Y1101825D03*
X537747Y101256D03*
X533747D03*
X527664Y101609D03*
X533853Y262593D03*
X539285Y728479D03*
X535285D03*
X531285D03*
X527285D03*
X524319Y761864D03*
X536715Y1009304D03*
X529000Y1113379D03*
X528274Y1158242D03*
X555758Y91859D03*
X543251Y100533D03*
Y108145D03*
X541853Y262593D03*
X544738Y578620D03*
X552923Y986014D03*
Y995014D03*
X554696Y1013880D03*
X561749Y116534D03*
X568669Y107807D03*
X570694Y130806D03*
X563883Y157923D03*
X568464Y757957D03*
X560256Y779157D03*
X556923Y986014D03*
X568923D03*
X560923D03*
X564923D03*
X556923Y995014D03*
X568923D03*
X560923D03*
X564923D03*
X562688Y1226509D03*
X566688D03*
X564242Y1528168D03*
X571809Y1538484D03*
X562786Y1537592D03*
X558786D03*
X571942Y1547268D03*
X576669Y107807D03*
X572669D03*
X585338Y146820D03*
X577271Y212889D03*
X584321Y448564D03*
X573203Y938380D03*
X576923Y986014D03*
X580923D03*
X584923D03*
X572923D03*
X576923Y995014D03*
X580923D03*
X584923D03*
X572923D03*
X584691Y1105591D03*
Y1118191D03*
Y1130791D03*
Y1143391D03*
Y1155991D03*
Y1168591D03*
Y1181191D03*
X587809Y1538484D03*
X579809D03*
X583742Y1547768D03*
X591420Y106469D03*
X591650Y236042D03*
X600047Y541833D03*
X596057Y541874D03*
X600923Y986014D03*
X604923D03*
X592923D03*
X596923D03*
X588923D03*
X600923Y995014D03*
X604923D03*
X592923D03*
X596923D03*
X588923D03*
X596337Y1012854D03*
Y1025454D03*
X600242Y1541568D03*
X591809Y1538484D03*
X608923Y986014D03*
X616923D03*
X608923Y995014D03*
X616923D03*
X612923D03*
X636109Y101256D03*
X630026Y101609D03*
X636215Y262593D03*
X645613Y100533D03*
X640109Y101256D03*
X645613Y108145D03*
X644215Y262593D03*
X658120Y91859D03*
X664111Y116534D03*
X666245Y157923D03*
X679031Y107807D03*
X671031D03*
X675031D03*
X673056Y130806D03*
X679633Y212889D03*
X693782Y106469D03*
X687700Y146820D03*
X694012Y236042D03*
X699188Y653729D03*
X688728Y703417D03*
X703188Y653729D03*
X707188D03*
X713382Y705220D03*
X732388Y101609D03*
X723811Y742039D03*
X742471Y101256D03*
X747975Y100533D03*
X738471Y101256D03*
X747975Y108145D03*
X738577Y262593D03*
X746577D03*
X747140Y1586793D03*
X748924Y1614851D03*
X748997Y1624393D03*
X747590Y1633692D03*
X760482Y91859D03*
X766473Y116534D03*
X763145Y1586771D03*
X759169Y1586818D03*
X763452Y1616825D03*
X752150Y1633717D03*
X781393Y107807D03*
X773393D03*
X777393D03*
X775418Y130806D03*
X768607Y157923D03*
X781995Y212889D03*
X769349Y321798D03*
X774502Y345377D03*
X778502D03*
X780371Y553195D03*
X783215Y1452633D03*
X767512Y1449685D03*
X777033Y1592480D03*
X781110D03*
X767452Y1616825D03*
X773822Y1633208D03*
X796144Y106469D03*
X790062Y146820D03*
X796374Y236042D03*
X799371Y558195D03*
X793842Y1140187D03*
X794716Y1178808D03*
X798324Y1198092D03*
X799230Y1206514D03*
X799901Y1472584D03*
X791610Y1599496D03*
X787447Y1599519D03*
X802835Y1140187D03*
X811529Y1185113D03*
X811501Y1178148D03*
X807501D03*
X807529Y1185113D03*
X814148Y1380666D03*
X832284Y716497D03*
X827284Y709547D03*
Y716497D03*
X828880Y870347D03*
X828643Y896072D03*
X826987Y929688D03*
X831409Y922276D03*
X827409D03*
X828423Y962177D03*
X822835Y1140187D03*
X816848Y1185109D03*
X820826Y1178196D03*
X820816Y1185146D03*
X816826Y1178196D03*
X840833Y101256D03*
X844833D03*
X834750Y101609D03*
X840939Y262593D03*
X848284Y716497D03*
X839290Y709527D03*
X843284Y709547D03*
X839290Y716477D03*
X843284Y716497D03*
X833112Y836573D03*
X836405Y863475D03*
X832880Y870347D03*
X832643Y896072D03*
X842000Y901483D03*
X848628Y912572D03*
X846000Y901483D03*
X841064Y922076D03*
X837235D03*
X840423Y962177D03*
X862844Y91859D03*
X850337Y100533D03*
Y108145D03*
X848939Y262593D03*
X858586Y379983D03*
X854086D03*
X858586Y390483D03*
X854086D03*
X863086D03*
X852284Y709547D03*
Y716497D03*
X856628Y912572D03*
X864628D03*
X849205Y929692D03*
X852488Y1017136D03*
X857884D03*
X864007D03*
X874531Y200408D03*
X880736Y388763D03*
X875916Y816523D03*
X872628Y912572D03*
X880628D03*
X879740Y944184D03*
X870401Y1017136D03*
X875954D03*
X893736Y388763D03*
X888736D03*
X884736D03*
X892931Y539551D03*
X885931D03*
X889431D03*
X895933Y615651D03*
X892728Y792759D03*
X895916Y816523D03*
X888628Y912572D03*
X892628D03*
X896628D03*
X881454Y1017136D03*
X885210D03*
X889089D03*
X893613Y1017279D03*
X904614Y343347D03*
X908114D03*
X911072Y384390D03*
X907173Y448661D03*
X899931Y539551D03*
X913208Y615502D03*
X909208D03*
X904376Y615422D03*
X900376D03*
X903916Y806373D03*
X899916D03*
Y816523D03*
X903916D03*
X909416D03*
X900200Y912583D03*
X907300D03*
X903700D03*
X912628Y925609D03*
X904057Y940596D03*
X906255Y1018764D03*
X898046Y1017223D03*
X902225Y1018711D03*
X901392Y1207731D03*
X905070Y1214457D03*
X897427Y1208891D03*
X916473Y116534D03*
X927393Y107807D03*
X923393D03*
X925418Y130806D03*
X918607Y157923D03*
X915072Y384390D03*
X920999Y475425D03*
X925418Y680853D03*
X921418D03*
X921061Y712828D03*
X925061D03*
X927916Y814523D03*
X921790Y816523D03*
X920628Y925609D03*
X924628D03*
X928628D03*
X916628D03*
X927984Y1017136D03*
X916465D03*
X921861D03*
X931393Y107807D03*
X940062Y146820D03*
X932661Y198060D03*
X938125Y236727D03*
X942757Y257672D03*
X941685Y360736D03*
X942437Y367688D03*
X931072Y384390D03*
X940365Y616794D03*
X944365D03*
X932412Y680853D03*
X938526Y730508D03*
X935916Y814523D03*
X939916D03*
X941535Y826540D03*
X937635D03*
X940516Y898088D03*
X944628Y925609D03*
X936628D03*
X940628D03*
X932628D03*
X945671Y988726D03*
X939931Y1017136D03*
X945431D03*
X934378D03*
X946144Y106469D03*
X947040Y221213D03*
X951278Y241031D03*
Y248010D03*
X959816Y470402D03*
X948165Y616794D03*
X961503Y704315D03*
X953551D03*
X957551D03*
X959950Y731521D03*
X951100Y841583D03*
X952783Y833266D03*
X947200Y841583D03*
X957900Y853483D03*
X958567Y933302D03*
X950567D03*
X953671Y988726D03*
X961671D03*
X949671D03*
X950987Y1017136D03*
X954866D03*
X961404Y1208891D03*
X969109Y454821D03*
X975932Y442977D03*
X971932D03*
X963816Y470402D03*
X976397Y470542D03*
X970687Y536891D03*
X978581Y578815D03*
X977857Y602708D03*
X973857D03*
X975365Y639294D03*
X971865D03*
X963950Y731521D03*
X966746Y933275D03*
X962567Y933302D03*
X965671Y988726D03*
X967625Y1017367D03*
X971760Y1017387D03*
X963823Y1017223D03*
X975659Y1017408D03*
X965369Y1207731D03*
X969047Y1214457D03*
X990833Y101256D03*
X994833D03*
X984750Y101609D03*
X990939Y262593D03*
X990405Y314000D03*
X988045Y364067D03*
X992045D03*
X979932Y442977D03*
X980518Y490147D03*
X978865Y639294D03*
X983712Y719572D03*
X994051Y816826D03*
X1000337Y100533D03*
Y108145D03*
X998939Y262593D03*
X1000698Y305734D03*
X996045Y364067D03*
X1001825Y578620D03*
X1007990Y771457D03*
X995990D03*
X1006699Y816883D03*
X1002699D03*
X1010699D03*
X1010009Y986014D03*
Y995014D03*
X998872Y1004449D03*
X1000248Y1024394D03*
X1012844Y91859D03*
X1018835Y116534D03*
X1025755Y107807D03*
X1020969Y157923D03*
X1016635Y305734D03*
X1020635D03*
X1025749D03*
X1012635D03*
X1018922Y805798D03*
X1014819Y935395D03*
X1026009Y986014D03*
X1018009D03*
X1022009D03*
X1014009D03*
X1026009Y995014D03*
X1018009D03*
X1022009D03*
X1014009D03*
X1011782Y1013880D03*
X1019774Y1226509D03*
X1023774D03*
X1017329Y1316495D03*
X1020049Y1333819D03*
X1019671Y1347982D03*
X1019257Y1366456D03*
X1033755Y107807D03*
X1029755D03*
X1027780Y130806D03*
X1042424Y146820D03*
X1034357Y212889D03*
X1029639Y305734D03*
X1041408Y448564D03*
X1030009Y986014D03*
X1038009D03*
X1042009D03*
X1034009D03*
Y995014D03*
X1030009D03*
X1038009D03*
X1042009D03*
X1041777Y1105591D03*
Y1118191D03*
Y1130791D03*
Y1143391D03*
Y1155991D03*
Y1168591D03*
Y1181191D03*
X1038996Y1371550D03*
X1048506Y106469D03*
X1048736Y236042D03*
X1045650Y305734D03*
X1057134Y541833D03*
X1053144Y541874D03*
X1046009Y986014D03*
X1050009D03*
X1054009D03*
X1058009D03*
X1046009Y995014D03*
X1050009D03*
X1054009D03*
X1058009D03*
X1053423Y1012854D03*
Y1025454D03*
X1074009Y986014D03*
X1066009D03*
X1062009D03*
X1074009Y995014D03*
X1066009D03*
X1062009D03*
X1070009D03*
X1087112Y101609D03*
X1086108Y1526491D03*
X1086469Y1585468D03*
X1090904Y1596264D03*
X1089474Y1634908D03*
X1093195Y101256D03*
X1097195D03*
X1102699Y100533D03*
Y108145D03*
X1093301Y262593D03*
X1101301D03*
X1096233Y1585491D03*
X1104233D03*
X1102904Y1596264D03*
X1093474Y1634908D03*
X1101474D03*
X1105474D03*
X1115206Y91859D03*
X1121197Y116534D03*
X1123331Y157923D03*
X1136117Y107807D03*
X1132117D03*
X1128117D03*
X1130142Y130806D03*
X1136719Y212889D03*
X1150868Y106469D03*
X1144786Y146820D03*
X1151098Y236042D03*
X1156275Y653729D03*
X1156485Y770625D03*
X1155485Y842125D03*
X1160275Y653729D03*
X1164275D03*
X1167485Y828625D03*
X1159485D03*
X1171485Y842125D03*
X1163485D03*
X1167485D03*
X1159485D03*
X1189474Y101609D03*
X1183485Y828625D03*
X1175485D03*
X1183485Y842125D03*
X1179485D03*
X1175485D03*
X1195557Y101256D03*
X1199557D03*
X1205061Y100533D03*
Y108145D03*
X1195663Y262593D03*
X1203663D03*
X1217568Y91859D03*
X1238479Y107807D03*
X1223559Y116534D03*
X1234479Y107807D03*
X1230479D03*
X1232504Y130806D03*
X1225693Y157923D03*
X1226436Y321798D03*
X1231589Y345377D03*
X1235589D03*
X1237458Y553195D03*
X1253230Y106469D03*
X1247148Y146820D03*
X1239081Y212889D03*
X1253460Y236042D03*
X1250928Y1140187D03*
X1251802Y1178808D03*
X1249230Y1192404D03*
X1256659Y382631D03*
X1268659D03*
X1260659D03*
X1264659D03*
X1267375Y411985D03*
X1256458Y558195D03*
X1261622Y901500D03*
X1259921Y1140187D03*
X1264587Y1178148D03*
X1268587D03*
X1268615Y1185113D03*
X1264615D03*
X1255485Y1201908D03*
X1275660Y345693D03*
X1279655Y345634D03*
X1276659Y382631D03*
X1272659D03*
X1280042Y905131D03*
X1279921Y1140187D03*
X1277912Y1178196D03*
X1273912D03*
X1273934Y1185109D03*
X1277902Y1185146D03*
X1297919Y101256D03*
X1301919D03*
X1291836Y101609D03*
X1298025Y262593D03*
X1303410Y376537D03*
X1287437Y375662D03*
X1295410Y376537D03*
X1299410D03*
X1292566Y807304D03*
X1298909Y818575D03*
X1288155Y897983D03*
X1302000Y922983D03*
X1298000D03*
X1300882Y934047D03*
X1300500Y966983D03*
X1314859Y42956D03*
X1318859D03*
X1307423Y100533D03*
Y108145D03*
X1306025Y262593D03*
X1308410Y376539D03*
X1316903Y368224D03*
X1317000Y793483D03*
X1313000D03*
Y809483D03*
X1317000D03*
X1313152Y934047D03*
X1309103D03*
X1317000Y940983D03*
X1304949Y934047D03*
X1307000Y966983D03*
X1317437Y1158242D03*
X1325007Y368232D03*
X1334009Y368093D03*
X1326020Y432320D03*
X1333000Y793483D03*
X1329000D03*
X1325000D03*
X1321000D03*
X1333000Y809483D03*
X1325000D03*
X1329000D03*
X1321000D03*
X1322500Y922983D03*
X1326500D03*
Y940983D03*
X1327000Y966983D03*
X1332000D03*
X1331856Y1057696D03*
X1324842Y1105613D03*
X1328629D03*
X1337609Y368093D03*
X1339846Y459084D03*
X1341000Y793483D03*
X1337000D03*
X1341000Y809483D03*
X1345000D03*
X1349000D03*
X1337000D03*
X1350500Y922983D03*
X1336000Y940983D03*
X1337691Y951626D03*
X1342087Y1101825D03*
X1336706D03*
X1345459Y1113379D03*
X1353000Y809483D03*
X1354500Y922983D03*
X1358500D03*
X1362500D03*
X1366500D03*
X1361948Y949086D03*
X1356970Y1105613D03*
X1360757D03*
X1373560Y116534D03*
X1384480Y107807D03*
X1380480D03*
X1382505Y130806D03*
X1375694Y157923D03*
X1370500Y922983D03*
X1378500D03*
X1374500D03*
X1382500D03*
X1373948Y949086D03*
X1374215Y1101825D03*
X1368834D03*
X1377587Y1113379D03*
X1376861Y1158242D03*
X1383024D03*
X1388480Y107807D03*
X1397149Y146820D03*
X1389082Y212889D03*
X1397452Y616794D03*
X1390537Y809162D03*
X1386335Y809187D03*
X1388346Y927128D03*
X1390429Y1105613D03*
X1394216D03*
X1403231Y106469D03*
X1403461Y236042D03*
X1414903Y467402D03*
X1405252Y616794D03*
X1401452D03*
X1401000Y922983D03*
X1407674Y1101825D03*
X1402293D03*
X1411046Y1113379D03*
X1416684Y1514632D03*
X1411586Y1546437D03*
X1411094Y1569115D03*
X1431019Y439977D03*
X1427019D03*
X1424196Y451821D03*
X1431484Y467542D03*
X1418903Y467402D03*
X1427774Y536891D03*
X1430944Y602708D03*
X1432452Y639294D03*
X1428952D03*
X1420132Y1057989D03*
X1422557Y1105613D03*
X1426344D03*
X1426253Y1410760D03*
X1430374Y1498553D03*
X1433405Y1543475D03*
X1432913Y1566153D03*
X1447920Y101256D03*
X1441837Y101609D03*
X1448026Y262593D03*
X1435019Y439977D03*
X1437605Y490147D03*
X1435668Y578815D03*
X1434944Y602708D03*
X1435952Y639294D03*
X1443459Y1037394D03*
X1434421Y1101825D03*
X1443174Y1113379D03*
X1442448Y1158242D03*
X1436792Y1558424D03*
X1457424Y100533D03*
X1451920Y101256D03*
X1457424Y108145D03*
X1456026Y262593D03*
X1458912Y578620D03*
X1455959Y1004449D03*
X1469931Y91859D03*
X1475922Y116534D03*
X1478056Y157923D03*
X1475096Y986014D03*
X1479096D03*
X1471096D03*
X1467096D03*
X1475096Y995014D03*
X1479096D03*
X1471096D03*
X1467096D03*
X1468869Y1013880D03*
X1480861Y1226509D03*
X1476861D03*
X1490842Y107807D03*
X1482842D03*
X1486842D03*
X1484867Y130806D03*
X1491444Y212889D03*
X1491096Y986014D03*
X1487096D03*
X1495096D03*
X1483096D03*
X1491096Y995014D03*
X1487096D03*
X1495096D03*
X1483096D03*
X1505593Y106469D03*
X1499511Y146820D03*
X1505823Y236042D03*
X1498495Y448564D03*
X1514221Y541833D03*
X1510231Y541874D03*
X1503096Y986014D03*
X1507096D03*
X1511096D03*
X1499096D03*
X1503096Y995014D03*
X1507096D03*
X1511096D03*
X1499096D03*
X1510510Y1025454D03*
Y1012854D03*
X1498864Y1105591D03*
Y1118191D03*
Y1130791D03*
Y1143391D03*
Y1155991D03*
Y1168591D03*
Y1181191D03*
X1525015Y906508D03*
X1523096Y986014D03*
X1519096D03*
X1515096D03*
X1523096Y995014D03*
X1519096D03*
X1527096D03*
X1515096D03*
X1544199Y101609D03*
X1531096Y986014D03*
Y995014D03*
X1554282Y101256D03*
X1559786Y100533D03*
X1550282Y101256D03*
X1559786Y108145D03*
X1550388Y262593D03*
X1558388D03*
X1572293Y91859D03*
X1578284Y116534D03*
X1593204Y107807D03*
X1589204D03*
X1585204D03*
X1587229Y130806D03*
X1580418Y157923D03*
X1593806Y212889D03*
X1594307Y1505038D03*
X1594500Y1511983D03*
X1607955Y106469D03*
X1601873Y146820D03*
X1608185Y236042D03*
X1608483Y783385D03*
X1608383Y798185D03*
X1608283Y812185D03*
X1600333Y1446468D03*
X1605000Y1511983D03*
X1598142Y1530368D03*
X1613362Y653729D03*
X1617362D03*
X1621362D03*
X1616683Y750485D03*
X1616583Y764485D03*
X1634083Y777685D03*
X1632583Y790385D03*
X1631383Y804485D03*
X1652644Y101256D03*
X1656644D03*
X1646561Y101609D03*
X1652750Y262593D03*
X1660750D03*
X1674655Y91859D03*
X1662148Y100533D03*
Y108145D03*
X1680646Y116534D03*
X1691566Y107807D03*
X1687566D03*
X1689591Y130806D03*
X1682780Y157923D03*
X1683523Y321798D03*
X1688676Y345377D03*
X1692676D03*
X1695566Y107807D03*
X1704235Y146820D03*
X1696168Y212889D03*
X1694545Y553195D03*
X1708015Y1140187D03*
X1708889Y1178808D03*
X1708745Y1227183D03*
X1710317Y106469D03*
X1710547Y236042D03*
X1713746Y382631D03*
X1717746D03*
X1725746D03*
X1721746D03*
X1724462Y411985D03*
X1713545Y558195D03*
X1717008Y1140187D03*
X1725674Y1178148D03*
X1721674D03*
X1725702Y1185113D03*
X1721702D03*
X1713721Y1206369D03*
X1709827Y1206323D03*
X1712966Y1227174D03*
X1733746Y382631D03*
X1729746D03*
X1737008Y1140187D03*
X1734999Y1178196D03*
X1730999D03*
X1731021Y1185109D03*
X1734989Y1185146D03*
X1755006Y101256D03*
X1748923Y101609D03*
X1755112Y262593D03*
X1752497Y376537D03*
X1756497D03*
X1756297Y1018535D03*
X1753221Y1621562D03*
X1764510Y100533D03*
X1759006Y101256D03*
X1764510Y108145D03*
X1763112Y262593D03*
X1765497Y376539D03*
X1760497Y376537D03*
X1765131Y1018535D03*
X1760487D03*
X1771992D03*
X1774339Y1443593D03*
X1774216Y1475783D03*
X1763000Y1584983D03*
X1777017Y91859D03*
X1783107Y432320D03*
X1789463Y966233D03*
X1784145Y1018535D03*
X1790035D03*
X1778042D03*
X1796933Y459084D03*
X1793474Y927469D03*
X1796344Y1018535D03*
X1802432D03*
X1805384Y1209377D03*
X1803885Y1440623D03*
X1803762Y1472813D03*
X1808320Y1018535D03*
X1812265D03*
X1816260D03*
X1809349Y1208217D03*
X1813027Y1214943D03*
X1828272Y1102015D03*
Y1109054D03*
G54D190*
X832961Y308900D03*
Y337836D03*
X855993Y308900D03*
Y337836D03*
X1298246Y748010D03*
Y776946D03*
X1321278Y748010D03*
Y776946D03*
X1350984Y561032D03*
Y589968D03*
Y607532D03*
Y636468D03*
Y652032D03*
Y680968D03*
Y699032D03*
Y727968D03*
X1374016Y561032D03*
Y589968D03*
Y607532D03*
Y636468D03*
Y652032D03*
Y680968D03*
Y699032D03*
Y727968D03*
X1441984Y683532D03*
Y712468D03*
Y727532D03*
Y756468D03*
X1465016Y683532D03*
Y712468D03*
Y727532D03*
Y756468D03*
X1458984Y769032D03*
Y797968D03*
Y813032D03*
Y841968D03*
X1482016Y769032D03*
Y797968D03*
Y813032D03*
Y841968D03*
G54D163*
X488765Y663326D03*
Y671200D03*
X493883Y663326D03*
X491324D03*
Y671200D03*
X493883D03*
X519753Y769259D03*
X517194D03*
X514635D03*
Y777133D03*
X517194D03*
X519753D03*
X829725Y727177D03*
Y735051D03*
X848284Y727177D03*
Y735051D03*
X845725Y727177D03*
Y735051D03*
X832284Y727177D03*
Y735051D03*
X834843Y727177D03*
Y735051D03*
X850843Y727177D03*
Y735051D03*
X1096264Y1574807D03*
Y1566933D03*
X1098823Y1574807D03*
Y1566933D03*
X1093705Y1574807D03*
Y1566933D03*
X1301348Y948224D03*
Y956098D03*
X1318000Y955937D03*
Y948063D03*
X1315441Y955937D03*
Y948063D03*
X1303907Y948224D03*
Y956098D03*
X1306466Y948224D03*
Y956098D03*
X1329500Y948063D03*
Y955937D03*
X1326941Y948063D03*
Y955937D03*
X1332059Y948063D03*
Y955937D03*
X1320559D03*
Y948063D03*
G54D118*
X343826Y1153242D03*
X341266D03*
X338707D03*
Y1167808D03*
X341266D03*
X343826D03*
X346385Y1153242D03*
Y1167808D03*
X798353Y1153242D03*
X795794D03*
Y1167808D03*
X798353D03*
X803472Y1153242D03*
X800913D03*
Y1167808D03*
X803472D03*
X874909Y761332D03*
X872350D03*
X880028D03*
X877469D03*
Y775898D03*
X874909D03*
X872350D03*
X880028D03*
X1091168Y1606949D03*
Y1621515D03*
X1093727Y1606949D03*
X1098846D03*
X1096287D03*
Y1621515D03*
X1093727D03*
X1098846D03*
X1252880Y1153242D03*
Y1167808D03*
X1260558Y1153242D03*
X1257999D03*
X1255439D03*
Y1167808D03*
X1257999D03*
X1260558D03*
X1717645Y1153242D03*
X1715086D03*
X1712526D03*
X1709967D03*
Y1167808D03*
X1712526D03*
X1715086D03*
X1717645D03*
G54D154*
X414519Y1250868D03*
Y1264254D03*
X512830Y1250868D03*
Y1264254D03*
X1328693Y1250868D03*
Y1264254D03*
X1427004Y1250868D03*
Y1264254D03*
G54D70*
X39062Y1200716D03*
X41424D03*
Y1210952D03*
X417631Y881916D03*
X415269Y871680D03*
Y881916D03*
X431394Y627843D03*
X433756Y638079D03*
Y627843D03*
X882752Y1209719D03*
X885114Y1219955D03*
Y1209719D03*
X946729D03*
X949091Y1219955D03*
Y1209719D03*
X1790709Y1210205D03*
X1793071Y1220441D03*
Y1210205D03*
G54D181*
X742224Y1594417D03*
X749704D03*
X745964D03*
Y1604731D03*
X742224D03*
X749704D03*
G54D235*
X990699Y783295D03*
X993258D03*
X990699Y806295D03*
X993258D03*
X1006053Y783295D03*
X998376D03*
X1003494D03*
X1000935D03*
X995817D03*
X998376Y806295D03*
X995817D03*
X1000935D03*
X1006053D03*
X1003494D03*
G54D25*
X18745Y200645D03*
X25745D03*
X29424Y667294D03*
X36424D03*
X29424Y675765D03*
X36424D03*
X34410Y1220505D03*
Y1234305D03*
Y1227405D03*
Y1241205D03*
X49393Y523969D03*
X37959Y559194D03*
X44959D03*
X37959Y567194D03*
X44959D03*
X37959Y575194D03*
X44959D03*
X41410Y1220505D03*
X47750Y1221988D03*
X41410Y1234305D03*
Y1227405D03*
X47750Y1228888D03*
Y1235788D03*
X41410Y1241205D03*
X59203Y477988D03*
X66203D03*
X56393Y523969D03*
X63149Y822618D03*
X54750Y1221988D03*
Y1228888D03*
Y1235788D03*
X83998Y229621D03*
X76998D03*
X83525Y664104D03*
X70149Y822618D03*
X90525Y664104D03*
X121107Y200645D03*
X128107D03*
X179360Y229621D03*
X186360D03*
X223469Y200645D03*
X230469D03*
X242583Y669913D03*
X246583Y661113D03*
X250583Y669913D03*
X288722Y229621D03*
X281722D03*
X325831Y200645D03*
X327427Y312849D03*
X319427D03*
X323427Y321649D03*
X332831Y200645D03*
X358676Y466326D03*
X365676D03*
X372500Y494216D03*
X365500D03*
X391084Y229621D03*
X384084D03*
X392767Y408142D03*
X385767D03*
X400968Y846677D03*
X407968D03*
X398190Y1093068D03*
X405190D03*
X398184Y1085881D03*
X405184D03*
X421726Y654538D03*
Y647730D03*
X423241Y846644D03*
X416241D03*
X423241Y862644D03*
X416241D03*
X423241Y854644D03*
X416241D03*
X440090Y515536D03*
X438226Y654538D03*
Y647730D03*
X428726Y654538D03*
Y647730D03*
X439744Y1093088D03*
X447090Y515536D03*
X445226Y654538D03*
Y647730D03*
X452591Y996766D03*
X459591D03*
X446744Y1093088D03*
X475832Y200645D03*
X471770Y480801D03*
X464770D03*
X463777Y1093068D03*
X470777D03*
X482832Y200645D03*
X506479Y523969D03*
X495045Y559194D03*
X502045D03*
X495045Y567194D03*
X502045D03*
X495045Y575194D03*
X502045D03*
X505331Y1093088D03*
X505189Y1085890D03*
X516289Y477988D03*
X523289D03*
X513479Y523969D03*
X512331Y1093088D03*
X512189Y1085890D03*
X534085Y229621D03*
X541085D03*
X578194Y200645D03*
X585194D03*
X580203Y936707D03*
X587203D03*
X636447Y229621D03*
X643447D03*
X680556Y200645D03*
X687556D03*
X699669Y669913D03*
X707669D03*
X703669Y661113D03*
X745809Y229621D03*
X738809D03*
X782918Y200645D03*
X784513Y312849D03*
X776513D03*
X780513Y321649D03*
X789918Y200645D03*
X815762Y460326D03*
X822762D03*
X829586Y489216D03*
X822586D03*
X848171Y229621D03*
X841171D03*
X881093Y421483D03*
X876440Y1236491D03*
Y1229591D03*
Y1243391D03*
Y1250291D03*
X888093Y421483D03*
X891440Y1230991D03*
Y1237891D03*
X883440Y1236491D03*
Y1229591D03*
X891440Y1244791D03*
X883440Y1243391D03*
Y1250291D03*
X898440Y1230991D03*
Y1237891D03*
Y1244791D03*
X933584Y185816D03*
X940584D03*
X940417Y1229591D03*
Y1236491D03*
Y1243391D03*
Y1250291D03*
X952132Y559194D03*
X959132D03*
X952132Y567194D03*
X959132D03*
X952132Y575194D03*
X959132D03*
X962417Y1230991D03*
X955417D03*
X962417Y1237891D03*
X955417D03*
X947417Y1229591D03*
Y1236491D03*
X962417Y1244791D03*
X955417D03*
X947417Y1243391D03*
Y1250291D03*
X973376Y477988D03*
X963566Y523969D03*
X970566D03*
X976703Y842659D03*
X991171Y229621D03*
X980376Y477988D03*
X983703Y842659D03*
X998171Y229621D03*
X1021703Y843159D03*
X1014703D03*
X1021819Y933722D03*
X1035280Y200645D03*
X1042280D03*
X1028819Y933722D03*
X1100533Y229621D03*
X1093533D03*
X1137642Y200645D03*
X1144642D03*
X1156756Y669913D03*
X1164756D03*
X1160756Y661113D03*
X1202895Y229621D03*
X1195895D03*
X1233600Y312849D03*
X1237600Y321649D03*
X1240004Y200645D03*
X1247004D03*
X1241600Y312849D03*
X1279849Y466326D03*
X1272849D03*
X1286673Y494216D03*
X1279673D03*
X1298257Y229621D03*
X1299940Y408142D03*
X1305257Y229621D03*
X1306940Y408142D03*
X1312364Y1093068D03*
X1319364D03*
X1312358Y1085881D03*
X1319358D03*
X1366765Y996766D03*
X1360918Y1093088D03*
X1353918D03*
X1373765Y996766D03*
X1377951Y1093068D03*
X1384951D03*
X1390005Y200645D03*
X1397005D03*
X1409219Y559194D03*
X1416219D03*
X1409219Y567194D03*
X1416219D03*
X1409219Y575194D03*
X1416219D03*
X1430463Y477988D03*
X1420653Y523969D03*
X1427653D03*
X1426505Y1093088D03*
X1419505D03*
X1426363Y1085890D03*
X1419363D03*
X1448258Y229621D03*
X1437463Y477988D03*
X1455258Y229621D03*
X1492367Y200645D03*
X1499367D03*
X1557620Y229621D03*
X1550620D03*
X1594729Y200645D03*
X1601729D03*
X1613843Y669913D03*
X1621843D03*
X1617843Y661113D03*
X1659982Y229621D03*
X1652982D03*
X1690687Y312849D03*
X1697091Y200645D03*
X1704091D03*
X1698687Y312849D03*
X1694687Y321649D03*
X1736936Y466326D03*
X1729936D03*
X1736760Y494216D03*
X1755344Y229621D03*
X1757027Y408142D03*
X1743760Y494216D03*
X1762344Y229621D03*
X1764027Y408142D03*
X1784397Y1236977D03*
X1791397D03*
X1784397Y1230077D03*
X1791397D03*
X1784397Y1243877D03*
X1791397D03*
X1784397Y1250777D03*
X1791397D03*
X1796463Y964560D03*
X1803463D03*
X1806397Y1231477D03*
X1799397D03*
X1806397Y1238377D03*
X1799397D03*
X1806397Y1245277D03*
X1799397D03*
G54D208*
X889303Y691560D03*
X895751Y696678D03*
X889303Y694119D03*
X895751Y691560D03*
X889303Y696678D03*
X895751Y694119D03*
G54D43*
X32051Y213243D03*
X30083D03*
X28114D03*
X26146D03*
X24177D03*
X22209D03*
Y225055D03*
X24177D03*
X26146D03*
X28114D03*
X30083D03*
X32051D03*
X132445Y213243D03*
X130476D03*
X128508D03*
X126539D03*
X124571D03*
Y225055D03*
X126539D03*
X128508D03*
X130476D03*
X132445D03*
X134413Y213243D03*
Y225055D03*
X230870Y213243D03*
X228901D03*
X226933D03*
Y225055D03*
X228901D03*
X230870D03*
X236775Y213243D03*
X234807D03*
X232838D03*
Y225055D03*
X234807D03*
X236775D03*
X339137Y213243D03*
X337169D03*
X335200D03*
X333232D03*
X331263D03*
X329295D03*
Y225055D03*
X331263D03*
X333232D03*
X335200D03*
X337169D03*
X339137D03*
X389303Y383732D03*
X387335D03*
X385366D03*
X383398D03*
X381429D03*
X379461D03*
Y395544D03*
X381429D03*
X383398D03*
X385366D03*
X387335D03*
X389303D03*
X489138Y213243D03*
X487170D03*
X485201D03*
X483233D03*
X481264D03*
X479296D03*
Y225055D03*
X481264D03*
X483233D03*
X485201D03*
X487170D03*
X489138D03*
X587563Y213243D03*
X585595D03*
X583626D03*
X581658D03*
Y225055D03*
X583626D03*
X585595D03*
X587563D03*
X591500Y213243D03*
X589532D03*
Y225055D03*
X591500D03*
X684020Y213243D03*
Y225055D03*
X693862Y213243D03*
X691894D03*
X689925D03*
X687957D03*
X685988D03*
Y225055D03*
X687957D03*
X689925D03*
X691894D03*
X693862D03*
X796224Y213243D03*
X794256D03*
X792287D03*
X790319D03*
X788350D03*
X786382D03*
Y225055D03*
X788350D03*
X790319D03*
X792287D03*
X794256D03*
X796224D03*
X880692Y397073D03*
X878724D03*
X876755D03*
X874787D03*
Y408885D03*
X876755D03*
X878724D03*
X880692D03*
X884629Y397073D03*
X882661D03*
Y408885D03*
X884629D03*
X944922Y198414D03*
X942953D03*
X940985D03*
X939016D03*
X937048D03*
Y210226D03*
X939016D03*
X940985D03*
X942953D03*
X944922D03*
X946890Y198414D03*
Y210226D03*
X1042681Y213243D03*
X1040712D03*
X1038744D03*
Y225055D03*
X1040712D03*
X1042681D03*
X1048586Y213243D03*
X1046618D03*
X1044649D03*
Y225055D03*
X1046618D03*
X1048586D03*
X1150948Y213243D03*
X1148980D03*
X1147011D03*
X1145043D03*
X1143074D03*
X1141106D03*
Y225055D03*
X1143074D03*
X1145043D03*
X1147011D03*
X1148980D03*
X1150948D03*
X1253310Y213243D03*
X1251342D03*
X1249373D03*
X1247405D03*
X1245436D03*
X1243468D03*
Y225055D03*
X1245436D03*
X1247405D03*
X1249373D03*
X1251342D03*
X1253310D03*
X1301508Y383732D03*
X1299539D03*
X1297571D03*
X1295602D03*
X1293634D03*
Y395544D03*
X1295602D03*
X1297571D03*
X1299539D03*
X1301508D03*
X1303476Y383732D03*
Y395544D03*
X1399374Y213243D03*
X1397406D03*
X1395437D03*
X1393469D03*
Y225055D03*
X1395437D03*
X1397406D03*
X1399374D03*
X1403311Y213243D03*
X1401343D03*
Y225055D03*
X1403311D03*
X1497799Y213243D03*
X1495831D03*
Y225055D03*
X1497799D03*
X1505673Y213243D03*
X1503705D03*
X1501736D03*
X1499768D03*
Y225055D03*
X1501736D03*
X1503705D03*
X1505673D03*
X1608035Y213243D03*
X1606067D03*
X1604098D03*
X1602130D03*
X1600161D03*
X1598193D03*
Y225055D03*
X1600161D03*
X1602130D03*
X1604098D03*
X1606067D03*
X1608035D03*
X1708429Y213243D03*
X1706460D03*
X1704492D03*
X1702523D03*
X1700555D03*
Y225055D03*
X1702523D03*
X1704492D03*
X1706460D03*
X1708429D03*
X1710397Y213243D03*
Y225055D03*
X1756626Y383732D03*
X1754658D03*
X1752689D03*
X1750721D03*
Y395544D03*
X1752689D03*
X1754658D03*
X1756626D03*
X1760563Y383732D03*
X1758595D03*
Y395544D03*
X1760563D03*
G54D217*
X938357Y798194D03*
X943475D03*
X938357Y804886D03*
X943475D03*
G54D61*
X51160Y613799D03*
X49192D03*
X47224D03*
X45255D03*
X43286D03*
X41318D03*
X51160Y624823D03*
X47224D03*
X49192D03*
X43286D03*
X45255D03*
X41318D03*
X57066Y613799D03*
X55098D03*
X53129D03*
X55098Y624823D03*
X53129D03*
X425641Y449550D03*
X421705D03*
X506278Y613799D03*
X504310D03*
X502341D03*
X500372D03*
X498404D03*
X504310Y624823D03*
X506278D03*
X500372D03*
X502341D03*
X498404D03*
X514152Y613799D03*
X512184D03*
X510215D03*
X508246D03*
Y624823D03*
X512184D03*
X510215D03*
X920967Y465891D03*
X917031D03*
X961397Y613799D03*
X959428D03*
X957459D03*
X955491D03*
X961397Y624823D03*
X957459D03*
X959428D03*
X955491D03*
X971239Y613799D03*
X969271D03*
X967302D03*
X965333D03*
X963365D03*
X965333Y624823D03*
X969271D03*
X963365D03*
X967302D03*
X1339814Y449550D03*
X1335878D03*
X1416515Y613799D03*
X1414546D03*
X1412578D03*
X1414546Y624823D03*
X1416515D03*
X1412578D03*
X1428326Y613799D03*
X1426358D03*
X1424389D03*
X1422420D03*
X1420452D03*
X1418484D03*
X1422420Y624823D03*
X1418484D03*
X1426358D03*
X1420452D03*
X1424389D03*
X1796901Y449550D03*
X1792965D03*
G54D145*
X423673Y439314D03*
Y435770D03*
Y446400D03*
Y442857D03*
X918999Y455655D03*
Y452111D03*
Y462741D03*
Y459198D03*
X1337846Y439314D03*
Y435770D03*
Y446400D03*
Y442857D03*
X1794933Y439314D03*
Y435770D03*
Y446400D03*
Y442857D03*
G54D172*
X656650Y694797D03*
X659209D03*
X656650Y702277D03*
X661768D03*
X659209D03*
X661768Y694797D03*
X781059Y1605740D03*
X778500D03*
X781059Y1598260D03*
X775941D03*
X778500D03*
X775941Y1605740D03*
X1113737Y694797D03*
X1116296D03*
X1113737Y702277D03*
X1118855D03*
X1116296D03*
X1118855Y694797D03*
X1570824D03*
X1573383D03*
X1570824Y702277D03*
X1575942D03*
X1573383D03*
X1575942Y694797D03*
G54D34*
X17874Y1041679D03*
X26360D03*
X48093D03*
X39607D03*
X440077Y1234726D03*
X448563D03*
X478786D03*
X487272D03*
X864564Y1050682D03*
X873050D03*
X894783D03*
X886297D03*
X928541D03*
X937027D03*
X958760D03*
X950274D03*
X1362737Y1234726D03*
X1354251D03*
X1392960D03*
X1401446D03*
X1772521Y1051168D03*
X1781007D03*
X1802740D03*
X1794254D03*
G54D253*
X1796437Y818780D03*
Y826457D03*
Y829016D03*
Y821339D03*
Y823898D03*
G54D244*
X1030635Y824546D03*
G54D136*
X413469Y1183065D03*
Y1208261D03*
X439639Y896653D03*
Y921849D03*
X440399Y1183065D03*
Y1208261D03*
X486671Y1183065D03*
Y1208261D03*
X513601Y1183065D03*
Y1208261D03*
X1327643Y1183065D03*
Y1208261D03*
X1354573Y1183065D03*
Y1208261D03*
X1400845Y1183065D03*
Y1208261D03*
X1427775Y1183065D03*
Y1208261D03*
G54D127*
X405466Y673038D03*
X426726D03*
X443226D03*
X464486D03*
G54D109*
X148818Y1075196D03*
Y1078936D03*
X145078D03*
X148818Y1086417D03*
X145078D03*
X148818Y1090157D03*
X145078D03*
X148818Y1082677D03*
X145078D03*
X148818Y1093897D03*
X145078D03*
X148818Y1097637D03*
X145078D03*
X148818Y1105117D03*
X145078D03*
X148818Y1101377D03*
X145078D03*
X148818Y1112598D03*
X145078D03*
X148818Y1120078D03*
X145078D03*
X148818Y1108858D03*
Y1116338D03*
Y1123818D03*
X145078Y1108858D03*
Y1116338D03*
Y1123818D03*
X148818Y1127558D03*
X145078D03*
X148818Y1135039D03*
X145078D03*
X148818Y1131299D03*
Y1138779D03*
X145078Y1131299D03*
Y1138779D03*
X148818Y1142519D03*
X145078D03*
X148818Y1146259D03*
X145078D03*
X148818Y1153740D03*
X145078D03*
X148818Y1149999D03*
X145078D03*
X148818Y1161220D03*
X145078D03*
X148818Y1168700D03*
X145078D03*
X148818Y1157480D03*
X145078D03*
X148818Y1164960D03*
X145078D03*
X148818Y1172440D03*
X145078D03*
X148818Y1183661D03*
X145078D03*
X148818Y1187401D03*
X145078D03*
X148818Y1176180D03*
X145078D03*
X148818Y1179921D03*
X145078D03*
X148818Y1194881D03*
X145078D03*
X148818Y1202362D03*
X145078D03*
X148818Y1198621D03*
Y1191141D03*
X145078Y1198621D03*
Y1191141D03*
X148818Y1209842D03*
X145078D03*
X148818Y1217322D03*
X145078D03*
X148818Y1221062D03*
Y1213582D03*
Y1206102D03*
X145078Y1221062D03*
Y1213582D03*
Y1206102D03*
X148818Y1224803D03*
X145078D03*
X148818Y1232283D03*
X145078D03*
X148818Y1236023D03*
X145078D03*
X148818Y1228543D03*
X145078D03*
X148818Y1243503D03*
X145078D03*
X148818Y1250984D03*
X145078D03*
X148818Y1239763D03*
X145078D03*
X148818Y1247243D03*
X145078D03*
X148818Y1254724D03*
X163779Y1075196D03*
X156299D03*
X160039D03*
X152559D03*
X163779Y1078936D03*
X156299D03*
X160039Y1082677D03*
X152559D03*
X160039Y1086417D03*
X152559D03*
X163779Y1090157D03*
X160039D03*
X156299D03*
X152559D03*
X163779Y1086417D03*
X160039Y1078936D03*
X156299Y1086417D03*
X152559Y1078936D03*
X163779Y1082677D03*
X156299D03*
X163779Y1093897D03*
X156299D03*
X163779Y1097637D03*
X156299D03*
X160039Y1101377D03*
X152559D03*
X160039Y1105117D03*
X152559D03*
X163779D03*
X160039Y1097637D03*
X156299Y1105117D03*
X152559Y1097637D03*
X163779Y1101377D03*
X160039Y1093897D03*
X156299Y1101377D03*
X152559Y1093897D03*
X163779Y1108858D03*
X160039D03*
X156299D03*
X152559D03*
X160039Y1112598D03*
X163779Y1116338D03*
X160039D03*
X156299D03*
X152559D03*
X160039Y1120078D03*
X163779Y1123818D03*
X160039D03*
X156299D03*
X152559D03*
X163779Y1112598D03*
Y1120078D03*
X156299Y1112598D03*
Y1120078D03*
X152559Y1112598D03*
Y1120078D03*
X160039Y1127558D03*
X163779Y1131299D03*
X160039D03*
X156299D03*
X152559D03*
X160039Y1135039D03*
X163779Y1138779D03*
X160039D03*
X156299D03*
X152559D03*
X163779Y1127558D03*
Y1135039D03*
X156299Y1127558D03*
Y1135039D03*
X152559Y1127558D03*
Y1135039D03*
X163779Y1142519D03*
X160039D03*
X156299D03*
X152559D03*
X163779Y1146259D03*
X152559D03*
X163779Y1149999D03*
X160039D03*
X156299D03*
X152559D03*
X163779Y1153740D03*
X152559D03*
X156299Y1146259D03*
X160039D03*
Y1153740D03*
X156299D03*
X163779Y1157480D03*
X160039D03*
X156299D03*
X152559D03*
X163779Y1161220D03*
X152559D03*
X163779Y1164960D03*
X160039D03*
X156299D03*
X152559D03*
X163779Y1168700D03*
X152559D03*
X163779Y1172440D03*
X160039D03*
X156299D03*
X152559D03*
X160039Y1161220D03*
X156299D03*
X160039Y1168700D03*
X156299D03*
X163779Y1183661D03*
X160039D03*
X156299D03*
X152559D03*
X160039Y1187401D03*
X163779Y1176180D03*
X152559D03*
X163779Y1179921D03*
X160039D03*
X156299D03*
X152559D03*
X160039Y1176180D03*
X156299D03*
X163779Y1187401D03*
X156299D03*
X152559D03*
X163779Y1191141D03*
X160039D03*
X156299D03*
X152559D03*
X160039Y1194881D03*
X163779Y1198621D03*
X160039D03*
X156299D03*
X152559D03*
X160039Y1202362D03*
X163779D03*
Y1194881D03*
X156299Y1202362D03*
Y1194881D03*
X152559Y1202362D03*
Y1194881D03*
X163779Y1206102D03*
X160039D03*
X156299D03*
X152559D03*
X160039Y1209842D03*
X163779Y1213582D03*
X160039D03*
X156299D03*
X152559D03*
X160039Y1217322D03*
X163779Y1221062D03*
X160039D03*
X156299D03*
X152559D03*
X163779Y1217322D03*
Y1209842D03*
X156299Y1217322D03*
Y1209842D03*
X152559Y1217322D03*
Y1209842D03*
X160039Y1224803D03*
X152559D03*
X160039Y1228543D03*
X152559D03*
X163779Y1232283D03*
X156299D03*
X163779Y1236023D03*
X156299D03*
X163779Y1224803D03*
X160039Y1232283D03*
X156299Y1224803D03*
X152559Y1232283D03*
X163779Y1228543D03*
X160039Y1236023D03*
X156299Y1228543D03*
X152559Y1236023D03*
X163779Y1239763D03*
X160039D03*
X156299D03*
X152559D03*
X160039Y1243503D03*
X152559D03*
X160039Y1247243D03*
X152559D03*
X163779Y1250984D03*
X156299D03*
X163779Y1243503D03*
X160039Y1250984D03*
X156299Y1243503D03*
X152559Y1250984D03*
X163779Y1247243D03*
X156299D03*
X163779Y1254724D03*
X156299D03*
X160039D03*
X152559D03*
X171259Y1075196D03*
X178740D03*
X167519D03*
X174999D03*
X182480D03*
X171259Y1078936D03*
X178740D03*
X174999Y1082677D03*
X167519D03*
X182480D03*
X174999Y1086417D03*
X167519D03*
X182480D03*
X174999Y1090157D03*
X171259D03*
X167519D03*
X182480D03*
X178740D03*
X171259Y1086417D03*
X167519Y1078936D03*
X171259Y1082677D03*
X174999Y1078936D03*
X178740Y1086417D03*
X182480Y1078936D03*
X178740Y1082677D03*
X171259Y1093897D03*
X178740D03*
X171259Y1097637D03*
X178740D03*
X174999Y1101377D03*
X167519D03*
X182480D03*
X174999Y1105117D03*
X167519D03*
X182480D03*
X171259D03*
X167519Y1097637D03*
X171259Y1101377D03*
X167519Y1093897D03*
X174999Y1097637D03*
X178740Y1105117D03*
X182480Y1097637D03*
X174999Y1093897D03*
X178740Y1101377D03*
X182480Y1093897D03*
X174999Y1108858D03*
X171259D03*
X167519D03*
X182480D03*
X178740D03*
X174999Y1112598D03*
X171259D03*
X182480D03*
X178740D03*
X167519Y1116338D03*
X182480D03*
X178740D03*
X174999Y1120078D03*
X171259D03*
X182480D03*
X178740D03*
X167519Y1123818D03*
X182480D03*
X178740D03*
X167519Y1112598D03*
X174999Y1116338D03*
X167519Y1120078D03*
X174999Y1123818D03*
X171259Y1116338D03*
Y1123818D03*
X174999Y1127558D03*
X171259D03*
X182480D03*
X178740D03*
X167519Y1131299D03*
X182480D03*
X178740D03*
X174999Y1135039D03*
X171259D03*
X182480D03*
X178740D03*
X167519Y1138779D03*
X182480D03*
X178740D03*
X167519Y1127558D03*
X174999Y1131299D03*
X167519Y1135039D03*
X174999Y1138779D03*
X171259Y1131299D03*
Y1138779D03*
X174999Y1142519D03*
X171259D03*
X167519D03*
X182480D03*
X178740D03*
X174999Y1146259D03*
X171259D03*
X182480D03*
X174999Y1149999D03*
X182480D03*
X174999Y1153740D03*
X182480D03*
X178740Y1146259D03*
Y1149999D03*
Y1153740D03*
X171259D03*
X167519Y1149999D03*
X171259D03*
X167519Y1146259D03*
Y1153740D03*
X174999Y1157480D03*
X182480D03*
X178740D03*
X174999Y1161220D03*
X182480D03*
X174999Y1164960D03*
X182480D03*
X174999Y1168700D03*
X182480D03*
X178740D03*
X174999Y1172440D03*
X182480D03*
X178740D03*
Y1161220D03*
Y1164960D03*
X171259D03*
Y1172440D03*
Y1168700D03*
X167519Y1172440D03*
Y1168700D03*
Y1164960D03*
X171259Y1157480D03*
Y1161220D03*
X167519D03*
Y1157480D03*
X174999Y1183661D03*
X171259D03*
X167519D03*
X182480D03*
X178740D03*
X174999Y1187401D03*
X171259D03*
X182480D03*
X178740D03*
X174999Y1176180D03*
X182480D03*
X174999Y1179921D03*
X171259D03*
X167519D03*
X182480D03*
X178740Y1176180D03*
Y1179921D03*
X167519Y1176180D03*
X171259D03*
X167519Y1187401D03*
Y1191141D03*
X182480D03*
X178740D03*
X174999Y1194881D03*
X171259D03*
X182480D03*
X178740D03*
X167519Y1198621D03*
X182480D03*
X178740D03*
X174999Y1202362D03*
X171259D03*
X182480D03*
X178740D03*
X167519D03*
X174999Y1198621D03*
X167519Y1194881D03*
X174999Y1191141D03*
X171259Y1198621D03*
Y1191141D03*
X167519Y1206102D03*
X182480D03*
X178740D03*
X174999Y1209842D03*
X171259D03*
X182480D03*
X178740D03*
X167519Y1213582D03*
X182480D03*
X178740D03*
X174999Y1217322D03*
X171259D03*
X182480D03*
X178740D03*
X174999Y1221062D03*
X171259D03*
X167519D03*
X182480D03*
X178740D03*
X167519Y1217322D03*
X174999Y1213582D03*
X167519Y1209842D03*
X174999Y1206102D03*
X171259Y1213582D03*
Y1206102D03*
X174999Y1224803D03*
X167519D03*
X182480D03*
X174999Y1228543D03*
X167519D03*
X182480D03*
X171259Y1232283D03*
X178740D03*
X171259Y1236023D03*
X178740D03*
X167519Y1232283D03*
Y1236023D03*
X171259Y1224803D03*
X174999Y1232283D03*
X178740Y1224803D03*
X182480Y1232283D03*
X171259Y1228543D03*
X174999Y1236023D03*
X178740Y1228543D03*
X182480Y1236023D03*
X174999Y1239763D03*
X171259D03*
X167519D03*
X182480D03*
X178740D03*
X174999Y1243503D03*
X167519D03*
X182480D03*
X174999Y1247243D03*
X167519D03*
X182480D03*
X171259Y1250984D03*
X178740D03*
X167519D03*
X171259Y1243503D03*
X174999Y1250984D03*
X178740Y1243503D03*
X182480Y1250984D03*
X171259Y1247243D03*
X178740D03*
X171259Y1254724D03*
X178740D03*
X167519D03*
X174999D03*
X182480D03*
X193700Y1075196D03*
X186220D03*
X189960D03*
X197440D03*
X193700Y1078936D03*
X186220D03*
X197440Y1082677D03*
X189960D03*
X197440Y1086417D03*
X189960D03*
X197440Y1090157D03*
X193700D03*
X189960D03*
X186220D03*
Y1086417D03*
X189960Y1078936D03*
X193700Y1086417D03*
X197440Y1078936D03*
X186220Y1082677D03*
X193700D03*
Y1093897D03*
X186220D03*
X193700Y1097637D03*
X186220D03*
X197440Y1101377D03*
X189960D03*
X197440Y1105117D03*
X189960D03*
X186220D03*
X189960Y1097637D03*
X193700Y1105117D03*
X197440Y1097637D03*
X186220Y1101377D03*
X189960Y1093897D03*
X193700Y1101377D03*
X197440Y1093897D03*
Y1108858D03*
X193700D03*
X189960D03*
X186220D03*
X197440Y1120078D03*
X193700D03*
X189960D03*
X186220D03*
X197440Y1123818D03*
X193700D03*
X189960D03*
X186220D03*
X189960Y1116338D03*
X186220D03*
Y1112598D03*
X189960D03*
X193700Y1116338D03*
Y1112598D03*
X197440Y1116338D03*
Y1112598D03*
Y1127558D03*
X193700D03*
X189960D03*
X186220D03*
X197440Y1131299D03*
X189960D03*
X186220D03*
X197440Y1135039D03*
X189960D03*
X186220D03*
X197440Y1138779D03*
X189960D03*
X186220D03*
X193700D03*
Y1131299D03*
Y1135039D03*
X186220Y1149999D03*
X189960Y1153740D03*
Y1142519D03*
X186220D03*
X197440Y1146259D03*
X189960D03*
X193700Y1149999D03*
X197440Y1153740D03*
X193700Y1142519D03*
X197440D03*
X186220Y1146259D03*
X189960Y1149999D03*
X186220Y1153740D03*
X193700Y1146259D03*
X197440Y1149999D03*
X193700Y1153740D03*
X186220Y1157480D03*
X189960Y1161220D03*
X186220Y1164960D03*
X189960Y1168700D03*
X186220Y1172440D03*
X193700Y1157480D03*
X197440Y1161220D03*
X193700Y1164960D03*
X197440Y1168700D03*
X193700Y1172440D03*
X189960D03*
Y1157480D03*
X186220Y1161220D03*
X189960Y1164960D03*
X186220Y1168700D03*
X197440Y1157480D03*
X193700Y1161220D03*
X197440Y1164960D03*
X193700Y1168700D03*
X197440Y1172440D03*
X189960Y1176180D03*
X186220Y1179921D03*
X197440Y1183661D03*
X189960D03*
X197440Y1187401D03*
X193700D03*
X189960D03*
X186220D03*
X197440Y1176180D03*
X193700Y1179921D03*
X186220Y1183661D03*
Y1176180D03*
X189960Y1179921D03*
X193700Y1183661D03*
Y1176180D03*
X197440Y1179921D03*
Y1191141D03*
X189960D03*
X186220D03*
X197440Y1194881D03*
X189960D03*
X186220D03*
X197440Y1198621D03*
X189960D03*
X186220D03*
X197440Y1202362D03*
X193700D03*
X189960D03*
X186220D03*
X193700Y1191141D03*
Y1198621D03*
Y1194881D03*
X197440Y1206102D03*
X193700D03*
X189960D03*
X186220D03*
X197440Y1209842D03*
X193700D03*
X189960D03*
X186220D03*
X193700Y1213582D03*
X186220D03*
X193700Y1217322D03*
X197440Y1221062D03*
X193700D03*
X189960D03*
X186220D03*
X189960Y1217322D03*
X186220D03*
X197440Y1213582D03*
Y1217322D03*
X189960Y1213582D03*
X197440Y1224803D03*
X189960D03*
X197440Y1228543D03*
X189960D03*
X193700Y1232283D03*
X186220D03*
X193700Y1236023D03*
X186220D03*
Y1224803D03*
X189960Y1232283D03*
X193700Y1224803D03*
X197440Y1232283D03*
X186220Y1228543D03*
X189960Y1236023D03*
X193700Y1228543D03*
X197440Y1236023D03*
Y1239763D03*
X193700D03*
X189960D03*
X186220D03*
X197440Y1243503D03*
X189960D03*
X197440Y1247243D03*
X189960D03*
X193700Y1250984D03*
X186220D03*
Y1243503D03*
X189960Y1250984D03*
X193700Y1243503D03*
X197440Y1250984D03*
X186220Y1247243D03*
X193700D03*
Y1254724D03*
X186220D03*
X189960D03*
X197440D03*
X208661Y1075196D03*
X201181D03*
X204921D03*
X212401D03*
X208661Y1078936D03*
X201181D03*
X212401Y1082677D03*
X204921D03*
X212401Y1086417D03*
X204921D03*
X212401Y1090157D03*
X208661D03*
X204921D03*
X201181D03*
Y1086417D03*
X204921Y1078936D03*
X208661Y1086417D03*
X212401Y1078936D03*
X201181Y1082677D03*
X208661D03*
Y1093897D03*
X201181D03*
X208661Y1097637D03*
X201181D03*
X212401Y1101377D03*
X204921D03*
X212401Y1105117D03*
X204921D03*
X201181D03*
X204921Y1097637D03*
X208661Y1105117D03*
X212401Y1097637D03*
X201181Y1101377D03*
X204921Y1093897D03*
X208661Y1101377D03*
X212401Y1093897D03*
Y1108858D03*
X208661D03*
X204921D03*
X201181D03*
X212401Y1120078D03*
X208661D03*
X204921D03*
X201181D03*
X212401Y1123818D03*
X208661D03*
X204921D03*
X201181D03*
Y1112598D03*
X204921Y1116338D03*
X201181D03*
X204921Y1112598D03*
X208661Y1116338D03*
Y1112598D03*
X212401Y1116338D03*
Y1112598D03*
Y1127558D03*
X208661D03*
X204921D03*
X201181D03*
X212401Y1135039D03*
X208661D03*
X204921D03*
X201181D03*
X212401Y1131299D03*
X208661D03*
X204921D03*
X201181D03*
X212401Y1138779D03*
X208661D03*
X204921D03*
X201181D03*
X212401Y1142519D03*
X208661D03*
X204921D03*
X201181D03*
X212401Y1149999D03*
X208661D03*
X204921D03*
X201181D03*
X212401Y1146259D03*
X208661D03*
X204921D03*
X201181D03*
X212401Y1153740D03*
X208661D03*
X204921D03*
X201181D03*
X208661Y1157480D03*
X201181D03*
X212401Y1161220D03*
X204921D03*
X208661Y1164960D03*
X201181D03*
X212401Y1168700D03*
X204921D03*
X208661Y1172440D03*
X201181D03*
X212401Y1157480D03*
X204921D03*
X208661Y1161220D03*
X201181D03*
X212401Y1164960D03*
X204921D03*
X208661Y1168700D03*
X201181D03*
X212401Y1172440D03*
X204921D03*
X212401Y1187401D03*
X208661D03*
X204921D03*
X201181D03*
X212401Y1179921D03*
X208661D03*
X204921D03*
X201181D03*
X212401Y1183661D03*
X208661D03*
X204921D03*
X201181D03*
X212401Y1176180D03*
X208661D03*
X204921D03*
X201181D03*
X212401Y1194881D03*
X208661D03*
X204921D03*
X201181D03*
X212401Y1202362D03*
X208661D03*
X204921D03*
X201181D03*
X212401Y1198621D03*
X208661D03*
X204921D03*
X201181D03*
X212401Y1191141D03*
X208661D03*
X204921D03*
X201181D03*
X212401Y1206102D03*
X208661D03*
X204921D03*
X201181D03*
X212401Y1209842D03*
X208661D03*
X204921D03*
X201181D03*
X212401Y1221062D03*
X208661D03*
X204921D03*
X201181D03*
X204921Y1213582D03*
X201181D03*
X212401D03*
X208661Y1217322D03*
Y1213582D03*
X212401Y1217322D03*
X204921D03*
X201181D03*
X212401Y1224803D03*
X204921D03*
X212401Y1228543D03*
X204921D03*
X208661Y1232283D03*
X201181D03*
X208661Y1236023D03*
X201181D03*
Y1224803D03*
X204921Y1232283D03*
X208661Y1224803D03*
X212401Y1232283D03*
X201181Y1228543D03*
X204921Y1236023D03*
X208661Y1228543D03*
X212401Y1236023D03*
Y1239763D03*
X208661D03*
X204921D03*
X201181D03*
X212401Y1243503D03*
X204921D03*
X212401Y1247243D03*
X204921D03*
X208661Y1250984D03*
X201181D03*
Y1243503D03*
X204921Y1250984D03*
X208661Y1243503D03*
X212401Y1250984D03*
X201181Y1247243D03*
X208661D03*
Y1254724D03*
X201181D03*
X204921D03*
X212401D03*
X231102Y1075196D03*
X223622D03*
X216141D03*
X219881D03*
X227362D03*
X231102Y1078936D03*
X223622D03*
X216141D03*
X227362Y1082677D03*
X219881D03*
X227362Y1086417D03*
X219881D03*
X231102Y1090157D03*
X227362D03*
X223622D03*
X219881D03*
X216141D03*
Y1086417D03*
X219881Y1078936D03*
X223622Y1086417D03*
X227362Y1078936D03*
X231102Y1086417D03*
X216141Y1082677D03*
X223622D03*
X231102D03*
Y1093897D03*
X223622D03*
X216141D03*
X231102Y1097637D03*
X223622D03*
X216141D03*
X227362Y1101377D03*
X219881D03*
X227362Y1105117D03*
X219881D03*
X216141D03*
X219881Y1097637D03*
X223622Y1105117D03*
X227362Y1097637D03*
X231102Y1105117D03*
X216141Y1101377D03*
X219881Y1093897D03*
X223622Y1101377D03*
X227362Y1093897D03*
X231102Y1101377D03*
Y1108858D03*
X227362D03*
X223622D03*
X219881D03*
X216141D03*
X231102Y1112598D03*
X216141D03*
X231102Y1116338D03*
X216141D03*
X231102Y1120078D03*
X227362D03*
X223622D03*
X219881D03*
X216141D03*
X231102Y1123818D03*
X227362D03*
X223622D03*
X219881D03*
X216141D03*
X227362Y1116338D03*
X223622Y1112598D03*
Y1116338D03*
X219881D03*
Y1112598D03*
X227362D03*
X231102Y1127558D03*
X227362D03*
X223622D03*
X219881D03*
X216141D03*
X231102Y1135039D03*
X227362D03*
X223622D03*
X219881D03*
X216141D03*
X231102Y1131299D03*
X227362D03*
X223622D03*
X219881D03*
X216141D03*
X231102Y1138779D03*
X227362D03*
X223622D03*
X219881D03*
X216141D03*
X231102Y1142519D03*
X227362D03*
X223622D03*
X219881D03*
X216141D03*
X231102Y1149999D03*
X227362D03*
X223622D03*
X219881D03*
X216141D03*
X231102Y1146259D03*
X227362D03*
X223622D03*
X219881D03*
X216141D03*
X231102Y1153740D03*
X227362D03*
X223622D03*
X219881D03*
X216141D03*
X231102Y1157480D03*
X223622D03*
X216141D03*
X227362Y1161220D03*
X219881D03*
X231102Y1164960D03*
X223622D03*
X216141D03*
X227362Y1168700D03*
X219881D03*
X231102Y1172440D03*
X223622D03*
X216141D03*
X227362Y1157480D03*
X219881D03*
X231102Y1161220D03*
X223622D03*
X216141D03*
X227362Y1164960D03*
X219881D03*
X231102Y1168700D03*
X223622D03*
X216141D03*
X227362Y1172440D03*
X219881D03*
X231102Y1187401D03*
X227362D03*
X223622D03*
X219881D03*
X216141D03*
X231102Y1179921D03*
X227362D03*
X223622D03*
X219881D03*
X216141D03*
X231102Y1183661D03*
X227362D03*
X223622D03*
X219881D03*
X216141D03*
X231102Y1176180D03*
X227362D03*
X223622D03*
X219881D03*
X216141D03*
X231102Y1194881D03*
X227362D03*
X223622D03*
X219881D03*
X216141D03*
X231102Y1202362D03*
X227362D03*
X223622D03*
X219881D03*
X216141D03*
X231102Y1198621D03*
X227362D03*
X223622D03*
X219881D03*
X216141D03*
X231102Y1191141D03*
X227362D03*
X223622D03*
X219881D03*
X216141D03*
X231102Y1206102D03*
X227362D03*
X223622D03*
X219881D03*
X216141D03*
X231102Y1209842D03*
X227362D03*
X223622D03*
X219881D03*
X216141D03*
X219881Y1213582D03*
Y1217322D03*
X231102Y1221062D03*
X227362D03*
X223622D03*
X219881D03*
X216141D03*
X231102Y1213582D03*
X227362Y1217322D03*
Y1213582D03*
X223622D03*
Y1217322D03*
X231102D03*
X216141D03*
Y1213582D03*
X227362Y1224803D03*
X219881D03*
X227362Y1228543D03*
X219881D03*
X231102Y1232283D03*
X223622D03*
X216141D03*
X231102Y1236023D03*
X223622D03*
X216141D03*
Y1224803D03*
X219881Y1232283D03*
X223622Y1224803D03*
X227362Y1232283D03*
X216141Y1228543D03*
X219881Y1236023D03*
X223622Y1228543D03*
X227362Y1236023D03*
X231102Y1224803D03*
Y1228543D03*
Y1239763D03*
X227362D03*
X223622D03*
X219881D03*
X216141D03*
X227362Y1243503D03*
X219881D03*
X227362Y1247243D03*
X219881D03*
X231102Y1250984D03*
X223622D03*
X216141D03*
Y1243503D03*
X219881Y1250984D03*
X223622Y1243503D03*
X227362Y1250984D03*
X216141Y1247243D03*
X223622D03*
X231102Y1243503D03*
Y1247243D03*
Y1254724D03*
X223622D03*
X216141D03*
X219881D03*
X227362D03*
X246062Y1075196D03*
X238582D03*
X242322D03*
X234842D03*
X246062Y1078936D03*
X238582D03*
X242322Y1082677D03*
X234842D03*
X242322Y1086417D03*
X234842D03*
X246062Y1090157D03*
X242322D03*
X238582D03*
X234842D03*
X246062Y1086417D03*
X242322Y1078936D03*
X238582Y1086417D03*
X234842Y1078936D03*
X246062Y1082677D03*
X238582D03*
X246062Y1093897D03*
X238582D03*
X246062Y1097637D03*
X238582D03*
X242322Y1101377D03*
X234842D03*
X242322Y1105117D03*
X234842D03*
X246062D03*
X242322Y1097637D03*
X238582Y1105117D03*
X234842Y1097637D03*
X246062Y1101377D03*
X242322Y1093897D03*
X238582Y1101377D03*
X234842Y1093897D03*
X246062Y1108858D03*
X242322D03*
X238582D03*
X234842D03*
X246062Y1120078D03*
X242322D03*
X238582D03*
X234842D03*
X246062Y1123818D03*
X242322D03*
X238582D03*
X234842D03*
X246062Y1116338D03*
X238582D03*
X234842Y1112598D03*
X246062D03*
X242322Y1116338D03*
X234842D03*
X242322Y1112598D03*
X238582D03*
X246062Y1127558D03*
X242322D03*
X238582D03*
X234842D03*
X246062Y1135039D03*
X242322D03*
X238582D03*
X234842D03*
X246062Y1131299D03*
X242322D03*
X238582D03*
X234842D03*
X246062Y1138779D03*
X242322D03*
X238582D03*
X234842D03*
X246062Y1142519D03*
X242322D03*
X238582D03*
X234842D03*
X246062Y1149999D03*
X242322D03*
X238582D03*
X234842D03*
X246062Y1146259D03*
X242322D03*
X238582D03*
X234842D03*
X246062Y1153740D03*
X242322D03*
X238582D03*
X234842D03*
X246062Y1157480D03*
X238582D03*
X242322Y1161220D03*
X234842D03*
X246062Y1164960D03*
X238582D03*
X242322Y1168700D03*
X234842D03*
X246062Y1172440D03*
X238582D03*
X242322Y1157480D03*
X234842D03*
X246062Y1161220D03*
X238582D03*
X242322Y1164960D03*
X234842D03*
X246062Y1168700D03*
X238582D03*
X242322Y1172440D03*
X234842D03*
X246062Y1187401D03*
X242322D03*
X238582D03*
X234842D03*
X246062Y1179921D03*
X242322D03*
X238582D03*
X234842D03*
X246062Y1183661D03*
X242322D03*
X238582D03*
X234842D03*
X246062Y1176180D03*
X242322D03*
X238582D03*
X234842D03*
X246062Y1194881D03*
X242322D03*
X238582D03*
X234842D03*
X246062Y1202362D03*
X242322D03*
X238582D03*
X234842D03*
X246062Y1198621D03*
X242322D03*
X238582D03*
X234842D03*
X246062Y1191141D03*
X242322D03*
X238582D03*
X234842D03*
X246062Y1206102D03*
X242322D03*
X238582D03*
X234842D03*
X246062Y1209842D03*
X242322D03*
X238582D03*
X234842D03*
X246062Y1221062D03*
X242322D03*
X238582D03*
X234842D03*
X238582Y1217322D03*
X246062Y1213582D03*
X242322D03*
X246062Y1217322D03*
X234842D03*
Y1213582D03*
X242322Y1217322D03*
X238582Y1213582D03*
X242322Y1224803D03*
X234842D03*
X242322Y1228543D03*
X234842D03*
X246062Y1232283D03*
X238582D03*
X246062Y1236023D03*
X238582D03*
X246062Y1224803D03*
X242322Y1232283D03*
X238582Y1224803D03*
X234842Y1232283D03*
X246062Y1228543D03*
X242322Y1236023D03*
X238582Y1228543D03*
X234842Y1236023D03*
X246062Y1239763D03*
X242322D03*
X238582D03*
X234842D03*
X242322Y1243503D03*
X234842D03*
X242322Y1247243D03*
X234842D03*
X246062Y1250984D03*
X238582D03*
X246062Y1243503D03*
X242322Y1250984D03*
X238582Y1243503D03*
X234842Y1250984D03*
X246062Y1247243D03*
X238582D03*
X246062Y1254724D03*
X238582D03*
X242322D03*
X234842D03*
X261023Y1075196D03*
X253543D03*
X257283D03*
X249803D03*
X261023Y1078936D03*
X253543D03*
X257283Y1082677D03*
X249803D03*
X257283Y1086417D03*
X249803D03*
X261023Y1090157D03*
X257283D03*
X253543D03*
X249803D03*
X261023Y1086417D03*
X257283Y1078936D03*
X253543Y1086417D03*
X249803Y1078936D03*
X261023Y1082677D03*
X253543D03*
X261023Y1093897D03*
X253543D03*
X261023Y1097637D03*
X253543D03*
X257283Y1101377D03*
X249803D03*
X257283Y1105117D03*
X249803D03*
X261023D03*
X257283Y1097637D03*
X253543Y1105117D03*
X249803Y1097637D03*
X261023Y1101377D03*
X257283Y1093897D03*
X253543Y1101377D03*
X249803Y1093897D03*
X261023Y1108858D03*
X257283D03*
X253543D03*
X249803D03*
X261023Y1120078D03*
X257283D03*
X253543D03*
X249803D03*
X261023Y1123818D03*
X257283D03*
X253543D03*
X249803D03*
X253543Y1116338D03*
X249803D03*
Y1112598D03*
X257283Y1116338D03*
X261023Y1112598D03*
X257283D03*
X261023Y1116338D03*
X253543Y1112598D03*
X261023Y1127558D03*
X257283D03*
X253543D03*
X249803D03*
X261023Y1135039D03*
X257283D03*
X253543D03*
X249803D03*
X261023Y1131299D03*
X257283D03*
X253543D03*
X249803D03*
X261023Y1138779D03*
X257283D03*
X253543D03*
X249803D03*
X261023Y1142519D03*
X257283D03*
X253543D03*
X249803D03*
X261023Y1149999D03*
X257283D03*
X253543D03*
X249803D03*
X261023Y1146259D03*
X257283D03*
X253543D03*
X249803D03*
X261023Y1153740D03*
X257283D03*
X253543D03*
X249803D03*
X261023Y1157480D03*
X253543D03*
X257283Y1161220D03*
X249803D03*
X261023Y1164960D03*
X253543D03*
X257283Y1168700D03*
X249803D03*
X261023Y1172440D03*
X253543D03*
X261023Y1161220D03*
Y1168700D03*
X257283Y1157480D03*
X249803D03*
X253543Y1161220D03*
X257283Y1164960D03*
X249803D03*
X253543Y1168700D03*
X257283Y1172440D03*
X249803D03*
X261023Y1187401D03*
X257283D03*
X253543D03*
X249803D03*
X261023Y1179921D03*
X257283D03*
X253543D03*
X249803D03*
X261023Y1183661D03*
X257283D03*
X253543D03*
X249803D03*
X261023Y1176180D03*
X257283D03*
X253543D03*
X249803D03*
X261023Y1194881D03*
X257283D03*
X253543D03*
X249803D03*
X261023Y1202362D03*
X257283D03*
X253543D03*
X249803D03*
X261023Y1198621D03*
X257283D03*
X253543D03*
X249803D03*
X261023Y1191141D03*
X257283D03*
X253543D03*
X249803D03*
X261023Y1206102D03*
X257283D03*
X253543D03*
X249803D03*
X261023Y1209842D03*
X257283D03*
X253543D03*
X249803D03*
X261023Y1221062D03*
X257283D03*
X253543D03*
X249803D03*
Y1213582D03*
X261023D03*
X257283Y1217322D03*
X249803D03*
X257283Y1213582D03*
X253543D03*
X261023Y1217322D03*
X253543D03*
X257283Y1224803D03*
X249803D03*
X257283Y1228543D03*
X249803D03*
X261023Y1232283D03*
X253543D03*
X261023Y1236023D03*
X253543D03*
X261023Y1224803D03*
X257283Y1232283D03*
X253543Y1224803D03*
X249803Y1232283D03*
X261023Y1228543D03*
X257283Y1236023D03*
X253543Y1228543D03*
X249803Y1236023D03*
X261023Y1239763D03*
X257283D03*
X253543D03*
X249803D03*
X257283Y1243503D03*
X249803D03*
X257283Y1247243D03*
X249803D03*
X261023Y1250984D03*
X253543D03*
X261023Y1243503D03*
X257283Y1250984D03*
X253543Y1243503D03*
X249803Y1250984D03*
X261023Y1247243D03*
X253543D03*
X261023Y1254724D03*
X253543D03*
X257283D03*
X249803D03*
X275984Y1075196D03*
X268503D03*
X279724D03*
X272244D03*
X264763D03*
X275984Y1078936D03*
X268503D03*
X279724Y1082677D03*
X272244D03*
X264763D03*
X279724Y1086417D03*
X272244D03*
X264763D03*
X279724Y1090157D03*
X275984D03*
X272244D03*
X268503D03*
X264763D03*
X279724Y1078936D03*
X275984Y1086417D03*
X272244Y1078936D03*
X268503Y1086417D03*
X264763Y1078936D03*
X275984Y1082677D03*
X268503D03*
X275984Y1093897D03*
X268503D03*
X275984Y1097637D03*
X268503D03*
X279724Y1101377D03*
X272244D03*
X264763D03*
X279724Y1105117D03*
X272244D03*
X264763D03*
X279724Y1097637D03*
X275984Y1105117D03*
X272244Y1097637D03*
X268503Y1105117D03*
X264763Y1097637D03*
X279724Y1093897D03*
X275984Y1101377D03*
X272244Y1093897D03*
X268503Y1101377D03*
X264763Y1093897D03*
X279724Y1108858D03*
X275984D03*
X272244D03*
X268503D03*
X264763D03*
X279724Y1120078D03*
X275984D03*
X272244D03*
X268503D03*
X264763D03*
X279724Y1123818D03*
X272244D03*
X268503D03*
X264763D03*
X275984D03*
X279724Y1112598D03*
Y1116338D03*
X272244D03*
X275984Y1112598D03*
X264763Y1116338D03*
Y1112598D03*
X275984Y1116338D03*
X272244Y1112598D03*
X268503Y1116338D03*
Y1112598D03*
X279724Y1127558D03*
X272244D03*
X268503D03*
X264763D03*
X279724Y1131299D03*
X268503D03*
X279724Y1135039D03*
X272244D03*
X268503D03*
X264763D03*
X279724Y1138779D03*
X275984D03*
X268503D03*
X272244Y1131299D03*
Y1138779D03*
X264763Y1131299D03*
Y1138779D03*
X275984Y1127558D03*
Y1135039D03*
Y1131299D03*
X279724Y1142519D03*
X275984D03*
X268503D03*
X264763D03*
X279724Y1146259D03*
X275984D03*
X268503D03*
X279724Y1149999D03*
X275984D03*
X272244D03*
X268503D03*
X264763D03*
X279724Y1153740D03*
X275984D03*
X272244D03*
X268503D03*
X264763Y1146259D03*
Y1153740D03*
X272244Y1142519D03*
Y1146259D03*
X279724Y1157480D03*
X272244D03*
X268503D03*
X279724Y1161220D03*
X272244D03*
X279724Y1164960D03*
X272244D03*
X279724Y1168700D03*
X272244D03*
X279724Y1172440D03*
X272244D03*
X268503D03*
Y1161220D03*
X264763D03*
X268503Y1164960D03*
X264763D03*
X268503Y1168700D03*
X264763D03*
Y1157480D03*
Y1172440D03*
X275984Y1157480D03*
Y1161220D03*
Y1164960D03*
Y1168700D03*
Y1172440D03*
X279724Y1183661D03*
X275984D03*
X268503D03*
X279724Y1187401D03*
X275984D03*
X268503D03*
X264763D03*
X279724Y1176180D03*
X275984D03*
X268503D03*
X275984Y1179921D03*
X264763D03*
Y1183661D03*
Y1176180D03*
X279724Y1179921D03*
X268503D03*
X272244Y1183661D03*
Y1187401D03*
Y1179921D03*
Y1176180D03*
X279724Y1191141D03*
X275984D03*
X268503D03*
X279724Y1194881D03*
X272244D03*
X268503D03*
X264763D03*
X279724Y1198621D03*
X268503D03*
X279724Y1202362D03*
X272244D03*
X268503D03*
X264763D03*
X272244Y1198621D03*
Y1191141D03*
X264763Y1198621D03*
Y1191141D03*
X275984Y1198621D03*
Y1202362D03*
Y1194881D03*
X279724Y1206102D03*
X272244D03*
X268503D03*
X264763D03*
X279724Y1209842D03*
X275984D03*
X272244D03*
X268503D03*
X264763D03*
X279724Y1221062D03*
X275984D03*
X272244D03*
X268503D03*
X264763D03*
X275984Y1206102D03*
X268503Y1217322D03*
X275984D03*
Y1213582D03*
X279724D03*
X272244D03*
X268503D03*
X264763D03*
Y1217322D03*
X272244D03*
X279724D03*
Y1224803D03*
X272244D03*
X264763D03*
X279724Y1228543D03*
X272244D03*
X264763D03*
X275984Y1232283D03*
X268503D03*
X275984Y1236023D03*
X268503D03*
X279724Y1232283D03*
X275984Y1224803D03*
X272244Y1232283D03*
X268503Y1224803D03*
X264763Y1232283D03*
X279724Y1236023D03*
X275984Y1228543D03*
X272244Y1236023D03*
X268503Y1228543D03*
X264763Y1236023D03*
X279724Y1239763D03*
X275984D03*
X272244D03*
X268503D03*
X264763D03*
X279724Y1243503D03*
X272244D03*
X264763D03*
X279724Y1247243D03*
X272244D03*
X264763D03*
X275984Y1250984D03*
X268503D03*
X279724D03*
X275984Y1243503D03*
X272244Y1250984D03*
X268503Y1243503D03*
X264763Y1250984D03*
X275984Y1247243D03*
X268503D03*
X275984Y1254724D03*
X268503D03*
X279724D03*
X272244D03*
X264763D03*
X290944Y1075196D03*
X283464D03*
X287204D03*
X294685D03*
X290944Y1078936D03*
X283464D03*
X294685Y1082677D03*
X287204D03*
X294685Y1086417D03*
X287204D03*
X294685Y1090157D03*
X290944D03*
X287204D03*
X283464D03*
X290944Y1086417D03*
X287204Y1078936D03*
X283464Y1086417D03*
X290944Y1082677D03*
X283464D03*
X294685Y1078936D03*
X290944Y1093897D03*
X283464D03*
X290944Y1097637D03*
X283464D03*
X294685Y1101377D03*
X287204D03*
X294685Y1105117D03*
X287204D03*
X290944D03*
X287204Y1097637D03*
X283464Y1105117D03*
X290944Y1101377D03*
X287204Y1093897D03*
X283464Y1101377D03*
X294685Y1097637D03*
Y1093897D03*
Y1108858D03*
X290944D03*
X287204D03*
X283464D03*
X294685Y1112598D03*
X290944D03*
Y1116338D03*
X294685Y1120078D03*
X290944D03*
Y1123818D03*
X283464Y1120078D03*
Y1116338D03*
Y1123818D03*
X287204Y1116338D03*
Y1123818D03*
Y1120078D03*
Y1112598D03*
X283464D03*
X294685Y1116338D03*
Y1123818D03*
Y1127558D03*
X290944D03*
Y1131299D03*
X294685Y1135039D03*
X290944D03*
Y1138779D03*
X287204Y1127558D03*
Y1131299D03*
X283464Y1127558D03*
Y1131299D03*
X287204Y1138779D03*
X283464Y1135039D03*
X287204D03*
X283464Y1138779D03*
X294685D03*
Y1131299D03*
Y1142519D03*
X290944D03*
Y1146259D03*
X294685Y1149999D03*
X290944D03*
Y1153740D03*
X287204D03*
X283464D03*
Y1142519D03*
X287204Y1149999D03*
X283464D03*
Y1146259D03*
X287204Y1142519D03*
Y1146259D03*
X294685D03*
Y1153740D03*
Y1157480D03*
X290944D03*
X287204D03*
X290944Y1161220D03*
X287204D03*
X294685Y1164960D03*
X290944D03*
X287204D03*
X290944Y1168700D03*
X287204D03*
X294685Y1172440D03*
X290944D03*
X287204D03*
X283464Y1157480D03*
Y1161220D03*
Y1164960D03*
Y1168700D03*
Y1172440D03*
X294685Y1161220D03*
Y1168700D03*
X290944Y1183661D03*
X283464D03*
X294685Y1187401D03*
X290944D03*
Y1176180D03*
X287204D03*
X283464D03*
X294685Y1179921D03*
X290944D03*
X283464D03*
X287204Y1187401D03*
X283464D03*
X287204Y1179921D03*
Y1183661D03*
X294685Y1176180D03*
Y1183661D03*
X290944Y1191141D03*
X283464D03*
X294685Y1194881D03*
X290944D03*
Y1198621D03*
X294685Y1202362D03*
X290944D03*
X287204Y1191141D03*
X283464Y1194881D03*
Y1202362D03*
X287204Y1194881D03*
Y1202362D03*
Y1198621D03*
X283464D03*
X294685Y1191141D03*
Y1198621D03*
X290944Y1206102D03*
X294685Y1209842D03*
X290944D03*
Y1213582D03*
X294685Y1217322D03*
X290944D03*
X294685Y1221062D03*
X290944D03*
X287204D03*
X283464D03*
X287204Y1217322D03*
X283464Y1209842D03*
Y1213582D03*
Y1217322D03*
X287204Y1213582D03*
Y1209842D03*
X283464Y1206102D03*
X287204D03*
X294685Y1213582D03*
Y1206102D03*
Y1224803D03*
X287204D03*
X294685Y1228543D03*
X287204D03*
X290944Y1232283D03*
X283464D03*
X290944Y1236023D03*
X283464D03*
X287204Y1232283D03*
X283464Y1224803D03*
X287204Y1236023D03*
X283464Y1228543D03*
X290944Y1224803D03*
X294685Y1232283D03*
X290944Y1228543D03*
X294685Y1236023D03*
Y1239763D03*
X290944D03*
X287204D03*
X283464D03*
X294685Y1243503D03*
X287204D03*
X294685Y1247243D03*
X287204D03*
X290944Y1250984D03*
X283464D03*
X287204D03*
X283464Y1243503D03*
Y1247243D03*
X290944Y1243503D03*
X294685Y1250984D03*
X290944Y1247243D03*
Y1254724D03*
X283464D03*
X287204D03*
X294685D03*
X305905Y1075196D03*
X298425D03*
X302165D03*
X309645D03*
X305905Y1078936D03*
X298425D03*
X309645Y1082677D03*
X302165D03*
X309645Y1086417D03*
X302165D03*
X309645Y1090157D03*
X305905D03*
X302165D03*
X298425D03*
Y1086417D03*
X302165Y1078936D03*
X305905Y1086417D03*
X309645Y1078936D03*
X298425Y1082677D03*
X305905D03*
Y1093897D03*
X298425D03*
X305905Y1097637D03*
X298425D03*
X309645Y1101377D03*
X302165D03*
X309645Y1105117D03*
X302165D03*
X298425D03*
X302165Y1097637D03*
X305905Y1105117D03*
X309645Y1097637D03*
X298425Y1101377D03*
X302165Y1093897D03*
X305905Y1101377D03*
X309645Y1093897D03*
Y1108858D03*
X305905D03*
X302165D03*
X298425D03*
X309645Y1112598D03*
X298425D03*
X309645Y1116338D03*
X305905D03*
X302165D03*
X309645Y1120078D03*
X298425D03*
X309645Y1123818D03*
X305905D03*
X302165D03*
Y1112598D03*
Y1120078D03*
X305905Y1112598D03*
X298425Y1116338D03*
X305905Y1120078D03*
X298425Y1123818D03*
X309645Y1127558D03*
X298425D03*
X309645Y1131299D03*
X305905D03*
X302165D03*
X309645Y1135039D03*
X298425D03*
X309645Y1138779D03*
X305905D03*
X302165D03*
X298425D03*
X302165Y1127558D03*
Y1135039D03*
X305905Y1127558D03*
X298425Y1131299D03*
X305905Y1135039D03*
X309645Y1142519D03*
X298425D03*
X309645Y1146259D03*
X305905D03*
X302165D03*
X309645Y1149999D03*
X298425D03*
X309645Y1153740D03*
X305905D03*
X302165D03*
Y1142519D03*
Y1149999D03*
X305905Y1142519D03*
X298425Y1146259D03*
X305905Y1149999D03*
X298425Y1153740D03*
X309645Y1157480D03*
X298425D03*
X309645Y1161220D03*
X305905D03*
X302165D03*
X309645Y1164960D03*
X298425D03*
X309645Y1168700D03*
X305905D03*
X302165D03*
X309645Y1172440D03*
X298425D03*
X302165Y1157480D03*
Y1164960D03*
Y1172440D03*
X305905Y1157480D03*
X298425Y1161220D03*
X305905Y1164960D03*
X298425Y1168700D03*
X305905Y1172440D03*
X309645Y1183661D03*
X305905D03*
X302165D03*
X309645Y1187401D03*
X298425D03*
X309645Y1176180D03*
X305905D03*
X302165D03*
X309645Y1179921D03*
X298425D03*
X302165D03*
Y1187401D03*
X298425Y1176180D03*
X305905Y1179921D03*
X298425Y1183661D03*
X305905Y1187401D03*
X309645Y1191141D03*
X305905D03*
X302165D03*
X309645Y1194881D03*
X298425D03*
X309645Y1198621D03*
X305905D03*
X302165D03*
X309645Y1202362D03*
X298425D03*
X302165Y1194881D03*
X298425Y1191141D03*
X305905Y1194881D03*
X302165Y1202362D03*
X305905D03*
X298425Y1198621D03*
X309645Y1206102D03*
X305905D03*
X302165D03*
X309645Y1209842D03*
X298425D03*
X309645Y1213582D03*
X305905D03*
X302165D03*
X309645Y1217322D03*
X298425D03*
X309645Y1221062D03*
X305905D03*
X302165D03*
X298425D03*
X302165Y1217322D03*
Y1209842D03*
X305905Y1217322D03*
X298425Y1213582D03*
X305905Y1209842D03*
X298425Y1206102D03*
X309645Y1224803D03*
X302165D03*
X309645Y1228543D03*
X302165D03*
X305905Y1232283D03*
X298425D03*
X305905Y1236023D03*
X298425D03*
Y1224803D03*
X302165Y1232283D03*
X305905Y1224803D03*
X309645Y1232283D03*
X298425Y1228543D03*
X302165Y1236023D03*
X305905Y1228543D03*
X309645Y1236023D03*
Y1239763D03*
X305905D03*
X302165D03*
X298425D03*
X309645Y1243503D03*
X302165D03*
X309645Y1247243D03*
X302165D03*
X305905Y1250984D03*
X298425D03*
Y1243503D03*
X302165Y1250984D03*
X305905Y1243503D03*
X309645Y1250984D03*
X298425Y1247243D03*
X305905D03*
Y1254724D03*
X298425D03*
X302165D03*
X309645D03*
X320866Y1075196D03*
X313385D03*
X317125D03*
X324606Y1078936D03*
X320866D03*
X313385D03*
X317125Y1082677D03*
X324606Y1086417D03*
X320866D03*
X317125D03*
Y1090157D03*
X313385D03*
X320866D03*
X324606D03*
X317125Y1078936D03*
X320866Y1082677D03*
X313385Y1086417D03*
X324606Y1082677D03*
X313385D03*
X324606Y1093897D03*
X320866D03*
X313385D03*
X324606Y1097637D03*
X320866D03*
X313385D03*
X317125Y1101377D03*
X324606Y1105117D03*
X320866D03*
X317125D03*
Y1097637D03*
X320866Y1101377D03*
X313385Y1105117D03*
X317125Y1093897D03*
X324606Y1101377D03*
X313385D03*
X317125Y1108858D03*
X313385D03*
X324606Y1112598D03*
X320866D03*
X317125Y1116338D03*
X313385D03*
X324606Y1120078D03*
X320866D03*
X317125Y1123818D03*
X313385D03*
X320866Y1108858D03*
X313385Y1112598D03*
X320866Y1116338D03*
X313385Y1120078D03*
X320866Y1123818D03*
X324606Y1108858D03*
X317125Y1112598D03*
X324606Y1116338D03*
X317125Y1120078D03*
X324606Y1123818D03*
Y1127558D03*
X320866D03*
X317125Y1131299D03*
X313385D03*
X324606Y1135039D03*
X320866D03*
X317125Y1138779D03*
X313385D03*
X320866D03*
X324606D03*
X313385Y1127558D03*
X320866Y1131299D03*
X313385Y1135039D03*
X317125Y1127558D03*
X324606Y1131299D03*
X317125Y1135039D03*
X324606Y1142519D03*
X320866D03*
X317125Y1146259D03*
X313385D03*
X324606Y1149999D03*
X320866D03*
X317125Y1153740D03*
X313385D03*
Y1142519D03*
X320866Y1146259D03*
X313385Y1149999D03*
X320866Y1153740D03*
X317125Y1142519D03*
X324606Y1146259D03*
X317125Y1149999D03*
X324606Y1153740D03*
Y1157480D03*
X320866D03*
X317125Y1161220D03*
X313385D03*
X324606Y1164960D03*
X320866D03*
X317125Y1168700D03*
X313385D03*
X324606Y1172440D03*
X320866D03*
X313385Y1157480D03*
X320866Y1161220D03*
X313385Y1164960D03*
X320866Y1168700D03*
X313385Y1172440D03*
X317125Y1157480D03*
X324606Y1161220D03*
X317125Y1164960D03*
X324606Y1168700D03*
X317125Y1172440D03*
Y1183661D03*
X313385D03*
X324606Y1187401D03*
X320866D03*
X317125Y1176180D03*
X313385D03*
X324606Y1179921D03*
X320866D03*
Y1176180D03*
X313385Y1179921D03*
X320866Y1183661D03*
X313385Y1187401D03*
X324606Y1176180D03*
X317125Y1179921D03*
X324606Y1183661D03*
X317125Y1187401D03*
Y1191141D03*
X313385D03*
X324606Y1194881D03*
X320866D03*
X317125Y1198621D03*
X313385D03*
X324606Y1202362D03*
X320866D03*
Y1191141D03*
X313385Y1194881D03*
X324606Y1191141D03*
X317125Y1194881D03*
X313385Y1202362D03*
X320866Y1198621D03*
X317125Y1202362D03*
X324606Y1198621D03*
X317125Y1206102D03*
X313385D03*
X324606Y1209842D03*
X320866D03*
X317125Y1213582D03*
X313385D03*
X324606Y1217322D03*
X320866D03*
X317125Y1221062D03*
X313385D03*
X320866D03*
X313385Y1217322D03*
X320866Y1213582D03*
X313385Y1209842D03*
X320866Y1206102D03*
X324606Y1221062D03*
X317125Y1217322D03*
X324606Y1213582D03*
X317125Y1209842D03*
X324606Y1206102D03*
Y1224803D03*
X320866D03*
X317125D03*
Y1228543D03*
X324606Y1232283D03*
X320866D03*
X313385D03*
X324606Y1236023D03*
X320866D03*
X313385D03*
Y1224803D03*
X317125Y1232283D03*
X320866Y1228543D03*
X313385D03*
X317125Y1236023D03*
X324606Y1228543D03*
X317125Y1239763D03*
X313385D03*
X324606Y1243503D03*
X320866D03*
X317125D03*
Y1247243D03*
X324606Y1250984D03*
X320866D03*
X313385D03*
X320866Y1239763D03*
X324606D03*
X313385Y1243503D03*
X317125Y1250984D03*
X320866Y1247243D03*
X313385D03*
X324606D03*
X320866Y1254724D03*
X313385D03*
X317125D03*
X602165Y1078936D03*
Y1086417D03*
Y1090157D03*
Y1082677D03*
Y1093897D03*
Y1097637D03*
Y1105117D03*
Y1101377D03*
Y1112598D03*
Y1120078D03*
Y1108858D03*
Y1116338D03*
Y1123818D03*
Y1127558D03*
Y1135039D03*
Y1131299D03*
Y1138779D03*
Y1142519D03*
Y1146259D03*
Y1153740D03*
Y1149999D03*
Y1161220D03*
Y1168700D03*
Y1157480D03*
Y1164960D03*
Y1172440D03*
Y1183661D03*
Y1187401D03*
Y1176180D03*
Y1179921D03*
Y1194881D03*
Y1202362D03*
Y1198621D03*
Y1191141D03*
Y1209842D03*
Y1217322D03*
Y1221062D03*
Y1213582D03*
Y1206102D03*
Y1224803D03*
Y1232283D03*
Y1236023D03*
Y1228543D03*
Y1243503D03*
Y1250984D03*
Y1239763D03*
Y1247243D03*
X620866Y1075196D03*
X613386D03*
X605905D03*
X617126D03*
X609646D03*
X620866Y1078936D03*
X613386D03*
X605905D03*
X617126Y1082677D03*
X609646D03*
X617126Y1086417D03*
X609646D03*
X605905D03*
X620866Y1090157D03*
X617126D03*
X613386D03*
X609646D03*
X605905D03*
X620866Y1086417D03*
X617126Y1078936D03*
X613386Y1086417D03*
X609646Y1078936D03*
X605905Y1082677D03*
X620866D03*
X613386D03*
X620866Y1093897D03*
X613386D03*
X605905D03*
X620866Y1097637D03*
X613386D03*
X605905D03*
X617126Y1101377D03*
X609646D03*
X617126Y1105117D03*
X609646D03*
X605905D03*
X620866D03*
X617126Y1097637D03*
X613386Y1105117D03*
X609646Y1097637D03*
X605905Y1101377D03*
X620866D03*
X617126Y1093897D03*
X613386Y1101377D03*
X609646Y1093897D03*
X620866Y1108858D03*
X617126D03*
X613386D03*
X609646D03*
X617126Y1112598D03*
X605905D03*
X620866Y1116338D03*
X617126D03*
X613386D03*
X609646D03*
X617126Y1120078D03*
X605905D03*
X620866Y1123818D03*
X617126D03*
X613386D03*
X609646D03*
X620866Y1112598D03*
Y1120078D03*
X605905Y1108858D03*
X613386Y1112598D03*
X605905Y1116338D03*
X613386Y1120078D03*
X605905Y1123818D03*
X609646Y1112598D03*
Y1120078D03*
X617126Y1127558D03*
X605905D03*
X620866Y1131299D03*
X617126D03*
X613386D03*
X609646D03*
X617126Y1135039D03*
X605905D03*
X620866Y1138779D03*
X617126D03*
X613386D03*
X609646D03*
X620866Y1127558D03*
Y1135039D03*
X613386Y1127558D03*
X605905Y1131299D03*
X613386Y1135039D03*
X605905Y1138779D03*
X609646Y1127558D03*
Y1135039D03*
X620866Y1142519D03*
X617126D03*
X613386D03*
X609646D03*
X605905D03*
X620866Y1146259D03*
X609646D03*
X605905D03*
X620866Y1149999D03*
X617126D03*
X613386D03*
X609646D03*
X620866Y1153740D03*
X609646D03*
X605905D03*
X613386Y1146259D03*
X617126D03*
X605905Y1149999D03*
X617126Y1153740D03*
X613386D03*
X620866Y1157480D03*
X617126D03*
X613386D03*
X609646D03*
X620866Y1161220D03*
X609646D03*
X605905D03*
X620866Y1164960D03*
X617126D03*
X613386D03*
X609646D03*
X620866Y1168700D03*
X609646D03*
X605905D03*
X620866Y1172440D03*
X617126D03*
X613386D03*
X609646D03*
X605905Y1157480D03*
X617126Y1161220D03*
X613386D03*
X605905Y1164960D03*
X617126Y1168700D03*
X613386D03*
X605905Y1172440D03*
X620866Y1183661D03*
X617126D03*
X613386D03*
X609646D03*
X605905D03*
X617126Y1187401D03*
X605905D03*
X620866Y1176180D03*
X609646D03*
X605905D03*
X620866Y1179921D03*
X617126D03*
X613386D03*
X609646D03*
X605905D03*
X617126Y1176180D03*
X613386D03*
X620866Y1187401D03*
X613386D03*
X609646D03*
X620866Y1191141D03*
X617126D03*
X613386D03*
X609646D03*
X617126Y1194881D03*
X605905D03*
X620866Y1198621D03*
X617126D03*
X613386D03*
X609646D03*
X617126Y1202362D03*
X605905D03*
X620866D03*
Y1194881D03*
X613386Y1202362D03*
X605905Y1198621D03*
X613386Y1194881D03*
X605905Y1191141D03*
X609646Y1202362D03*
Y1194881D03*
X620866Y1206102D03*
X617126D03*
X613386D03*
X609646D03*
X617126Y1209842D03*
X605905D03*
X620866Y1213582D03*
X617126D03*
X613386D03*
X609646D03*
X617126Y1217322D03*
X605905D03*
X620866Y1221062D03*
X617126D03*
X613386D03*
X609646D03*
X620866Y1217322D03*
Y1209842D03*
X605905Y1221062D03*
X613386Y1217322D03*
X605905Y1213582D03*
X613386Y1209842D03*
X605905Y1206102D03*
X609646Y1217322D03*
Y1209842D03*
X617126Y1224803D03*
X609646D03*
X605905D03*
X617126Y1228543D03*
X609646D03*
X620866Y1232283D03*
X613386D03*
X605905D03*
X620866Y1236023D03*
X613386D03*
X605905D03*
X620866Y1224803D03*
X617126Y1232283D03*
X613386Y1224803D03*
X609646Y1232283D03*
X605905Y1228543D03*
X620866D03*
X617126Y1236023D03*
X613386Y1228543D03*
X609646Y1236023D03*
X620866Y1239763D03*
X617126D03*
X613386D03*
X609646D03*
X617126Y1243503D03*
X609646D03*
X605905D03*
X617126Y1247243D03*
X609646D03*
X620866Y1250984D03*
X613386D03*
X605905D03*
Y1239763D03*
X620866Y1243503D03*
X617126Y1250984D03*
X613386Y1243503D03*
X609646Y1250984D03*
X605905Y1247243D03*
X620866D03*
X613386D03*
X620866Y1254724D03*
X613386D03*
X605905D03*
X617126D03*
X609646D03*
X628346Y1075196D03*
X635827D03*
X624606D03*
X632086D03*
X628346Y1078936D03*
X635827D03*
X632086Y1082677D03*
X624606D03*
X632086Y1086417D03*
X624606D03*
X632086Y1090157D03*
X628346D03*
X624606D03*
X635827D03*
X628346Y1086417D03*
X624606Y1078936D03*
X628346Y1082677D03*
X632086Y1078936D03*
X635827Y1086417D03*
Y1082677D03*
X628346Y1093897D03*
X635827D03*
X628346Y1097637D03*
X635827D03*
X632086Y1101377D03*
X624606D03*
X632086Y1105117D03*
X624606D03*
X628346D03*
X624606Y1097637D03*
X628346Y1101377D03*
X624606Y1093897D03*
X632086Y1097637D03*
X635827Y1105117D03*
X632086Y1093897D03*
X635827Y1101377D03*
X632086Y1108858D03*
X628346D03*
X624606D03*
X635827D03*
X632086Y1112598D03*
X628346D03*
X635827D03*
X624606Y1116338D03*
X635827D03*
X632086Y1120078D03*
X628346D03*
X635827D03*
X624606Y1123818D03*
X635827D03*
X624606Y1112598D03*
X632086Y1116338D03*
X624606Y1120078D03*
X632086Y1123818D03*
X628346Y1116338D03*
Y1123818D03*
X632086Y1127558D03*
X628346D03*
X635827D03*
X624606Y1131299D03*
X635827D03*
X632086Y1135039D03*
X628346D03*
X635827D03*
X624606Y1138779D03*
X635827D03*
X624606Y1127558D03*
X632086Y1131299D03*
X624606Y1135039D03*
X632086Y1138779D03*
X628346Y1131299D03*
Y1138779D03*
X632086Y1142519D03*
X628346D03*
X624606D03*
X635827D03*
X632086Y1146259D03*
X628346D03*
X632086Y1149999D03*
Y1153740D03*
X635827Y1146259D03*
Y1149999D03*
Y1153740D03*
X628346D03*
X624606Y1149999D03*
X628346D03*
X624606Y1146259D03*
Y1153740D03*
X632086Y1157480D03*
X635827D03*
X632086Y1161220D03*
Y1164960D03*
Y1168700D03*
X635827D03*
X632086Y1172440D03*
X635827D03*
Y1161220D03*
Y1164960D03*
X628346D03*
Y1172440D03*
Y1168700D03*
X624606Y1172440D03*
Y1168700D03*
Y1164960D03*
X628346Y1157480D03*
Y1161220D03*
X624606D03*
Y1157480D03*
X632086Y1183661D03*
X628346D03*
X624606D03*
X635827D03*
X632086Y1187401D03*
X628346D03*
X635827D03*
X632086Y1176180D03*
Y1179921D03*
X628346D03*
X624606D03*
X635827Y1176180D03*
Y1179921D03*
X624606Y1176180D03*
X628346D03*
X624606Y1187401D03*
Y1191141D03*
X635827D03*
X632086Y1194881D03*
X628346D03*
X635827D03*
X624606Y1198621D03*
X635827D03*
X632086Y1202362D03*
X628346D03*
X635827D03*
X624606D03*
X632086Y1198621D03*
X624606Y1194881D03*
X632086Y1191141D03*
X628346Y1198621D03*
Y1191141D03*
X624606Y1206102D03*
X635827D03*
X632086Y1209842D03*
X628346D03*
X635827D03*
X624606Y1213582D03*
X635827D03*
X632086Y1217322D03*
X628346D03*
X635827D03*
X632086Y1221062D03*
X628346D03*
X624606D03*
X635827D03*
X624606Y1217322D03*
X632086Y1213582D03*
X624606Y1209842D03*
X632086Y1206102D03*
X628346Y1213582D03*
Y1206102D03*
X632086Y1224803D03*
X624606D03*
X632086Y1228543D03*
X624606D03*
X628346Y1232283D03*
X635827D03*
X628346Y1236023D03*
X635827D03*
X624606Y1232283D03*
Y1236023D03*
X628346Y1224803D03*
X632086Y1232283D03*
X635827Y1224803D03*
X628346Y1228543D03*
X632086Y1236023D03*
X635827Y1228543D03*
X632086Y1239763D03*
X628346D03*
X624606D03*
X635827D03*
X632086Y1243503D03*
X624606D03*
X632086Y1247243D03*
X624606D03*
X628346Y1250984D03*
X635827D03*
X624606D03*
X628346Y1243503D03*
X632086Y1250984D03*
X635827Y1243503D03*
X628346Y1247243D03*
X635827D03*
X628346Y1254724D03*
X635827D03*
X624606D03*
X632086D03*
X650787Y1075196D03*
X643307D03*
X639567D03*
X647047D03*
X650787Y1078936D03*
X643307D03*
X647047Y1082677D03*
X639567D03*
X647047Y1086417D03*
X639567D03*
X650787Y1090157D03*
X647047D03*
X643307D03*
X639567D03*
Y1078936D03*
X643307Y1086417D03*
X647047Y1078936D03*
X650787Y1086417D03*
X643307Y1082677D03*
X650787D03*
Y1093897D03*
X643307D03*
X650787Y1097637D03*
X643307D03*
X647047Y1101377D03*
X639567D03*
X647047Y1105117D03*
X639567D03*
Y1097637D03*
X643307Y1105117D03*
X647047Y1097637D03*
X650787Y1105117D03*
X639567Y1093897D03*
X643307Y1101377D03*
X647047Y1093897D03*
X650787Y1101377D03*
Y1108858D03*
X647047D03*
X643307D03*
X639567D03*
Y1112598D03*
Y1116338D03*
X650787Y1120078D03*
X647047D03*
X643307D03*
X639567D03*
X650787Y1123818D03*
X647047D03*
X643307D03*
X639567D03*
X647047Y1116338D03*
X643307D03*
Y1112598D03*
X647047D03*
X650787Y1116338D03*
Y1112598D03*
Y1127558D03*
X647047D03*
X643307D03*
X639567D03*
X647047Y1131299D03*
X643307D03*
X639567D03*
X647047Y1135039D03*
X643307D03*
X639567D03*
X647047Y1138779D03*
X639567D03*
X643307D03*
X650787D03*
Y1131299D03*
Y1135039D03*
X643307Y1149999D03*
X647047Y1153740D03*
Y1142519D03*
X643307D03*
X639567D03*
X647047Y1146259D03*
X639567D03*
X650787Y1149999D03*
X639567D03*
Y1153740D03*
X650787Y1142519D03*
X643307Y1146259D03*
X647047Y1149999D03*
X643307Y1153740D03*
X650787Y1146259D03*
Y1153740D03*
X643307Y1157480D03*
X647047Y1161220D03*
X643307Y1164960D03*
X647047Y1168700D03*
X643307Y1172440D03*
X650787Y1157480D03*
X639567D03*
Y1161220D03*
X650787Y1164960D03*
X639567D03*
Y1168700D03*
X650787Y1172440D03*
X639567D03*
X647047D03*
Y1157480D03*
X643307Y1161220D03*
X647047Y1164960D03*
X643307Y1168700D03*
X650787Y1161220D03*
Y1168700D03*
X647047Y1176180D03*
X643307Y1179921D03*
X647047Y1183661D03*
X639567D03*
X650787Y1187401D03*
X647047D03*
X643307D03*
X639567D03*
Y1176180D03*
X650787Y1179921D03*
X639567D03*
X643307Y1183661D03*
Y1176180D03*
X647047Y1179921D03*
X650787Y1183661D03*
Y1176180D03*
X647047Y1191141D03*
X643307D03*
X639567D03*
X647047Y1194881D03*
X643307D03*
X639567D03*
X647047Y1198621D03*
X643307D03*
X639567D03*
X650787Y1202362D03*
X647047D03*
X643307D03*
X639567D03*
X650787Y1191141D03*
Y1198621D03*
Y1194881D03*
Y1206102D03*
X647047D03*
X643307D03*
X639567D03*
X650787Y1209842D03*
X647047D03*
X643307D03*
X639567D03*
X650787Y1213582D03*
X643307D03*
X639567D03*
X650787Y1217322D03*
X639567D03*
X650787Y1221062D03*
X647047D03*
X643307D03*
X639567D03*
X647047Y1217322D03*
X643307D03*
X647047Y1213582D03*
Y1224803D03*
X639567D03*
X647047Y1228543D03*
X639567D03*
X650787Y1232283D03*
X643307D03*
X650787Y1236023D03*
X643307D03*
X639567Y1232283D03*
X643307Y1224803D03*
X647047Y1232283D03*
X650787Y1224803D03*
X639567Y1236023D03*
X643307Y1228543D03*
X647047Y1236023D03*
X650787Y1228543D03*
Y1239763D03*
X647047D03*
X643307D03*
X639567D03*
X647047Y1243503D03*
X639567D03*
X647047Y1247243D03*
X639567D03*
X650787Y1250984D03*
X643307D03*
X639567D03*
X643307Y1243503D03*
X647047Y1250984D03*
X650787Y1243503D03*
X643307Y1247243D03*
X650787D03*
Y1254724D03*
X643307D03*
X639567D03*
X647047D03*
X665748Y1075196D03*
X658268D03*
X654527D03*
X662008D03*
X669488D03*
X665748Y1078936D03*
X658268D03*
X669488Y1082677D03*
X662008D03*
X654527D03*
X669488Y1086417D03*
X662008D03*
X654527D03*
X669488Y1090157D03*
X665748D03*
X662008D03*
X658268D03*
X654527D03*
Y1078936D03*
X658268Y1086417D03*
X662008Y1078936D03*
X665748Y1086417D03*
X669488Y1078936D03*
X658268Y1082677D03*
X665748D03*
Y1093897D03*
X658268D03*
X665748Y1097637D03*
X658268D03*
X669488Y1101377D03*
X662008D03*
X654527D03*
X669488Y1105117D03*
X662008D03*
X654527D03*
Y1097637D03*
X658268Y1105117D03*
X662008Y1097637D03*
X665748Y1105117D03*
X669488Y1097637D03*
X654527Y1093897D03*
X658268Y1101377D03*
X662008Y1093897D03*
X665748Y1101377D03*
X669488Y1093897D03*
Y1108858D03*
X665748D03*
X662008D03*
X658268D03*
X654527D03*
X669488Y1120078D03*
X665748D03*
X662008D03*
X658268D03*
X654527D03*
X669488Y1123818D03*
X665748D03*
X662008D03*
X658268D03*
X654527D03*
X658268Y1112598D03*
X662008Y1116338D03*
X658268D03*
X662008Y1112598D03*
X665748Y1116338D03*
Y1112598D03*
X669488Y1116338D03*
X654527D03*
Y1112598D03*
X669488D03*
Y1127558D03*
X665748D03*
X662008D03*
X658268D03*
X654527D03*
Y1131299D03*
X669488Y1135039D03*
X665748D03*
X662008D03*
X658268D03*
X654527D03*
Y1138779D03*
X669488Y1131299D03*
X665748D03*
X662008D03*
X658268D03*
X669488Y1138779D03*
X665748D03*
X662008D03*
X658268D03*
X669488Y1142519D03*
X665748D03*
X662008D03*
X658268D03*
X654527Y1146259D03*
X669488Y1149999D03*
X665748D03*
X662008D03*
X658268D03*
X654527Y1153740D03*
X669488Y1146259D03*
X665748D03*
X662008D03*
X658268D03*
X669488Y1153740D03*
X665748D03*
X662008D03*
X658268D03*
X654527Y1142519D03*
Y1149999D03*
X665748Y1157480D03*
X658268D03*
X669488Y1161220D03*
X662008D03*
X654527D03*
X665748Y1164960D03*
X658268D03*
X669488Y1168700D03*
X662008D03*
X654527D03*
X665748Y1172440D03*
X658268D03*
X669488Y1157480D03*
X662008D03*
X654527D03*
X665748Y1161220D03*
X658268D03*
X669488Y1164960D03*
X662008D03*
X654527D03*
X665748Y1168700D03*
X658268D03*
X669488Y1172440D03*
X662008D03*
X654527D03*
Y1183661D03*
X669488Y1187401D03*
X665748D03*
X662008D03*
X658268D03*
X654527D03*
Y1176180D03*
X669488Y1179921D03*
X665748D03*
X662008D03*
X658268D03*
X669488Y1183661D03*
X665748D03*
X662008D03*
X658268D03*
X669488Y1176180D03*
X665748D03*
X662008D03*
X658268D03*
X654527Y1179921D03*
Y1191141D03*
X669488Y1194881D03*
X665748D03*
X662008D03*
X658268D03*
X654527D03*
Y1198621D03*
X669488Y1202362D03*
X665748D03*
X662008D03*
X658268D03*
X654527D03*
X669488Y1198621D03*
X665748D03*
X662008D03*
X658268D03*
X669488Y1191141D03*
X665748D03*
X662008D03*
X658268D03*
X669488Y1206102D03*
X665748D03*
X662008D03*
X658268D03*
X654527D03*
X669488Y1209842D03*
X665748D03*
X662008D03*
X658268D03*
X654527D03*
X669488Y1221062D03*
X665748D03*
X662008D03*
X658268D03*
X654527D03*
X662008Y1213582D03*
X658268D03*
X669488D03*
X665748Y1217322D03*
Y1213582D03*
X669488Y1217322D03*
X662008D03*
X654527Y1213582D03*
X658268Y1217322D03*
X654527D03*
X669488Y1224803D03*
X662008D03*
X654527D03*
X669488Y1228543D03*
X662008D03*
X654527D03*
X665748Y1232283D03*
X658268D03*
X665748Y1236023D03*
X658268D03*
X654527Y1232283D03*
X658268Y1224803D03*
X662008Y1232283D03*
X665748Y1224803D03*
X669488Y1232283D03*
X654527Y1236023D03*
X658268Y1228543D03*
X662008Y1236023D03*
X665748Y1228543D03*
X669488Y1236023D03*
Y1239763D03*
X665748D03*
X662008D03*
X658268D03*
X654527D03*
X669488Y1243503D03*
X662008D03*
X654527D03*
X669488Y1247243D03*
X662008D03*
X654527D03*
X665748Y1250984D03*
X658268D03*
X654527D03*
X658268Y1243503D03*
X662008Y1250984D03*
X665748Y1243503D03*
X669488Y1250984D03*
X658268Y1247243D03*
X665748D03*
Y1254724D03*
X658268D03*
X654527D03*
X662008D03*
X669488D03*
X680709Y1075196D03*
X673228D03*
X676968D03*
X684449D03*
X680709Y1078936D03*
X673228D03*
X684449Y1082677D03*
X676968D03*
X684449Y1086417D03*
X676968D03*
X684449Y1090157D03*
X680709D03*
X676968D03*
X673228D03*
Y1086417D03*
X676968Y1078936D03*
X680709Y1086417D03*
X684449Y1078936D03*
X673228Y1082677D03*
X680709D03*
Y1093897D03*
X673228D03*
X680709Y1097637D03*
X673228D03*
X684449Y1101377D03*
X676968D03*
X684449Y1105117D03*
X676968D03*
X673228D03*
X676968Y1097637D03*
X680709Y1105117D03*
X684449Y1097637D03*
X673228Y1101377D03*
X676968Y1093897D03*
X680709Y1101377D03*
X684449Y1093897D03*
Y1108858D03*
X680709D03*
X676968D03*
X673228D03*
Y1112598D03*
Y1116338D03*
X684449Y1120078D03*
X680709D03*
X676968D03*
X673228D03*
X684449Y1123818D03*
X680709D03*
X676968D03*
X673228D03*
X684449Y1116338D03*
X680709Y1112598D03*
Y1116338D03*
X676968D03*
Y1112598D03*
X684449D03*
Y1127558D03*
X680709D03*
X676968D03*
X673228D03*
X684449Y1135039D03*
X680709D03*
X676968D03*
X673228D03*
X684449Y1131299D03*
X680709D03*
X676968D03*
X673228D03*
X684449Y1138779D03*
X680709D03*
X676968D03*
X673228D03*
X684449Y1142519D03*
X680709D03*
X676968D03*
X673228D03*
X684449Y1149999D03*
X680709D03*
X676968D03*
X673228D03*
X684449Y1146259D03*
X680709D03*
X676968D03*
X673228D03*
X684449Y1153740D03*
X680709D03*
X676968D03*
X673228D03*
X680709Y1157480D03*
X673228D03*
X684449Y1161220D03*
X676968D03*
X680709Y1164960D03*
X673228D03*
X684449Y1168700D03*
X676968D03*
X680709Y1172440D03*
X673228D03*
X684449Y1157480D03*
X676968D03*
X680709Y1161220D03*
X673228D03*
X684449Y1164960D03*
X676968D03*
X680709Y1168700D03*
X673228D03*
X684449Y1172440D03*
X676968D03*
X684449Y1187401D03*
X680709D03*
X676968D03*
X673228D03*
X684449Y1179921D03*
X680709D03*
X676968D03*
X673228D03*
X684449Y1183661D03*
X680709D03*
X676968D03*
X673228D03*
X684449Y1176180D03*
X680709D03*
X676968D03*
X673228D03*
X684449Y1194881D03*
X680709D03*
X676968D03*
X673228D03*
X684449Y1202362D03*
X680709D03*
X676968D03*
X673228D03*
X684449Y1198621D03*
X680709D03*
X676968D03*
X673228D03*
X684449Y1191141D03*
X680709D03*
X676968D03*
X673228D03*
X684449Y1206102D03*
X680709D03*
X676968D03*
X673228D03*
X684449Y1209842D03*
X680709D03*
X676968D03*
X673228D03*
X676968Y1213582D03*
Y1217322D03*
X684449Y1221062D03*
X680709D03*
X676968D03*
X673228D03*
X684449Y1217322D03*
Y1213582D03*
X680709D03*
Y1217322D03*
X673228D03*
Y1213582D03*
X684449Y1224803D03*
X676968D03*
X684449Y1228543D03*
X676968D03*
X680709Y1232283D03*
X673228D03*
X680709Y1236023D03*
X673228D03*
Y1224803D03*
X676968Y1232283D03*
X680709Y1224803D03*
X684449Y1232283D03*
X673228Y1228543D03*
X676968Y1236023D03*
X680709Y1228543D03*
X684449Y1236023D03*
Y1239763D03*
X680709D03*
X676968D03*
X673228D03*
X684449Y1243503D03*
X676968D03*
X684449Y1247243D03*
X676968D03*
X680709Y1250984D03*
X673228D03*
Y1243503D03*
X676968Y1250984D03*
X680709Y1243503D03*
X684449Y1250984D03*
X673228Y1247243D03*
X680709D03*
Y1254724D03*
X673228D03*
X676968D03*
X684449D03*
X695669Y1075196D03*
X688189D03*
X699409D03*
X691929D03*
X695669Y1078936D03*
X688189D03*
X699409Y1082677D03*
X691929D03*
X699409Y1086417D03*
X691929D03*
X699409Y1090157D03*
X695669D03*
X691929D03*
X688189D03*
Y1086417D03*
Y1082677D03*
X699409Y1078936D03*
X695669Y1086417D03*
X691929Y1078936D03*
X695669Y1082677D03*
Y1093897D03*
X688189D03*
X695669Y1097637D03*
X688189D03*
X699409Y1101377D03*
X691929D03*
X699409Y1105117D03*
X691929D03*
X688189D03*
Y1101377D03*
X699409Y1097637D03*
X695669Y1105117D03*
X691929Y1097637D03*
X699409Y1093897D03*
X695669Y1101377D03*
X691929Y1093897D03*
X699409Y1108858D03*
X695669D03*
X691929D03*
X688189D03*
Y1112598D03*
Y1116338D03*
X699409Y1120078D03*
X695669D03*
X691929D03*
X688189D03*
X699409Y1123818D03*
X695669D03*
X691929D03*
X688189D03*
X695669Y1116338D03*
X691929Y1112598D03*
X699409Y1116338D03*
X691929D03*
X699409Y1112598D03*
X695669D03*
X699409Y1127558D03*
X695669D03*
X691929D03*
X688189D03*
X699409Y1135039D03*
X695669D03*
X691929D03*
X688189D03*
X699409Y1131299D03*
X695669D03*
X691929D03*
X688189D03*
X699409Y1138779D03*
X695669D03*
X691929D03*
X688189D03*
X699409Y1142519D03*
X695669D03*
X691929D03*
X688189D03*
X699409Y1149999D03*
X695669D03*
X691929D03*
X688189D03*
X699409Y1146259D03*
X695669D03*
X691929D03*
X688189D03*
X699409Y1153740D03*
X695669D03*
X691929D03*
X688189D03*
X695669Y1157480D03*
X688189D03*
X699409Y1161220D03*
X691929D03*
X695669Y1164960D03*
X688189D03*
X699409Y1168700D03*
X691929D03*
X695669Y1172440D03*
X688189D03*
X699409Y1157480D03*
X691929D03*
X695669Y1161220D03*
X688189D03*
X699409Y1164960D03*
X691929D03*
X695669Y1168700D03*
X688189D03*
X699409Y1172440D03*
X691929D03*
X699409Y1187401D03*
X695669D03*
X691929D03*
X688189D03*
X699409Y1179921D03*
X695669D03*
X691929D03*
X688189D03*
X699409Y1183661D03*
X695669D03*
X691929D03*
X688189D03*
X699409Y1176180D03*
X695669D03*
X691929D03*
X688189D03*
X699409Y1194881D03*
X695669D03*
X691929D03*
X688189D03*
X699409Y1202362D03*
X695669D03*
X691929D03*
X688189D03*
X699409Y1198621D03*
X695669D03*
X691929D03*
X688189D03*
X699409Y1191141D03*
X695669D03*
X691929D03*
X688189D03*
X699409Y1206102D03*
X695669D03*
X691929D03*
X688189D03*
X699409Y1209842D03*
X695669D03*
X691929D03*
X688189D03*
X699409Y1221062D03*
X695669D03*
X691929D03*
X688189D03*
X695669Y1217322D03*
X688189Y1213582D03*
Y1217322D03*
X699409Y1213582D03*
X691929Y1217322D03*
Y1213582D03*
X699409Y1217322D03*
X695669Y1213582D03*
X699409Y1224803D03*
X691929D03*
X699409Y1228543D03*
X691929D03*
X695669Y1232283D03*
X688189D03*
X695669Y1236023D03*
X688189D03*
X699409Y1232283D03*
X695669Y1224803D03*
X691929Y1232283D03*
X688189Y1224803D03*
X699409Y1236023D03*
X695669Y1228543D03*
X691929Y1236023D03*
X688189Y1228543D03*
X699409Y1239763D03*
X695669D03*
X691929D03*
X688189D03*
X699409Y1243503D03*
X691929D03*
X699409Y1247243D03*
X691929D03*
X695669Y1250984D03*
X688189D03*
X699409D03*
X695669Y1243503D03*
X691929Y1250984D03*
X688189Y1243503D03*
X695669Y1247243D03*
X688189D03*
X695669Y1254724D03*
X688189D03*
X699409D03*
X691929D03*
X718110Y1075196D03*
X710630D03*
X703149D03*
X714370D03*
X706890D03*
X718110Y1078936D03*
X710630D03*
X703149D03*
X714370Y1082677D03*
X706890D03*
X714370Y1086417D03*
X706890D03*
X718110Y1090157D03*
X714370D03*
X710630D03*
X706890D03*
X703149D03*
X718110Y1086417D03*
X714370Y1078936D03*
X710630Y1086417D03*
X706890Y1078936D03*
X703149Y1086417D03*
X718110Y1082677D03*
X710630D03*
X703149D03*
X718110Y1093897D03*
X710630D03*
X703149D03*
X718110Y1097637D03*
X710630D03*
X703149D03*
X714370Y1101377D03*
X706890D03*
X714370Y1105117D03*
X706890D03*
X718110D03*
X714370Y1097637D03*
X710630Y1105117D03*
X706890Y1097637D03*
X703149Y1105117D03*
X718110Y1101377D03*
X714370Y1093897D03*
X710630Y1101377D03*
X706890Y1093897D03*
X703149Y1101377D03*
X718110Y1108858D03*
X714370D03*
X710630D03*
X706890D03*
X703149D03*
X718110Y1120078D03*
X714370D03*
X710630D03*
X706890D03*
X703149D03*
X718110Y1123818D03*
X714370D03*
X710630D03*
X706890D03*
X703149D03*
X710630Y1116338D03*
X706890D03*
X703149D03*
X706890Y1112598D03*
X714370Y1116338D03*
X703149Y1112598D03*
X718110D03*
X714370D03*
X718110Y1116338D03*
X710630Y1112598D03*
X718110Y1127558D03*
X714370D03*
X710630D03*
X706890D03*
X703149D03*
X718110Y1135039D03*
X714370D03*
X710630D03*
X706890D03*
X703149D03*
X718110Y1131299D03*
X714370D03*
X710630D03*
X706890D03*
X703149D03*
X718110Y1138779D03*
X714370D03*
X710630D03*
X706890D03*
X703149D03*
X718110Y1142519D03*
X714370D03*
X710630D03*
X706890D03*
X703149D03*
X718110Y1149999D03*
X714370D03*
X710630D03*
X706890D03*
X703149D03*
X718110Y1146259D03*
X714370D03*
X710630D03*
X706890D03*
X703149D03*
X718110Y1153740D03*
X714370D03*
X710630D03*
X706890D03*
X703149D03*
X718110Y1157480D03*
X710630D03*
X703149D03*
X714370Y1161220D03*
X706890D03*
X718110Y1164960D03*
X710630D03*
X703149D03*
X714370Y1168700D03*
X706890D03*
X718110Y1172440D03*
X710630D03*
X703149D03*
X718110Y1161220D03*
Y1168700D03*
X714370Y1157480D03*
X706890D03*
X710630Y1161220D03*
X703149D03*
X714370Y1164960D03*
X706890D03*
X710630Y1168700D03*
X703149D03*
X714370Y1172440D03*
X706890D03*
X718110Y1187401D03*
X714370D03*
X710630D03*
X706890D03*
X703149D03*
X718110Y1179921D03*
X714370D03*
X710630D03*
X706890D03*
X703149D03*
X718110Y1183661D03*
X714370D03*
X710630D03*
X706890D03*
X703149D03*
X718110Y1176180D03*
X714370D03*
X710630D03*
X706890D03*
X703149D03*
X718110Y1194881D03*
X714370D03*
X710630D03*
X706890D03*
X703149D03*
X718110Y1202362D03*
X714370D03*
X710630D03*
X706890D03*
X703149D03*
X718110Y1198621D03*
X714370D03*
X710630D03*
X706890D03*
X703149D03*
X718110Y1191141D03*
X714370D03*
X710630D03*
X706890D03*
X703149D03*
X718110Y1206102D03*
X714370D03*
X710630D03*
X706890D03*
X703149D03*
X718110Y1209842D03*
X714370D03*
X710630D03*
X706890D03*
X703149D03*
X718110Y1221062D03*
X714370D03*
X710630D03*
X706890D03*
X703149D03*
Y1213582D03*
X706890D03*
X718110D03*
X714370Y1217322D03*
X706890D03*
X714370Y1213582D03*
X710630D03*
X703149Y1217322D03*
X718110D03*
X710630D03*
X714370Y1224803D03*
X706890D03*
X714370Y1228543D03*
X706890D03*
X718110Y1232283D03*
X710630D03*
X703149D03*
X718110Y1236023D03*
X710630D03*
X703149D03*
X718110Y1224803D03*
X714370Y1232283D03*
X710630Y1224803D03*
X706890Y1232283D03*
X703149Y1224803D03*
X718110Y1228543D03*
X714370Y1236023D03*
X710630Y1228543D03*
X706890Y1236023D03*
X703149Y1228543D03*
X718110Y1239763D03*
X714370D03*
X710630D03*
X706890D03*
X703149D03*
X714370Y1243503D03*
X706890D03*
X714370Y1247243D03*
X706890D03*
X718110Y1250984D03*
X710630D03*
X703149D03*
X718110Y1243503D03*
X714370Y1250984D03*
X710630Y1243503D03*
X706890Y1250984D03*
X703149Y1243503D03*
X718110Y1247243D03*
X710630D03*
X703149D03*
X718110Y1254724D03*
X710630D03*
X703149D03*
X714370D03*
X706890D03*
X733071Y1075196D03*
X725590D03*
X729331D03*
X721850D03*
X733071Y1078936D03*
X725590D03*
X729331Y1082677D03*
X721850D03*
X729331Y1086417D03*
X721850D03*
X733071Y1090157D03*
X729331D03*
X725590D03*
X721850D03*
X733071Y1086417D03*
X729331Y1078936D03*
X725590Y1086417D03*
X721850Y1078936D03*
X733071Y1082677D03*
X725590D03*
X733071Y1093897D03*
X725590D03*
X733071Y1097637D03*
X725590D03*
X729331Y1101377D03*
X721850D03*
X729331Y1105117D03*
X721850D03*
X733071D03*
X729331Y1097637D03*
X725590Y1105117D03*
X721850Y1097637D03*
X733071Y1101377D03*
X729331Y1093897D03*
X725590Y1101377D03*
X721850Y1093897D03*
X733071Y1108858D03*
X729331D03*
X725590D03*
X721850D03*
X733071Y1120078D03*
X729331D03*
X725590D03*
X721850D03*
X729331Y1123818D03*
X725590D03*
X721850D03*
X733071D03*
X729331Y1116338D03*
X733071Y1112598D03*
X721850Y1116338D03*
Y1112598D03*
X733071Y1116338D03*
X729331Y1112598D03*
X725590Y1116338D03*
Y1112598D03*
X729331Y1127558D03*
X725590D03*
X721850D03*
X725590Y1131299D03*
X729331Y1135039D03*
X725590D03*
X721850D03*
X733071Y1138779D03*
X725590D03*
X729331Y1131299D03*
Y1138779D03*
X721850Y1131299D03*
Y1138779D03*
X733071Y1127558D03*
Y1135039D03*
Y1131299D03*
Y1142519D03*
X725590D03*
X721850D03*
X733071Y1146259D03*
X725590D03*
X733071Y1149999D03*
X729331D03*
X725590D03*
X721850D03*
X733071Y1153740D03*
X729331D03*
X725590D03*
X721850Y1146259D03*
Y1153740D03*
X729331Y1142519D03*
Y1146259D03*
Y1157480D03*
X725590D03*
X729331Y1161220D03*
Y1164960D03*
Y1168700D03*
Y1172440D03*
X725590D03*
Y1161220D03*
X721850D03*
X725590Y1164960D03*
X721850D03*
X725590Y1168700D03*
X721850D03*
Y1157480D03*
Y1172440D03*
X733071Y1157480D03*
Y1161220D03*
Y1164960D03*
Y1168700D03*
Y1172440D03*
Y1183661D03*
X725590D03*
X733071Y1187401D03*
X725590D03*
X721850D03*
X733071Y1176180D03*
X725590D03*
X733071Y1179921D03*
X721850D03*
Y1183661D03*
Y1176180D03*
X725590Y1179921D03*
X729331Y1183661D03*
Y1187401D03*
Y1179921D03*
Y1176180D03*
X733071Y1191141D03*
X725590D03*
X729331Y1194881D03*
X725590D03*
X721850D03*
X725590Y1198621D03*
X729331Y1202362D03*
X725590D03*
X721850D03*
X729331Y1198621D03*
Y1191141D03*
X721850Y1198621D03*
Y1191141D03*
X733071Y1198621D03*
Y1202362D03*
Y1194881D03*
X729331Y1206102D03*
X725590D03*
X721850D03*
X733071Y1209842D03*
X729331D03*
X725590D03*
X721850D03*
X733071Y1221062D03*
X729331D03*
X725590D03*
X721850D03*
X733071Y1206102D03*
X725590Y1217322D03*
X733071D03*
Y1213582D03*
X729331D03*
X725590D03*
X721850D03*
Y1217322D03*
X729331D03*
Y1224803D03*
X721850D03*
X729331Y1228543D03*
X721850D03*
X733071Y1232283D03*
X725590D03*
X733071Y1236023D03*
X725590D03*
X733071Y1224803D03*
X729331Y1232283D03*
X725590Y1224803D03*
X721850Y1232283D03*
X733071Y1228543D03*
X729331Y1236023D03*
X725590Y1228543D03*
X721850Y1236023D03*
X733071Y1239763D03*
X729331D03*
X725590D03*
X721850D03*
X729331Y1243503D03*
X721850D03*
X729331Y1247243D03*
X721850D03*
X733071Y1250984D03*
X725590D03*
X733071Y1243503D03*
X729331Y1250984D03*
X725590Y1243503D03*
X721850Y1250984D03*
X733071Y1247243D03*
X725590D03*
X733071Y1254724D03*
X725590D03*
X729331D03*
X721850D03*
X748031Y1075196D03*
X740551D03*
X744291D03*
X736811D03*
X748031Y1078936D03*
X740551D03*
X744291Y1082677D03*
X736811D03*
X744291Y1086417D03*
X736811D03*
X748031Y1090157D03*
X744291D03*
X740551D03*
X736811D03*
X748031Y1086417D03*
X744291Y1078936D03*
X740551Y1086417D03*
X736811Y1078936D03*
X748031Y1082677D03*
X740551D03*
X748031Y1093897D03*
X740551D03*
X748031Y1097637D03*
X740551D03*
X744291Y1101377D03*
X736811D03*
X744291Y1105117D03*
X736811D03*
X748031D03*
X744291Y1097637D03*
X740551Y1105117D03*
X736811Y1097637D03*
X748031Y1101377D03*
X744291Y1093897D03*
X740551Y1101377D03*
X736811Y1093897D03*
X748031Y1108858D03*
X744291D03*
X740551D03*
X736811D03*
X748031Y1112598D03*
Y1116338D03*
Y1120078D03*
X736811D03*
X748031Y1123818D03*
X736811D03*
X740551Y1120078D03*
X736811Y1112598D03*
Y1116338D03*
X740551D03*
Y1123818D03*
X744291Y1116338D03*
Y1123818D03*
Y1120078D03*
Y1112598D03*
X740551D03*
X748031Y1127558D03*
X736811D03*
X748031Y1131299D03*
X736811D03*
X748031Y1135039D03*
X736811D03*
X748031Y1138779D03*
X736811D03*
X744291Y1127558D03*
Y1131299D03*
X740551Y1127558D03*
Y1131299D03*
X744291Y1138779D03*
X740551Y1135039D03*
X744291D03*
X740551Y1138779D03*
X748031Y1142519D03*
X736811D03*
X748031Y1146259D03*
X736811D03*
X748031Y1149999D03*
X736811D03*
X748031Y1153740D03*
X744291D03*
X740551D03*
X736811D03*
X740551Y1142519D03*
X744291Y1149999D03*
X740551D03*
Y1146259D03*
X744291Y1142519D03*
Y1146259D03*
X748031Y1157480D03*
X744291D03*
X736811D03*
X748031Y1161220D03*
X744291D03*
X736811D03*
X748031Y1164960D03*
X744291D03*
X736811D03*
X748031Y1168700D03*
X744291D03*
X736811D03*
X748031Y1172440D03*
X744291D03*
X736811D03*
X740551Y1157480D03*
Y1161220D03*
Y1164960D03*
Y1168700D03*
Y1172440D03*
X748031Y1183661D03*
X740551D03*
X736811D03*
X748031Y1187401D03*
X736811D03*
X748031Y1176180D03*
X744291D03*
X740551D03*
X736811D03*
X748031Y1179921D03*
X740551D03*
X744291Y1187401D03*
X736811Y1179921D03*
X740551Y1187401D03*
X744291Y1179921D03*
Y1183661D03*
X748031Y1191141D03*
X740551D03*
X736811D03*
X748031Y1194881D03*
X736811D03*
X748031Y1198621D03*
X736811D03*
X748031Y1202362D03*
X736811D03*
X744291Y1191141D03*
X740551Y1194881D03*
Y1202362D03*
X744291Y1194881D03*
Y1202362D03*
Y1198621D03*
X740551D03*
X748031Y1206102D03*
X736811D03*
X748031Y1209842D03*
X736811D03*
X748031Y1213582D03*
Y1217322D03*
Y1221062D03*
X744291D03*
X740551D03*
X736811D03*
X744291Y1217322D03*
X740551Y1209842D03*
Y1213582D03*
X736811D03*
X740551Y1217322D03*
X744291Y1213582D03*
Y1209842D03*
X736811Y1217322D03*
X740551Y1206102D03*
X744291D03*
Y1224803D03*
X736811D03*
X744291Y1228543D03*
X736811D03*
X748031Y1232283D03*
X740551D03*
X748031Y1236023D03*
X740551D03*
X744291Y1232283D03*
X740551Y1224803D03*
X736811Y1232283D03*
X744291Y1236023D03*
X740551Y1228543D03*
X736811Y1236023D03*
X748031Y1224803D03*
Y1228543D03*
Y1239763D03*
X744291D03*
X740551D03*
X736811D03*
X744291Y1243503D03*
X736811D03*
X744291Y1247243D03*
X736811D03*
X748031Y1250984D03*
X740551D03*
X744291D03*
X740551Y1243503D03*
X736811Y1250984D03*
X740551Y1247243D03*
X748031Y1243503D03*
Y1247243D03*
Y1254724D03*
X740551D03*
X744291D03*
X736811D03*
X762992Y1075196D03*
X755512D03*
X751772D03*
X759252D03*
X766732D03*
X762992Y1078936D03*
X755512D03*
X766732Y1082677D03*
X759252D03*
X751772D03*
X766732Y1086417D03*
X759252D03*
X751772D03*
X766732Y1090157D03*
X762992D03*
X759252D03*
X755512D03*
X751772D03*
Y1078936D03*
X755512Y1086417D03*
X759252Y1078936D03*
X762992Y1086417D03*
X766732Y1078936D03*
X755512Y1082677D03*
X762992D03*
Y1093897D03*
X755512D03*
X762992Y1097637D03*
X755512D03*
X766732Y1101377D03*
X759252D03*
X751772D03*
X766732Y1105117D03*
X759252D03*
X751772D03*
Y1097637D03*
X755512Y1105117D03*
X759252Y1097637D03*
X762992Y1105117D03*
X766732Y1097637D03*
X751772Y1093897D03*
X755512Y1101377D03*
X759252Y1093897D03*
X762992Y1101377D03*
X766732Y1093897D03*
Y1108858D03*
X762992D03*
X759252D03*
X755512D03*
X751772D03*
X766732Y1112598D03*
X755512D03*
X751772D03*
X766732Y1116338D03*
X762992D03*
X759252D03*
X766732Y1120078D03*
X755512D03*
X751772D03*
X766732Y1123818D03*
X762992D03*
X759252D03*
Y1112598D03*
X751772Y1116338D03*
X759252Y1120078D03*
X751772Y1123818D03*
X762992Y1112598D03*
X755512Y1116338D03*
X762992Y1120078D03*
X755512Y1123818D03*
X766732Y1127558D03*
X755512D03*
X751772D03*
X766732Y1131299D03*
X762992D03*
X759252D03*
X766732Y1135039D03*
X755512D03*
X751772D03*
X766732Y1138779D03*
X762992D03*
X759252D03*
X751772D03*
X755512D03*
X759252Y1127558D03*
X751772Y1131299D03*
X759252Y1135039D03*
X762992Y1127558D03*
X755512Y1131299D03*
X762992Y1135039D03*
X766732Y1142519D03*
X755512D03*
X751772D03*
X766732Y1146259D03*
X762992D03*
X759252D03*
X766732Y1149999D03*
X755512D03*
X751772D03*
X766732Y1153740D03*
X762992D03*
X759252D03*
Y1142519D03*
X751772Y1146259D03*
X759252Y1149999D03*
X751772Y1153740D03*
X762992Y1142519D03*
X755512Y1146259D03*
X762992Y1149999D03*
X755512Y1153740D03*
X766732Y1157480D03*
X755512D03*
X751772D03*
X766732Y1161220D03*
X762992D03*
X759252D03*
X766732Y1164960D03*
X755512D03*
X751772D03*
X766732Y1168700D03*
X762992D03*
X759252D03*
X766732Y1172440D03*
X755512D03*
X751772D03*
X759252Y1157480D03*
X751772Y1161220D03*
X759252Y1164960D03*
X751772Y1168700D03*
X759252Y1172440D03*
X762992Y1157480D03*
X755512Y1161220D03*
X762992Y1164960D03*
X755512Y1168700D03*
X762992Y1172440D03*
X766732Y1183661D03*
X762992D03*
X759252D03*
X766732Y1187401D03*
X755512D03*
X751772D03*
X766732Y1176180D03*
X762992D03*
X759252D03*
X766732Y1179921D03*
X755512D03*
X751772D03*
Y1176180D03*
X759252Y1179921D03*
X751772Y1183661D03*
X759252Y1187401D03*
X755512Y1176180D03*
X762992Y1179921D03*
X755512Y1183661D03*
X762992Y1187401D03*
X766732Y1191141D03*
X762992D03*
X759252D03*
X766732Y1194881D03*
X755512D03*
X751772D03*
X766732Y1198621D03*
X762992D03*
X759252D03*
X766732Y1202362D03*
X755512D03*
X751772D03*
Y1191141D03*
X759252Y1194881D03*
X755512Y1191141D03*
X762992Y1194881D03*
X759252Y1202362D03*
X751772Y1198621D03*
X762992Y1202362D03*
X755512Y1198621D03*
X766732Y1206102D03*
X762992D03*
X759252D03*
X766732Y1209842D03*
X755512D03*
X751772D03*
X766732Y1213582D03*
X762992D03*
X759252D03*
X766732Y1217322D03*
X755512D03*
X751772D03*
X766732Y1221062D03*
X762992D03*
X759252D03*
X755512D03*
X751772D03*
X759252Y1217322D03*
X751772Y1213582D03*
X759252Y1209842D03*
X751772Y1206102D03*
X762992Y1217322D03*
X755512Y1213582D03*
X762992Y1209842D03*
X755512Y1206102D03*
X766732Y1224803D03*
X759252D03*
X751772D03*
X766732Y1228543D03*
X759252D03*
X751772D03*
X762992Y1232283D03*
X755512D03*
X762992Y1236023D03*
X755512D03*
X751772Y1232283D03*
X755512Y1224803D03*
X759252Y1232283D03*
X762992Y1224803D03*
X766732Y1232283D03*
X751772Y1236023D03*
X755512Y1228543D03*
X759252Y1236023D03*
X762992Y1228543D03*
X766732Y1236023D03*
Y1239763D03*
X762992D03*
X759252D03*
X755512D03*
X751772D03*
X766732Y1243503D03*
X759252D03*
X751772D03*
X766732Y1247243D03*
X759252D03*
X751772D03*
X762992Y1250984D03*
X755512D03*
X751772D03*
X755512Y1243503D03*
X759252Y1250984D03*
X762992Y1243503D03*
X766732Y1250984D03*
X755512Y1247243D03*
X762992D03*
Y1254724D03*
X755512D03*
X751772D03*
X759252D03*
X766732D03*
X777953Y1075196D03*
X770472D03*
X774212D03*
X781693Y1078936D03*
X777953D03*
X770472D03*
X774212Y1082677D03*
X781693Y1086417D03*
X777953D03*
X774212D03*
Y1090157D03*
X770472D03*
X777953D03*
X781693D03*
X774212Y1078936D03*
X777953Y1082677D03*
X770472Y1086417D03*
X781693Y1082677D03*
X770472D03*
X781693Y1093897D03*
X777953D03*
X770472D03*
X781693Y1097637D03*
X777953D03*
X770472D03*
X774212Y1101377D03*
X781693Y1105117D03*
X777953D03*
X774212D03*
Y1097637D03*
X777953Y1101377D03*
X770472Y1105117D03*
X774212Y1093897D03*
X781693Y1101377D03*
X770472D03*
X774212Y1108858D03*
X770472D03*
X781693Y1112598D03*
X777953D03*
X774212Y1116338D03*
X770472D03*
X781693Y1120078D03*
X777953D03*
X774212Y1123818D03*
X770472D03*
X777953Y1108858D03*
X770472Y1112598D03*
X777953Y1116338D03*
X770472Y1120078D03*
X777953Y1123818D03*
X781693Y1108858D03*
X774212Y1112598D03*
X781693Y1116338D03*
X774212Y1120078D03*
X781693Y1123818D03*
Y1127558D03*
X777953D03*
X774212Y1131299D03*
X770472D03*
X781693Y1135039D03*
X777953D03*
X774212Y1138779D03*
X770472D03*
X777953D03*
X781693D03*
X770472Y1127558D03*
X777953Y1131299D03*
X770472Y1135039D03*
X774212Y1127558D03*
X781693Y1131299D03*
X774212Y1135039D03*
X781693Y1142519D03*
X777953D03*
X774212Y1146259D03*
X770472D03*
X781693Y1149999D03*
X777953D03*
X774212Y1153740D03*
X770472D03*
Y1142519D03*
X777953Y1146259D03*
X770472Y1149999D03*
X777953Y1153740D03*
X774212Y1142519D03*
X781693Y1146259D03*
X774212Y1149999D03*
X781693Y1153740D03*
Y1157480D03*
X777953D03*
X774212Y1161220D03*
X770472D03*
X781693Y1164960D03*
X777953D03*
X774212Y1168700D03*
X770472D03*
X781693Y1172440D03*
X777953D03*
X770472Y1157480D03*
X777953Y1161220D03*
X770472Y1164960D03*
X777953Y1168700D03*
X770472Y1172440D03*
X774212Y1157480D03*
X781693Y1161220D03*
X774212Y1164960D03*
X781693Y1168700D03*
X774212Y1172440D03*
Y1183661D03*
X770472D03*
X781693Y1187401D03*
X777953D03*
X774212Y1176180D03*
X770472D03*
X781693Y1179921D03*
X777953D03*
Y1176180D03*
X770472Y1179921D03*
X777953Y1183661D03*
X770472Y1187401D03*
X781693Y1176180D03*
X774212Y1179921D03*
X781693Y1183661D03*
X774212Y1187401D03*
Y1191141D03*
X770472D03*
X781693Y1194881D03*
X777953D03*
X774212Y1198621D03*
X770472D03*
X781693Y1202362D03*
X777953D03*
Y1191141D03*
X770472Y1194881D03*
X781693Y1191141D03*
X774212Y1194881D03*
X770472Y1202362D03*
X777953Y1198621D03*
X774212Y1202362D03*
X781693Y1198621D03*
X774212Y1206102D03*
X770472D03*
X781693Y1209842D03*
X777953D03*
X774212Y1213582D03*
X770472D03*
X781693Y1217322D03*
X777953D03*
X774212Y1221062D03*
X770472D03*
X777953D03*
X770472Y1217322D03*
X777953Y1213582D03*
X770472Y1209842D03*
X777953Y1206102D03*
X781693Y1221062D03*
X774212Y1217322D03*
X781693Y1213582D03*
X774212Y1209842D03*
X781693Y1206102D03*
Y1224803D03*
X777953D03*
X774212D03*
Y1228543D03*
X781693Y1232283D03*
X777953D03*
X770472D03*
X781693Y1236023D03*
X777953D03*
X770472D03*
Y1224803D03*
X774212Y1232283D03*
X777953Y1228543D03*
X770472D03*
X774212Y1236023D03*
X781693Y1228543D03*
X774212Y1239763D03*
X770472D03*
X781693Y1243503D03*
X777953D03*
X774212D03*
Y1247243D03*
X781693Y1250984D03*
X777953D03*
X770472D03*
X777953Y1239763D03*
X781693D03*
X770472Y1243503D03*
X774212Y1250984D03*
X777953Y1247243D03*
X770472D03*
X781693D03*
X777953Y1254724D03*
X770472D03*
X774212D03*
X1059251Y1078936D03*
Y1086417D03*
Y1090157D03*
Y1082677D03*
Y1093897D03*
Y1097637D03*
Y1105117D03*
Y1101377D03*
Y1112598D03*
Y1120078D03*
Y1108858D03*
Y1116338D03*
Y1123818D03*
Y1127558D03*
Y1135039D03*
Y1131299D03*
Y1138779D03*
Y1142519D03*
Y1146259D03*
Y1153740D03*
Y1149999D03*
Y1161220D03*
Y1168700D03*
Y1157480D03*
Y1164960D03*
Y1172440D03*
Y1183661D03*
Y1187401D03*
Y1176180D03*
Y1179921D03*
Y1194881D03*
Y1202362D03*
Y1198621D03*
Y1191141D03*
Y1209842D03*
Y1217322D03*
Y1221062D03*
Y1213582D03*
Y1206102D03*
Y1224803D03*
Y1232283D03*
Y1236023D03*
Y1228543D03*
Y1243503D03*
Y1250984D03*
Y1239763D03*
Y1247243D03*
X1070472Y1075196D03*
X1062991D03*
X1074212D03*
X1066732D03*
X1070472Y1078936D03*
X1062991D03*
X1074212Y1082677D03*
X1066732D03*
X1074212Y1086417D03*
X1066732D03*
X1062991D03*
X1074212Y1090157D03*
X1070472D03*
X1066732D03*
X1062991D03*
X1074212Y1078936D03*
X1070472Y1086417D03*
X1066732Y1078936D03*
X1062991Y1082677D03*
X1070472D03*
Y1093897D03*
X1062991D03*
X1070472Y1097637D03*
X1062991D03*
X1074212Y1101377D03*
X1066732D03*
X1074212Y1105117D03*
X1066732D03*
X1062991D03*
X1074212Y1097637D03*
X1070472Y1105117D03*
X1066732Y1097637D03*
X1062991Y1101377D03*
X1074212Y1093897D03*
X1070472Y1101377D03*
X1066732Y1093897D03*
X1074212Y1108858D03*
X1070472D03*
X1066732D03*
X1074212Y1112598D03*
X1062991D03*
X1074212Y1116338D03*
X1070472D03*
X1066732D03*
X1074212Y1120078D03*
X1062991D03*
X1074212Y1123818D03*
X1070472D03*
X1066732D03*
X1062991Y1108858D03*
X1070472Y1112598D03*
X1062991Y1116338D03*
X1070472Y1120078D03*
X1062991Y1123818D03*
X1066732Y1112598D03*
Y1120078D03*
X1074212Y1127558D03*
X1062991D03*
X1074212Y1131299D03*
X1070472D03*
X1066732D03*
X1074212Y1135039D03*
X1062991D03*
X1074212Y1138779D03*
X1070472D03*
X1066732D03*
X1070472Y1127558D03*
X1062991Y1131299D03*
X1070472Y1135039D03*
X1062991Y1138779D03*
X1066732Y1127558D03*
Y1135039D03*
X1074212Y1142519D03*
X1070472D03*
X1066732D03*
X1062991D03*
X1066732Y1146259D03*
X1062991D03*
X1074212Y1149999D03*
X1070472D03*
X1066732D03*
Y1153740D03*
X1062991D03*
X1070472Y1146259D03*
X1074212D03*
X1062991Y1149999D03*
X1074212Y1153740D03*
X1070472D03*
X1074212Y1157480D03*
X1070472D03*
X1066732D03*
Y1161220D03*
X1062991D03*
X1074212Y1164960D03*
X1070472D03*
X1066732D03*
Y1168700D03*
X1062991D03*
X1074212Y1172440D03*
X1070472D03*
X1066732D03*
X1062991Y1157480D03*
X1074212Y1161220D03*
X1070472D03*
X1062991Y1164960D03*
X1074212Y1168700D03*
X1070472D03*
X1062991Y1172440D03*
X1074212Y1183661D03*
X1070472D03*
X1066732D03*
X1062991D03*
X1074212Y1187401D03*
X1062991D03*
X1066732Y1176180D03*
X1062991D03*
X1074212Y1179921D03*
X1070472D03*
X1066732D03*
X1062991D03*
X1074212Y1176180D03*
X1070472D03*
Y1187401D03*
X1066732D03*
X1074212Y1191141D03*
X1070472D03*
X1066732D03*
X1074212Y1194881D03*
X1062991D03*
X1074212Y1198621D03*
X1070472D03*
X1066732D03*
X1074212Y1202362D03*
X1062991D03*
X1070472D03*
X1062991Y1198621D03*
X1070472Y1194881D03*
X1062991Y1191141D03*
X1066732Y1202362D03*
Y1194881D03*
X1074212Y1206102D03*
X1070472D03*
X1066732D03*
X1074212Y1209842D03*
X1062991D03*
X1074212Y1213582D03*
X1070472D03*
X1066732D03*
X1074212Y1217322D03*
X1062991D03*
X1074212Y1221062D03*
X1070472D03*
X1066732D03*
X1062991D03*
X1070472Y1217322D03*
X1062991Y1213582D03*
X1070472Y1209842D03*
X1062991Y1206102D03*
X1066732Y1217322D03*
Y1209842D03*
X1074212Y1224803D03*
X1066732D03*
X1062991D03*
X1074212Y1228543D03*
X1066732D03*
X1070472Y1232283D03*
X1062991D03*
X1070472Y1236023D03*
X1062991D03*
X1074212Y1232283D03*
X1070472Y1224803D03*
X1066732Y1232283D03*
X1062991Y1228543D03*
X1074212Y1236023D03*
X1070472Y1228543D03*
X1066732Y1236023D03*
X1074212Y1239763D03*
X1070472D03*
X1066732D03*
X1074212Y1243503D03*
X1066732D03*
X1062991D03*
X1074212Y1247243D03*
X1066732D03*
X1070472Y1250984D03*
X1062991D03*
Y1239763D03*
X1074212Y1250984D03*
X1070472Y1243503D03*
X1066732Y1250984D03*
X1062991Y1247243D03*
X1070472D03*
Y1254724D03*
X1062991D03*
X1074212D03*
X1066732D03*
X1085432Y1075196D03*
X1077952D03*
X1081692D03*
X1089172D03*
X1085432Y1078936D03*
X1077952D03*
X1089172Y1082677D03*
X1081692D03*
X1089172Y1086417D03*
X1081692D03*
X1089172Y1090157D03*
X1085432D03*
X1081692D03*
X1077952D03*
X1085432Y1086417D03*
X1081692Y1078936D03*
X1077952Y1086417D03*
X1085432Y1082677D03*
X1077952D03*
X1089172Y1078936D03*
X1085432Y1093897D03*
X1077952D03*
X1085432Y1097637D03*
X1077952D03*
X1089172Y1101377D03*
X1081692D03*
X1089172Y1105117D03*
X1081692D03*
X1085432D03*
X1081692Y1097637D03*
X1077952Y1105117D03*
X1085432Y1101377D03*
X1081692Y1093897D03*
X1077952Y1101377D03*
X1089172Y1097637D03*
Y1093897D03*
Y1108858D03*
X1085432D03*
X1081692D03*
X1077952D03*
X1089172Y1112598D03*
X1085432D03*
X1081692Y1116338D03*
X1077952D03*
X1089172Y1120078D03*
X1085432D03*
X1081692Y1123818D03*
X1077952D03*
X1081692Y1112598D03*
X1089172Y1116338D03*
X1081692Y1120078D03*
X1089172Y1123818D03*
X1077952Y1112598D03*
X1085432Y1116338D03*
X1077952Y1120078D03*
X1085432Y1123818D03*
X1089172Y1127558D03*
X1085432D03*
X1081692Y1131299D03*
X1077952D03*
X1089172Y1135039D03*
X1085432D03*
X1081692Y1138779D03*
X1077952D03*
X1081692Y1127558D03*
X1089172Y1131299D03*
X1081692Y1135039D03*
X1089172Y1138779D03*
X1077952Y1127558D03*
X1085432Y1131299D03*
X1077952Y1135039D03*
X1085432Y1138779D03*
X1089172Y1142519D03*
X1085432D03*
X1081692D03*
X1077952D03*
X1089172Y1146259D03*
X1085432D03*
X1077952D03*
X1089172Y1149999D03*
X1077952D03*
X1089172Y1153740D03*
X1077952D03*
X1085432D03*
X1081692Y1149999D03*
X1085432D03*
X1081692Y1146259D03*
Y1153740D03*
X1089172Y1157480D03*
X1077952D03*
X1089172Y1161220D03*
X1077952D03*
X1089172Y1164960D03*
X1077952D03*
X1089172Y1168700D03*
X1077952D03*
X1089172Y1172440D03*
X1077952D03*
X1085432Y1164960D03*
Y1172440D03*
Y1168700D03*
X1081692Y1172440D03*
Y1168700D03*
Y1164960D03*
X1085432Y1157480D03*
Y1161220D03*
X1081692D03*
Y1157480D03*
X1089172Y1183661D03*
X1085432D03*
X1081692D03*
X1077952D03*
X1089172Y1187401D03*
X1085432D03*
X1089172Y1176180D03*
X1077952D03*
X1089172Y1179921D03*
X1085432D03*
X1081692D03*
X1077952D03*
X1081692Y1176180D03*
X1085432D03*
X1081692Y1187401D03*
X1077952D03*
X1081692Y1191141D03*
X1077952D03*
X1089172Y1194881D03*
X1085432D03*
X1081692Y1198621D03*
X1077952D03*
X1089172Y1202362D03*
X1085432D03*
X1081692D03*
X1089172Y1198621D03*
X1081692Y1194881D03*
X1089172Y1191141D03*
X1077952Y1202362D03*
X1085432Y1198621D03*
X1077952Y1194881D03*
X1085432Y1191141D03*
X1081692Y1206102D03*
X1077952D03*
X1089172Y1209842D03*
X1085432D03*
X1081692Y1213582D03*
X1077952D03*
X1089172Y1217322D03*
X1085432D03*
X1089172Y1221062D03*
X1085432D03*
X1081692D03*
X1077952D03*
X1081692Y1217322D03*
X1089172Y1213582D03*
X1081692Y1209842D03*
X1089172Y1206102D03*
X1077952Y1217322D03*
X1085432Y1213582D03*
X1077952Y1209842D03*
X1085432Y1206102D03*
X1089172Y1224803D03*
X1081692D03*
X1089172Y1228543D03*
X1081692D03*
X1085432Y1232283D03*
X1077952D03*
X1085432Y1236023D03*
X1077952D03*
X1081692Y1232283D03*
X1077952Y1224803D03*
X1081692Y1236023D03*
X1077952Y1228543D03*
X1085432Y1224803D03*
X1089172Y1232283D03*
X1085432Y1228543D03*
X1089172Y1236023D03*
Y1239763D03*
X1085432D03*
X1081692D03*
X1077952D03*
X1089172Y1243503D03*
X1081692D03*
X1089172Y1247243D03*
X1081692D03*
X1085432Y1250984D03*
X1077952D03*
X1081692D03*
X1077952Y1243503D03*
Y1247243D03*
X1085432Y1243503D03*
X1089172Y1250984D03*
X1085432Y1247243D03*
Y1254724D03*
X1077952D03*
X1081692D03*
X1089172D03*
X1107873Y1075196D03*
X1100393D03*
X1092913D03*
X1096653D03*
X1104133D03*
X1107873Y1078936D03*
X1100393D03*
X1092913D03*
X1104133Y1082677D03*
X1096653D03*
X1104133Y1086417D03*
X1096653D03*
X1107873Y1090157D03*
X1104133D03*
X1100393D03*
X1096653D03*
X1092913D03*
Y1086417D03*
X1096653Y1078936D03*
X1100393Y1086417D03*
X1104133Y1078936D03*
X1107873Y1086417D03*
X1092913Y1082677D03*
X1100393D03*
X1107873D03*
Y1093897D03*
X1100393D03*
X1092913D03*
X1107873Y1097637D03*
X1100393D03*
X1092913D03*
X1104133Y1101377D03*
X1096653D03*
X1104133Y1105117D03*
X1096653D03*
X1092913D03*
X1096653Y1097637D03*
X1100393Y1105117D03*
X1104133Y1097637D03*
X1107873Y1105117D03*
X1092913Y1101377D03*
X1096653Y1093897D03*
X1100393Y1101377D03*
X1104133Y1093897D03*
X1107873Y1101377D03*
Y1108858D03*
X1104133D03*
X1100393D03*
X1096653D03*
X1092913D03*
X1096653Y1112598D03*
X1092913D03*
X1096653Y1116338D03*
X1092913D03*
X1107873Y1120078D03*
X1104133D03*
X1100393D03*
X1096653D03*
X1092913D03*
X1107873Y1123818D03*
X1104133D03*
X1100393D03*
X1096653D03*
X1092913D03*
X1104133Y1116338D03*
X1100393D03*
Y1112598D03*
X1104133D03*
X1107873Y1116338D03*
Y1112598D03*
Y1127558D03*
X1104133D03*
X1100393D03*
X1096653D03*
X1092913D03*
X1104133Y1131299D03*
X1100393D03*
X1096653D03*
X1092913D03*
X1104133Y1135039D03*
X1100393D03*
X1096653D03*
X1092913D03*
X1104133Y1138779D03*
X1096653D03*
X1092913D03*
X1100393D03*
X1107873D03*
Y1131299D03*
Y1135039D03*
X1100393Y1149999D03*
X1104133Y1153740D03*
Y1142519D03*
X1100393D03*
X1096653D03*
X1092913D03*
X1104133Y1146259D03*
X1096653D03*
X1107873Y1149999D03*
X1096653D03*
Y1153740D03*
X1107873Y1142519D03*
X1100393Y1146259D03*
X1092913D03*
Y1149999D03*
Y1153740D03*
X1104133Y1149999D03*
X1100393Y1153740D03*
X1107873Y1146259D03*
Y1153740D03*
X1100393Y1157480D03*
X1104133Y1161220D03*
X1100393Y1164960D03*
X1104133Y1168700D03*
X1100393Y1172440D03*
X1107873Y1157480D03*
X1096653D03*
X1092913D03*
X1096653Y1161220D03*
X1107873Y1164960D03*
X1096653D03*
Y1168700D03*
X1092913D03*
X1107873Y1172440D03*
X1096653D03*
X1092913D03*
Y1161220D03*
Y1164960D03*
X1104133Y1172440D03*
Y1157480D03*
X1100393Y1161220D03*
X1104133Y1164960D03*
X1100393Y1168700D03*
X1107873Y1161220D03*
Y1168700D03*
X1104133Y1176180D03*
X1100393Y1179921D03*
X1104133Y1183661D03*
X1096653D03*
X1092913D03*
X1107873Y1187401D03*
X1104133D03*
X1100393D03*
X1096653D03*
X1092913D03*
X1096653Y1176180D03*
X1107873Y1179921D03*
X1096653D03*
X1092913Y1176180D03*
Y1179921D03*
X1100393Y1183661D03*
Y1176180D03*
X1104133Y1179921D03*
X1107873Y1183661D03*
Y1176180D03*
X1104133Y1191141D03*
X1100393D03*
X1096653D03*
X1092913D03*
X1104133Y1194881D03*
X1100393D03*
X1096653D03*
X1092913D03*
X1104133Y1198621D03*
X1100393D03*
X1096653D03*
X1092913D03*
X1107873Y1202362D03*
X1104133D03*
X1100393D03*
X1096653D03*
X1092913D03*
X1107873Y1191141D03*
Y1198621D03*
Y1194881D03*
Y1206102D03*
X1104133D03*
X1100393D03*
X1096653D03*
X1092913D03*
X1107873Y1209842D03*
X1104133D03*
X1100393D03*
X1096653D03*
X1092913D03*
X1107873Y1213582D03*
X1100393D03*
X1096653D03*
X1092913D03*
X1107873Y1217322D03*
X1096653D03*
X1092913D03*
X1107873Y1221062D03*
X1104133D03*
X1100393D03*
X1096653D03*
X1092913D03*
X1104133Y1217322D03*
X1100393D03*
X1104133Y1213582D03*
Y1224803D03*
X1096653D03*
X1104133Y1228543D03*
X1096653D03*
X1107873Y1232283D03*
X1100393D03*
X1092913D03*
X1107873Y1236023D03*
X1100393D03*
X1092913D03*
Y1224803D03*
X1096653Y1232283D03*
X1100393Y1224803D03*
X1104133Y1232283D03*
X1107873Y1224803D03*
X1092913Y1228543D03*
X1096653Y1236023D03*
X1100393Y1228543D03*
X1104133Y1236023D03*
X1107873Y1228543D03*
Y1239763D03*
X1104133D03*
X1100393D03*
X1096653D03*
X1092913D03*
X1104133Y1243503D03*
X1096653D03*
X1104133Y1247243D03*
X1096653D03*
X1107873Y1250984D03*
X1100393D03*
X1092913D03*
Y1243503D03*
X1096653Y1250984D03*
X1100393Y1243503D03*
X1104133Y1250984D03*
X1107873Y1243503D03*
X1092913Y1247243D03*
X1100393D03*
X1107873D03*
Y1254724D03*
X1100393D03*
X1092913D03*
X1096653D03*
X1104133D03*
X1122834Y1075196D03*
X1115354D03*
X1111613D03*
X1119094D03*
X1122834Y1078936D03*
X1115354D03*
X1119094Y1082677D03*
X1111613D03*
X1119094Y1086417D03*
X1111613D03*
X1122834Y1090157D03*
X1119094D03*
X1115354D03*
X1111613D03*
Y1078936D03*
X1115354Y1086417D03*
X1119094Y1078936D03*
X1122834Y1086417D03*
X1115354Y1082677D03*
X1122834D03*
Y1093897D03*
X1115354D03*
X1122834Y1097637D03*
X1115354D03*
X1119094Y1101377D03*
X1111613D03*
X1119094Y1105117D03*
X1111613D03*
Y1097637D03*
X1115354Y1105117D03*
X1119094Y1097637D03*
X1122834Y1105117D03*
X1111613Y1093897D03*
X1115354Y1101377D03*
X1119094Y1093897D03*
X1122834Y1101377D03*
Y1108858D03*
X1119094D03*
X1115354D03*
X1111613D03*
X1122834Y1120078D03*
X1119094D03*
X1115354D03*
X1111613D03*
X1122834Y1123818D03*
X1119094D03*
X1115354D03*
X1111613D03*
X1115354Y1112598D03*
X1119094Y1116338D03*
X1115354D03*
X1119094Y1112598D03*
X1122834Y1116338D03*
Y1112598D03*
X1111613Y1116338D03*
Y1112598D03*
X1122834Y1127558D03*
X1119094D03*
X1115354D03*
X1111613D03*
Y1131299D03*
X1122834Y1135039D03*
X1119094D03*
X1115354D03*
X1111613D03*
Y1138779D03*
X1122834Y1131299D03*
X1119094D03*
X1115354D03*
X1122834Y1138779D03*
X1119094D03*
X1115354D03*
X1122834Y1142519D03*
X1119094D03*
X1115354D03*
X1111613Y1146259D03*
X1122834Y1149999D03*
X1119094D03*
X1115354D03*
X1111613Y1153740D03*
X1122834Y1146259D03*
X1119094D03*
X1115354D03*
X1122834Y1153740D03*
X1119094D03*
X1115354D03*
X1111613Y1142519D03*
Y1149999D03*
X1122834Y1157480D03*
X1115354D03*
X1119094Y1161220D03*
X1111613D03*
X1122834Y1164960D03*
X1115354D03*
X1119094Y1168700D03*
X1111613D03*
X1122834Y1172440D03*
X1115354D03*
X1119094Y1157480D03*
X1111613D03*
X1122834Y1161220D03*
X1115354D03*
X1119094Y1164960D03*
X1111613D03*
X1122834Y1168700D03*
X1115354D03*
X1119094Y1172440D03*
X1111613D03*
Y1183661D03*
X1122834Y1187401D03*
X1119094D03*
X1115354D03*
X1111613D03*
Y1176180D03*
X1122834Y1179921D03*
X1119094D03*
X1115354D03*
X1122834Y1183661D03*
X1119094D03*
X1115354D03*
X1122834Y1176180D03*
X1119094D03*
X1115354D03*
X1111613Y1179921D03*
Y1191141D03*
X1122834Y1194881D03*
X1119094D03*
X1115354D03*
X1111613D03*
Y1198621D03*
X1122834Y1202362D03*
X1119094D03*
X1115354D03*
X1111613D03*
X1122834Y1198621D03*
X1119094D03*
X1115354D03*
X1122834Y1191141D03*
X1119094D03*
X1115354D03*
X1122834Y1206102D03*
X1119094D03*
X1115354D03*
X1111613D03*
X1122834Y1209842D03*
X1119094D03*
X1115354D03*
X1111613D03*
X1122834Y1221062D03*
X1119094D03*
X1115354D03*
X1111613D03*
X1119094Y1213582D03*
X1115354D03*
X1122834Y1217322D03*
Y1213582D03*
X1119094Y1217322D03*
X1111613Y1213582D03*
X1115354Y1217322D03*
X1111613D03*
X1119094Y1224803D03*
X1111613D03*
X1119094Y1228543D03*
X1111613D03*
X1122834Y1232283D03*
X1115354D03*
X1122834Y1236023D03*
X1115354D03*
X1111613Y1232283D03*
X1115354Y1224803D03*
X1119094Y1232283D03*
X1122834Y1224803D03*
X1111613Y1236023D03*
X1115354Y1228543D03*
X1119094Y1236023D03*
X1122834Y1228543D03*
Y1239763D03*
X1119094D03*
X1115354D03*
X1111613D03*
X1119094Y1243503D03*
X1111613D03*
X1119094Y1247243D03*
X1111613D03*
X1122834Y1250984D03*
X1115354D03*
X1111613D03*
X1115354Y1243503D03*
X1119094Y1250984D03*
X1122834Y1243503D03*
X1115354Y1247243D03*
X1122834D03*
Y1254724D03*
X1115354D03*
X1111613D03*
X1119094D03*
X1137795Y1075196D03*
X1130314D03*
X1126574D03*
X1134054D03*
X1137795Y1078936D03*
X1130314D03*
X1134054Y1082677D03*
X1126574D03*
X1134054Y1086417D03*
X1126574D03*
X1137795Y1090157D03*
X1134054D03*
X1130314D03*
X1126574D03*
Y1078936D03*
X1130314Y1086417D03*
X1134054Y1078936D03*
X1137795Y1086417D03*
X1130314Y1082677D03*
X1137795D03*
Y1093897D03*
X1130314D03*
X1137795Y1097637D03*
X1130314D03*
X1134054Y1101377D03*
X1126574D03*
X1134054Y1105117D03*
X1126574D03*
Y1097637D03*
X1130314Y1105117D03*
X1134054Y1097637D03*
X1137795Y1105117D03*
X1126574Y1093897D03*
X1130314Y1101377D03*
X1134054Y1093897D03*
X1137795Y1101377D03*
Y1108858D03*
X1134054D03*
X1130314D03*
X1126574D03*
X1130314Y1112598D03*
Y1116338D03*
X1137795Y1120078D03*
X1134054D03*
X1130314D03*
X1126574D03*
X1137795Y1123818D03*
X1134054D03*
X1130314D03*
X1126574D03*
X1137795Y1112598D03*
Y1116338D03*
X1134054D03*
Y1112598D03*
X1126574Y1116338D03*
Y1112598D03*
X1137795Y1127558D03*
X1134054D03*
X1130314D03*
X1126574D03*
X1137795Y1135039D03*
X1134054D03*
X1130314D03*
X1126574D03*
X1137795Y1131299D03*
X1134054D03*
X1130314D03*
X1126574D03*
X1137795Y1138779D03*
X1134054D03*
X1130314D03*
X1126574D03*
X1137795Y1142519D03*
X1134054D03*
X1130314D03*
X1126574D03*
X1137795Y1149999D03*
X1134054D03*
X1130314D03*
X1126574D03*
X1137795Y1146259D03*
X1134054D03*
X1130314D03*
X1126574D03*
X1137795Y1153740D03*
X1134054D03*
X1130314D03*
X1126574D03*
X1137795Y1157480D03*
X1130314D03*
X1134054Y1161220D03*
X1126574D03*
X1137795Y1164960D03*
X1130314D03*
X1134054Y1168700D03*
X1126574D03*
X1137795Y1172440D03*
X1130314D03*
X1134054Y1157480D03*
X1126574D03*
X1137795Y1161220D03*
X1130314D03*
X1134054Y1164960D03*
X1126574D03*
X1137795Y1168700D03*
X1130314D03*
X1134054Y1172440D03*
X1126574D03*
X1137795Y1187401D03*
X1134054D03*
X1130314D03*
X1126574D03*
X1137795Y1179921D03*
X1134054D03*
X1130314D03*
X1126574D03*
X1137795Y1183661D03*
X1134054D03*
X1130314D03*
X1126574D03*
X1137795Y1176180D03*
X1134054D03*
X1130314D03*
X1126574D03*
X1137795Y1194881D03*
X1134054D03*
X1130314D03*
X1126574D03*
X1137795Y1202362D03*
X1134054D03*
X1130314D03*
X1126574D03*
X1137795Y1198621D03*
X1134054D03*
X1130314D03*
X1126574D03*
X1137795Y1191141D03*
X1134054D03*
X1130314D03*
X1126574D03*
X1137795Y1206102D03*
X1134054D03*
X1130314D03*
X1126574D03*
X1137795Y1209842D03*
X1134054D03*
X1130314D03*
X1126574D03*
X1134054Y1213582D03*
Y1217322D03*
X1137795Y1221062D03*
X1134054D03*
X1130314D03*
X1126574D03*
X1137795Y1213582D03*
Y1217322D03*
X1126574Y1213582D03*
X1130314Y1217322D03*
Y1213582D03*
X1126574Y1217322D03*
X1134054Y1224803D03*
X1126574D03*
X1134054Y1228543D03*
X1126574D03*
X1137795Y1232283D03*
X1130314D03*
X1137795Y1236023D03*
X1130314D03*
Y1224803D03*
X1134054Y1232283D03*
X1137795Y1224803D03*
X1126574Y1232283D03*
X1130314Y1228543D03*
X1134054Y1236023D03*
X1137795Y1228543D03*
X1126574Y1236023D03*
X1137795Y1239763D03*
X1134054D03*
X1130314D03*
X1126574D03*
X1134054Y1243503D03*
X1126574D03*
X1134054Y1247243D03*
X1126574D03*
X1137795Y1250984D03*
X1130314D03*
Y1243503D03*
X1134054Y1250984D03*
X1137795Y1243503D03*
X1126574Y1250984D03*
X1130314Y1247243D03*
X1137795D03*
Y1254724D03*
X1130314D03*
X1134054D03*
X1126574D03*
X1152755Y1075196D03*
X1145275D03*
X1141535D03*
X1156495D03*
X1149015D03*
X1152755Y1078936D03*
X1145275D03*
X1156495Y1082677D03*
X1149015D03*
X1141535D03*
X1156495Y1086417D03*
X1149015D03*
X1141535D03*
X1156495Y1090157D03*
X1152755D03*
X1149015D03*
X1145275D03*
X1141535D03*
Y1078936D03*
X1145275Y1086417D03*
Y1082677D03*
X1156495Y1078936D03*
X1152755Y1086417D03*
X1149015Y1078936D03*
X1152755Y1082677D03*
Y1093897D03*
X1145275D03*
X1152755Y1097637D03*
X1145275D03*
X1156495Y1101377D03*
X1149015D03*
X1141535D03*
X1156495Y1105117D03*
X1149015D03*
X1141535D03*
Y1097637D03*
X1145275Y1105117D03*
X1141535Y1093897D03*
X1145275Y1101377D03*
X1156495Y1097637D03*
X1152755Y1105117D03*
X1149015Y1097637D03*
X1156495Y1093897D03*
X1152755Y1101377D03*
X1149015Y1093897D03*
X1156495Y1108858D03*
X1152755D03*
X1149015D03*
X1145275D03*
X1141535D03*
X1145275Y1112598D03*
Y1116338D03*
X1156495Y1120078D03*
X1152755D03*
X1149015D03*
X1145275D03*
X1141535D03*
X1156495Y1123818D03*
X1152755D03*
X1149015D03*
X1145275D03*
X1141535D03*
Y1116338D03*
Y1112598D03*
X1152755Y1116338D03*
X1149015Y1112598D03*
X1156495Y1116338D03*
X1149015D03*
X1156495Y1112598D03*
X1152755D03*
X1156495Y1127558D03*
X1152755D03*
X1149015D03*
X1145275D03*
X1141535D03*
X1156495Y1135039D03*
X1152755D03*
X1149015D03*
X1145275D03*
X1141535D03*
X1156495Y1131299D03*
X1152755D03*
X1149015D03*
X1145275D03*
X1141535D03*
X1156495Y1138779D03*
X1152755D03*
X1149015D03*
X1145275D03*
X1141535D03*
X1156495Y1142519D03*
X1152755D03*
X1149015D03*
X1145275D03*
X1141535D03*
X1156495Y1149999D03*
X1152755D03*
X1149015D03*
X1145275D03*
X1141535D03*
X1156495Y1146259D03*
X1152755D03*
X1149015D03*
X1145275D03*
X1141535D03*
X1156495Y1153740D03*
X1152755D03*
X1149015D03*
X1145275D03*
X1141535D03*
X1152755Y1157480D03*
X1145275D03*
X1156495Y1161220D03*
X1149015D03*
X1141535D03*
X1152755Y1164960D03*
X1145275D03*
X1156495Y1168700D03*
X1149015D03*
X1141535D03*
X1152755Y1172440D03*
X1145275D03*
X1156495Y1157480D03*
X1149015D03*
X1141535D03*
X1152755Y1161220D03*
X1145275D03*
X1156495Y1164960D03*
X1149015D03*
X1141535D03*
X1152755Y1168700D03*
X1145275D03*
X1156495Y1172440D03*
X1149015D03*
X1141535D03*
X1156495Y1187401D03*
X1152755D03*
X1149015D03*
X1145275D03*
X1141535D03*
X1156495Y1179921D03*
X1152755D03*
X1149015D03*
X1145275D03*
X1141535D03*
X1156495Y1183661D03*
X1152755D03*
X1149015D03*
X1145275D03*
X1141535D03*
X1156495Y1176180D03*
X1152755D03*
X1149015D03*
X1145275D03*
X1141535D03*
X1156495Y1194881D03*
X1152755D03*
X1149015D03*
X1145275D03*
X1141535D03*
X1156495Y1202362D03*
X1152755D03*
X1149015D03*
X1145275D03*
X1141535D03*
X1156495Y1198621D03*
X1152755D03*
X1149015D03*
X1145275D03*
X1141535D03*
X1156495Y1191141D03*
X1152755D03*
X1149015D03*
X1145275D03*
X1141535D03*
X1156495Y1206102D03*
X1152755D03*
X1149015D03*
X1145275D03*
X1141535D03*
X1156495Y1209842D03*
X1152755D03*
X1149015D03*
X1145275D03*
X1141535D03*
X1156495Y1221062D03*
X1152755D03*
X1149015D03*
X1145275D03*
X1141535D03*
X1152755Y1217322D03*
X1145275Y1213582D03*
X1141535Y1217322D03*
Y1213582D03*
X1145275Y1217322D03*
X1156495Y1213582D03*
X1149015Y1217322D03*
Y1213582D03*
X1156495Y1217322D03*
X1152755Y1213582D03*
X1156495Y1224803D03*
X1149015D03*
X1141535D03*
X1156495Y1228543D03*
X1149015D03*
X1141535D03*
X1152755Y1232283D03*
X1145275D03*
X1152755Y1236023D03*
X1145275D03*
X1141535Y1232283D03*
Y1236023D03*
X1156495Y1232283D03*
X1152755Y1224803D03*
X1149015Y1232283D03*
X1145275Y1224803D03*
X1156495Y1236023D03*
X1152755Y1228543D03*
X1149015Y1236023D03*
X1145275Y1228543D03*
X1156495Y1239763D03*
X1152755D03*
X1149015D03*
X1145275D03*
X1141535D03*
X1156495Y1243503D03*
X1149015D03*
X1141535D03*
X1156495Y1247243D03*
X1149015D03*
X1141535D03*
X1152755Y1250984D03*
X1145275D03*
X1141535D03*
X1156495D03*
X1152755Y1243503D03*
X1149015Y1250984D03*
X1145275Y1243503D03*
X1152755Y1247243D03*
X1145275D03*
X1152755Y1254724D03*
X1145275D03*
X1141535D03*
X1156495D03*
X1149015D03*
X1167716Y1075196D03*
X1160235D03*
X1171456D03*
X1163976D03*
X1167716Y1078936D03*
X1160235D03*
X1171456Y1082677D03*
X1163976D03*
X1171456Y1086417D03*
X1163976D03*
X1171456Y1090157D03*
X1167716D03*
X1163976D03*
X1160235D03*
X1171456Y1078936D03*
X1167716Y1086417D03*
X1163976Y1078936D03*
X1160235Y1086417D03*
X1167716Y1082677D03*
X1160235D03*
X1167716Y1093897D03*
X1160235D03*
X1167716Y1097637D03*
X1160235D03*
X1171456Y1101377D03*
X1163976D03*
X1171456Y1105117D03*
X1163976D03*
X1171456Y1097637D03*
X1167716Y1105117D03*
X1163976Y1097637D03*
X1160235Y1105117D03*
X1171456Y1093897D03*
X1167716Y1101377D03*
X1163976Y1093897D03*
X1160235Y1101377D03*
X1171456Y1108858D03*
X1167716D03*
X1163976D03*
X1160235D03*
X1171456Y1120078D03*
X1167716D03*
X1163976D03*
X1160235D03*
X1171456Y1123818D03*
X1167716D03*
X1163976D03*
X1160235D03*
X1167716Y1116338D03*
X1163976D03*
X1160235D03*
X1163976Y1112598D03*
X1171456Y1116338D03*
X1160235Y1112598D03*
X1171456D03*
X1167716D03*
X1171456Y1127558D03*
X1167716D03*
X1163976D03*
X1160235D03*
X1171456Y1135039D03*
X1167716D03*
X1163976D03*
X1160235D03*
X1171456Y1131299D03*
X1167716D03*
X1163976D03*
X1160235D03*
X1171456Y1138779D03*
X1167716D03*
X1163976D03*
X1160235D03*
X1171456Y1142519D03*
X1167716D03*
X1163976D03*
X1160235D03*
X1171456Y1149999D03*
X1167716D03*
X1163976D03*
X1160235D03*
X1171456Y1146259D03*
X1167716D03*
X1163976D03*
X1160235D03*
X1171456Y1153740D03*
X1167716D03*
X1163976D03*
X1160235D03*
X1167716Y1157480D03*
X1160235D03*
X1171456Y1161220D03*
X1163976D03*
X1167716Y1164960D03*
X1160235D03*
X1171456Y1168700D03*
X1163976D03*
X1167716Y1172440D03*
X1160235D03*
X1171456Y1157480D03*
X1163976D03*
X1167716Y1161220D03*
X1160235D03*
X1171456Y1164960D03*
X1163976D03*
X1167716Y1168700D03*
X1160235D03*
X1171456Y1172440D03*
X1163976D03*
X1171456Y1187401D03*
X1167716D03*
X1163976D03*
X1160235D03*
X1171456Y1179921D03*
X1167716D03*
X1163976D03*
X1160235D03*
X1171456Y1183661D03*
X1167716D03*
X1163976D03*
X1160235D03*
X1171456Y1176180D03*
X1167716D03*
X1163976D03*
X1160235D03*
X1171456Y1194881D03*
X1167716D03*
X1163976D03*
X1160235D03*
X1171456Y1202362D03*
X1167716D03*
X1163976D03*
X1160235D03*
X1171456Y1198621D03*
X1167716D03*
X1163976D03*
X1160235D03*
X1171456Y1191141D03*
X1167716D03*
X1163976D03*
X1160235D03*
X1171456Y1206102D03*
X1167716D03*
X1163976D03*
X1160235D03*
X1171456Y1209842D03*
X1167716D03*
X1163976D03*
X1160235D03*
X1171456Y1221062D03*
X1167716D03*
X1163976D03*
X1160235D03*
Y1213582D03*
X1163976D03*
X1171456Y1217322D03*
X1163976D03*
X1171456Y1213582D03*
X1167716D03*
X1160235Y1217322D03*
X1167716D03*
X1171456Y1224803D03*
X1163976D03*
X1171456Y1228543D03*
X1163976D03*
X1167716Y1232283D03*
X1160235D03*
X1167716Y1236023D03*
X1160235D03*
X1171456Y1232283D03*
X1167716Y1224803D03*
X1163976Y1232283D03*
X1160235Y1224803D03*
X1171456Y1236023D03*
X1167716Y1228543D03*
X1163976Y1236023D03*
X1160235Y1228543D03*
X1171456Y1239763D03*
X1167716D03*
X1163976D03*
X1160235D03*
X1171456Y1243503D03*
X1163976D03*
X1171456Y1247243D03*
X1163976D03*
X1167716Y1250984D03*
X1160235D03*
X1171456D03*
X1167716Y1243503D03*
X1163976Y1250984D03*
X1160235Y1243503D03*
X1167716Y1247243D03*
X1160235D03*
X1167716Y1254724D03*
X1160235D03*
X1171456D03*
X1163976D03*
X1182676Y1075196D03*
X1175196D03*
X1186417D03*
X1178936D03*
X1182676Y1078936D03*
X1175196D03*
X1186417Y1082677D03*
X1178936D03*
X1186417Y1086417D03*
X1178936D03*
X1186417Y1090157D03*
X1182676D03*
X1178936D03*
X1175196D03*
X1186417Y1078936D03*
X1182676Y1086417D03*
X1178936Y1078936D03*
X1175196Y1086417D03*
X1182676Y1082677D03*
X1175196D03*
X1182676Y1093897D03*
X1175196D03*
X1182676Y1097637D03*
X1175196D03*
X1186417Y1101377D03*
X1178936D03*
X1186417Y1105117D03*
X1178936D03*
X1186417Y1097637D03*
X1182676Y1105117D03*
X1178936Y1097637D03*
X1175196Y1105117D03*
X1186417Y1093897D03*
X1182676Y1101377D03*
X1178936Y1093897D03*
X1175196Y1101377D03*
X1186417Y1108858D03*
X1182676D03*
X1178936D03*
X1175196D03*
X1186417Y1120078D03*
X1182676D03*
X1178936D03*
X1175196D03*
X1186417Y1123818D03*
X1182676D03*
X1178936D03*
X1175196D03*
X1186417Y1116338D03*
X1178936D03*
Y1112598D03*
X1186417D03*
X1182676Y1116338D03*
X1175196Y1112598D03*
Y1116338D03*
X1182676Y1112598D03*
X1186417Y1127558D03*
X1182676D03*
X1178936D03*
X1175196D03*
X1182676Y1131299D03*
X1186417Y1135039D03*
X1182676D03*
X1178936D03*
X1175196D03*
X1182676Y1138779D03*
X1186417Y1131299D03*
Y1138779D03*
X1178936Y1131299D03*
X1175196D03*
X1178936Y1138779D03*
X1175196D03*
X1182676Y1142519D03*
X1178936D03*
X1175196D03*
X1182676Y1146259D03*
X1186417Y1149999D03*
X1182676D03*
X1178936D03*
X1175196D03*
X1186417Y1153740D03*
X1182676D03*
X1178936Y1146259D03*
X1175196D03*
X1178936Y1153740D03*
X1175196D03*
X1186417Y1142519D03*
Y1146259D03*
Y1157480D03*
X1182676D03*
X1175196D03*
X1186417Y1161220D03*
Y1164960D03*
X1175196D03*
X1186417Y1168700D03*
Y1172440D03*
X1182676D03*
X1175196D03*
X1182676Y1161220D03*
X1178936D03*
X1175196D03*
X1182676Y1164960D03*
X1178936D03*
X1182676Y1168700D03*
X1178936D03*
X1175196D03*
X1178936Y1157480D03*
Y1172440D03*
X1182676Y1183661D03*
Y1187401D03*
X1178936D03*
X1175196D03*
X1182676Y1176180D03*
X1178936Y1179921D03*
X1175196D03*
X1178936Y1183661D03*
X1175196D03*
X1178936Y1176180D03*
X1175196D03*
X1182676Y1179921D03*
X1186417Y1183661D03*
Y1187401D03*
Y1179921D03*
Y1176180D03*
X1182676Y1191141D03*
X1186417Y1194881D03*
X1182676D03*
X1178936D03*
X1175196D03*
X1182676Y1198621D03*
X1186417Y1202362D03*
X1182676D03*
X1178936D03*
X1175196D03*
X1186417Y1198621D03*
Y1191141D03*
X1178936Y1198621D03*
X1175196D03*
X1178936Y1191141D03*
X1175196D03*
X1186417Y1206102D03*
X1182676D03*
X1178936D03*
X1175196D03*
X1186417Y1209842D03*
X1182676D03*
X1178936D03*
X1175196D03*
X1186417Y1221062D03*
X1182676D03*
X1178936D03*
X1175196D03*
X1182676Y1217322D03*
X1186417Y1213582D03*
X1175196D03*
X1182676D03*
X1178936D03*
Y1217322D03*
X1186417D03*
X1175196D03*
X1186417Y1224803D03*
X1178936D03*
X1186417Y1228543D03*
X1178936D03*
X1182676Y1232283D03*
X1175196D03*
X1182676Y1236023D03*
X1175196D03*
X1186417Y1232283D03*
X1182676Y1224803D03*
X1178936Y1232283D03*
X1175196Y1224803D03*
X1186417Y1236023D03*
X1182676Y1228543D03*
X1178936Y1236023D03*
X1175196Y1228543D03*
X1186417Y1239763D03*
X1182676D03*
X1178936D03*
X1175196D03*
X1186417Y1243503D03*
X1178936D03*
X1186417Y1247243D03*
X1178936D03*
X1182676Y1250984D03*
X1175196D03*
X1186417D03*
X1182676Y1243503D03*
X1178936Y1250984D03*
X1175196Y1243503D03*
X1182676Y1247243D03*
X1175196D03*
X1182676Y1254724D03*
X1175196D03*
X1186417D03*
X1178936D03*
X1205117Y1075196D03*
X1197637D03*
X1190157D03*
X1201377D03*
X1193897D03*
X1205117Y1078936D03*
X1197637D03*
X1190157D03*
X1201377Y1082677D03*
X1193897D03*
X1201377Y1086417D03*
X1193897D03*
X1205117Y1090157D03*
X1201377D03*
X1197637D03*
X1193897D03*
X1190157D03*
X1205117Y1086417D03*
X1201377Y1078936D03*
X1197637Y1086417D03*
X1193897Y1078936D03*
X1190157Y1086417D03*
X1205117Y1082677D03*
X1197637D03*
X1190157D03*
X1205117Y1093897D03*
X1197637D03*
X1190157D03*
X1205117Y1097637D03*
X1197637D03*
X1190157D03*
X1201377Y1101377D03*
X1193897D03*
X1201377Y1105117D03*
X1193897D03*
X1205117D03*
X1201377Y1097637D03*
X1197637Y1105117D03*
X1193897Y1097637D03*
X1190157Y1105117D03*
X1205117Y1101377D03*
X1201377Y1093897D03*
X1197637Y1101377D03*
X1193897Y1093897D03*
X1190157Y1101377D03*
X1205117Y1108858D03*
X1201377D03*
X1197637D03*
X1193897D03*
X1190157D03*
X1205117Y1112598D03*
Y1116338D03*
Y1120078D03*
X1193897D03*
X1190157D03*
X1205117Y1123818D03*
X1193897D03*
X1190157D03*
X1197637Y1120078D03*
X1193897Y1112598D03*
Y1116338D03*
X1197637D03*
X1190157Y1112598D03*
X1197637Y1123818D03*
X1201377Y1116338D03*
Y1123818D03*
X1190157Y1116338D03*
X1201377Y1120078D03*
Y1112598D03*
X1197637D03*
X1205117Y1127558D03*
X1193897D03*
X1205117Y1131299D03*
X1193897D03*
X1205117Y1135039D03*
X1193897D03*
X1205117Y1138779D03*
X1193897D03*
X1190157D03*
Y1127558D03*
Y1135039D03*
Y1131299D03*
X1201377Y1127558D03*
Y1131299D03*
X1197637Y1127558D03*
Y1131299D03*
X1201377Y1138779D03*
X1197637Y1135039D03*
X1201377D03*
X1197637Y1138779D03*
X1205117Y1142519D03*
X1193897D03*
X1190157D03*
X1205117Y1146259D03*
X1193897D03*
X1190157D03*
X1205117Y1149999D03*
X1193897D03*
X1190157D03*
X1205117Y1153740D03*
X1201377D03*
X1197637D03*
X1193897D03*
X1190157D03*
X1197637Y1142519D03*
X1201377Y1149999D03*
X1197637D03*
Y1146259D03*
X1201377Y1142519D03*
Y1146259D03*
X1205117Y1157480D03*
X1201377D03*
X1193897D03*
X1205117Y1161220D03*
X1201377D03*
X1193897D03*
X1205117Y1164960D03*
X1201377D03*
X1193897D03*
X1205117Y1168700D03*
X1201377D03*
X1193897D03*
X1205117Y1172440D03*
X1201377D03*
X1193897D03*
X1197637Y1157480D03*
Y1161220D03*
Y1164960D03*
Y1168700D03*
Y1172440D03*
X1190157Y1157480D03*
Y1161220D03*
Y1164960D03*
Y1168700D03*
Y1172440D03*
X1205117Y1183661D03*
X1197637D03*
X1193897D03*
X1190157D03*
X1205117Y1187401D03*
X1193897D03*
X1190157D03*
X1205117Y1176180D03*
X1201377D03*
X1197637D03*
X1193897D03*
X1190157D03*
X1205117Y1179921D03*
X1197637D03*
X1190157D03*
X1201377Y1187401D03*
X1193897Y1179921D03*
X1197637Y1187401D03*
X1201377Y1179921D03*
Y1183661D03*
X1205117Y1191141D03*
X1197637D03*
X1193897D03*
X1190157D03*
X1205117Y1194881D03*
X1193897D03*
X1205117Y1198621D03*
X1193897D03*
X1205117Y1202362D03*
X1193897D03*
X1201377Y1191141D03*
X1190157Y1198621D03*
Y1202362D03*
Y1194881D03*
X1197637D03*
Y1202362D03*
X1201377Y1194881D03*
Y1202362D03*
Y1198621D03*
X1197637D03*
X1205117Y1206102D03*
X1193897D03*
X1205117Y1209842D03*
X1193897D03*
X1190157D03*
X1205117Y1213582D03*
Y1217322D03*
Y1221062D03*
X1201377D03*
X1197637D03*
X1193897D03*
X1190157D03*
Y1206102D03*
X1201377Y1217322D03*
X1197637Y1209842D03*
Y1213582D03*
X1190157Y1217322D03*
Y1213582D03*
X1193897D03*
X1197637Y1217322D03*
X1201377Y1213582D03*
Y1209842D03*
X1193897Y1217322D03*
X1197637Y1206102D03*
X1201377D03*
Y1224803D03*
X1193897D03*
X1201377Y1228543D03*
X1193897D03*
X1205117Y1232283D03*
X1197637D03*
X1190157D03*
X1205117Y1236023D03*
X1197637D03*
X1190157D03*
X1201377Y1232283D03*
X1197637Y1224803D03*
X1193897Y1232283D03*
X1190157Y1224803D03*
X1201377Y1236023D03*
X1197637Y1228543D03*
X1193897Y1236023D03*
X1190157Y1228543D03*
X1205117Y1224803D03*
Y1228543D03*
Y1239763D03*
X1201377D03*
X1197637D03*
X1193897D03*
X1190157D03*
X1201377Y1243503D03*
X1193897D03*
X1201377Y1247243D03*
X1193897D03*
X1205117Y1250984D03*
X1197637D03*
X1190157D03*
X1201377D03*
X1197637Y1243503D03*
X1193897Y1250984D03*
X1190157Y1243503D03*
X1197637Y1247243D03*
X1190157D03*
X1205117Y1243503D03*
Y1247243D03*
Y1254724D03*
X1197637D03*
X1190157D03*
X1201377D03*
X1193897D03*
X1220078Y1075196D03*
X1212598D03*
X1208858D03*
X1216338D03*
X1220078Y1078936D03*
X1212598D03*
X1216338Y1082677D03*
X1208858D03*
X1216338Y1086417D03*
X1208858D03*
X1220078Y1090157D03*
X1216338D03*
X1212598D03*
X1208858D03*
Y1078936D03*
X1212598Y1086417D03*
X1216338Y1078936D03*
X1220078Y1086417D03*
X1212598Y1082677D03*
X1220078D03*
Y1093897D03*
X1212598D03*
X1220078Y1097637D03*
X1212598D03*
X1216338Y1101377D03*
X1208858D03*
X1216338Y1105117D03*
X1208858D03*
Y1097637D03*
X1212598Y1105117D03*
X1216338Y1097637D03*
X1220078Y1105117D03*
X1208858Y1093897D03*
X1212598Y1101377D03*
X1216338Y1093897D03*
X1220078Y1101377D03*
Y1108858D03*
X1216338D03*
X1212598D03*
X1208858D03*
X1212598Y1112598D03*
X1208858D03*
X1220078Y1116338D03*
X1216338D03*
X1212598Y1120078D03*
X1208858D03*
X1220078Y1123818D03*
X1216338D03*
Y1112598D03*
X1208858Y1116338D03*
X1216338Y1120078D03*
X1208858Y1123818D03*
X1220078Y1112598D03*
X1212598Y1116338D03*
X1220078Y1120078D03*
X1212598Y1123818D03*
Y1127558D03*
X1208858D03*
X1220078Y1131299D03*
X1216338D03*
X1212598Y1135039D03*
X1208858D03*
X1220078Y1138779D03*
X1216338D03*
X1208858D03*
X1212598D03*
X1216338Y1127558D03*
X1208858Y1131299D03*
X1216338Y1135039D03*
X1220078Y1127558D03*
X1212598Y1131299D03*
X1220078Y1135039D03*
X1212598Y1142519D03*
X1208858D03*
X1220078Y1146259D03*
X1216338D03*
X1212598Y1149999D03*
X1208858D03*
X1220078Y1153740D03*
X1216338D03*
Y1142519D03*
X1208858Y1146259D03*
X1216338Y1149999D03*
X1208858Y1153740D03*
X1220078Y1142519D03*
X1212598Y1146259D03*
X1220078Y1149999D03*
X1212598Y1153740D03*
Y1157480D03*
X1208858D03*
X1220078Y1161220D03*
X1216338D03*
X1212598Y1164960D03*
X1208858D03*
X1220078Y1168700D03*
X1216338D03*
X1212598Y1172440D03*
X1208858D03*
X1216338Y1157480D03*
X1208858Y1161220D03*
X1216338Y1164960D03*
X1208858Y1168700D03*
X1216338Y1172440D03*
X1220078Y1157480D03*
X1212598Y1161220D03*
X1220078Y1164960D03*
X1212598Y1168700D03*
X1220078Y1172440D03*
Y1183661D03*
X1216338D03*
X1212598Y1187401D03*
X1208858D03*
X1220078Y1176180D03*
X1216338D03*
X1212598Y1179921D03*
X1208858D03*
Y1176180D03*
X1216338Y1179921D03*
X1208858Y1183661D03*
X1216338Y1187401D03*
X1212598Y1176180D03*
X1220078Y1179921D03*
X1212598Y1183661D03*
X1220078Y1187401D03*
Y1191141D03*
X1216338D03*
X1212598Y1194881D03*
X1208858D03*
X1220078Y1198621D03*
X1216338D03*
X1212598Y1202362D03*
X1208858D03*
Y1191141D03*
X1216338Y1194881D03*
X1212598Y1191141D03*
X1220078Y1194881D03*
X1216338Y1202362D03*
X1208858Y1198621D03*
X1220078Y1202362D03*
X1212598Y1198621D03*
X1220078Y1206102D03*
X1216338D03*
X1212598Y1209842D03*
X1208858D03*
X1220078Y1213582D03*
X1216338D03*
X1212598Y1217322D03*
X1208858D03*
X1220078Y1221062D03*
X1216338D03*
X1212598D03*
X1208858D03*
X1216338Y1217322D03*
X1208858Y1213582D03*
X1216338Y1209842D03*
X1208858Y1206102D03*
X1220078Y1217322D03*
X1212598Y1213582D03*
X1220078Y1209842D03*
X1212598Y1206102D03*
X1216338Y1224803D03*
X1208858D03*
X1216338Y1228543D03*
X1208858D03*
X1220078Y1232283D03*
X1212598D03*
X1220078Y1236023D03*
X1212598D03*
X1208858Y1232283D03*
X1212598Y1224803D03*
X1216338Y1232283D03*
X1220078Y1224803D03*
X1208858Y1236023D03*
X1212598Y1228543D03*
X1216338Y1236023D03*
X1220078Y1228543D03*
Y1239763D03*
X1216338D03*
X1212598D03*
X1208858D03*
X1216338Y1243503D03*
X1208858D03*
X1216338Y1247243D03*
X1208858D03*
X1220078Y1250984D03*
X1212598D03*
X1208858D03*
X1212598Y1243503D03*
X1216338Y1250984D03*
X1220078Y1243503D03*
X1212598Y1247243D03*
X1220078D03*
Y1254724D03*
X1212598D03*
X1208858D03*
X1216338D03*
X1235039Y1075196D03*
X1227558D03*
X1231298D03*
X1223818D03*
X1235039Y1078936D03*
X1227558D03*
X1231298Y1082677D03*
X1223818D03*
X1235039Y1086417D03*
X1231298D03*
X1223818D03*
X1231298Y1090157D03*
X1227558D03*
X1223818D03*
X1235039D03*
X1231298Y1078936D03*
X1235039Y1082677D03*
X1223818Y1078936D03*
X1227558Y1086417D03*
Y1082677D03*
X1235039Y1093897D03*
X1227558D03*
X1235039Y1097637D03*
X1227558D03*
X1231298Y1101377D03*
X1223818D03*
X1235039Y1105117D03*
X1231298D03*
X1223818D03*
X1231298Y1097637D03*
X1235039Y1101377D03*
X1223818Y1097637D03*
X1227558Y1105117D03*
X1231298Y1093897D03*
X1223818D03*
X1227558Y1101377D03*
X1231298Y1108858D03*
X1227558D03*
X1223818D03*
X1235039Y1112598D03*
X1223818D03*
X1231298Y1116338D03*
X1227558D03*
X1223818D03*
X1235039Y1120078D03*
X1223818D03*
X1231298Y1123818D03*
X1227558D03*
X1223818D03*
X1235039Y1108858D03*
X1227558Y1112598D03*
X1235039Y1116338D03*
X1227558Y1120078D03*
X1235039Y1123818D03*
X1231298Y1112598D03*
Y1120078D03*
X1235039Y1127558D03*
X1223818D03*
X1231298Y1131299D03*
X1227558D03*
X1223818D03*
X1235039Y1135039D03*
X1223818D03*
X1231298Y1138779D03*
X1227558D03*
X1223818D03*
X1235039D03*
X1227558Y1127558D03*
X1235039Y1131299D03*
X1227558Y1135039D03*
X1231298Y1127558D03*
Y1135039D03*
X1235039Y1142519D03*
X1223818D03*
X1231298Y1146259D03*
X1227558D03*
X1223818D03*
X1235039Y1149999D03*
X1223818D03*
X1231298Y1153740D03*
X1227558D03*
X1223818D03*
X1227558Y1142519D03*
X1235039Y1146259D03*
X1227558Y1149999D03*
X1235039Y1153740D03*
X1231298Y1142519D03*
Y1149999D03*
X1235039Y1157480D03*
X1223818D03*
X1231298Y1161220D03*
X1227558D03*
X1223818D03*
X1235039Y1164960D03*
X1223818D03*
X1231298Y1168700D03*
X1227558D03*
X1223818D03*
X1235039Y1172440D03*
X1223818D03*
X1227558Y1157480D03*
X1235039Y1161220D03*
X1227558Y1164960D03*
X1235039Y1168700D03*
X1227558Y1172440D03*
X1231298Y1157480D03*
Y1164960D03*
Y1172440D03*
Y1183661D03*
X1227558D03*
X1223818D03*
X1235039Y1187401D03*
X1223818D03*
X1231298Y1176180D03*
X1227558D03*
X1223818D03*
X1235039Y1179921D03*
X1223818D03*
X1235039Y1176180D03*
X1227558Y1179921D03*
X1235039Y1183661D03*
X1227558Y1187401D03*
X1231298Y1179921D03*
Y1187401D03*
Y1191141D03*
X1227558D03*
X1223818D03*
X1235039Y1194881D03*
X1223818D03*
X1231298Y1198621D03*
X1227558D03*
X1223818D03*
X1235039Y1202362D03*
X1223818D03*
X1235039Y1191141D03*
X1227558Y1194881D03*
X1231298D03*
X1227558Y1202362D03*
X1235039Y1198621D03*
X1231298Y1202362D03*
Y1206102D03*
X1227558D03*
X1223818D03*
X1235039Y1209842D03*
X1223818D03*
X1231298Y1213582D03*
X1227558D03*
X1223818D03*
X1235039Y1217322D03*
X1223818D03*
X1231298Y1221062D03*
X1227558D03*
X1223818D03*
X1235039D03*
X1227558Y1217322D03*
X1235039Y1213582D03*
X1227558Y1209842D03*
X1235039Y1206102D03*
X1231298Y1217322D03*
Y1209842D03*
X1235039Y1224803D03*
X1231298D03*
X1223818D03*
X1231298Y1228543D03*
X1223818D03*
X1235039Y1232283D03*
X1227558D03*
X1235039Y1236023D03*
X1227558D03*
X1223818Y1232283D03*
X1227558Y1224803D03*
X1231298Y1232283D03*
X1235039Y1228543D03*
X1223818Y1236023D03*
X1227558Y1228543D03*
X1231298Y1236023D03*
Y1239763D03*
X1227558D03*
X1223818D03*
X1235039Y1243503D03*
X1231298D03*
X1223818D03*
X1231298Y1247243D03*
X1223818D03*
X1235039Y1250984D03*
X1227558D03*
X1235039Y1239763D03*
X1223818Y1250984D03*
X1227558Y1243503D03*
X1231298Y1250984D03*
X1235039Y1247243D03*
X1227558D03*
X1235039Y1254724D03*
X1227558D03*
X1223818D03*
X1231298D03*
X1238779Y1078936D03*
Y1086417D03*
Y1090157D03*
Y1082677D03*
Y1093897D03*
Y1097637D03*
Y1105117D03*
Y1101377D03*
Y1112598D03*
Y1120078D03*
Y1108858D03*
Y1116338D03*
Y1123818D03*
Y1127558D03*
Y1135039D03*
Y1138779D03*
Y1131299D03*
Y1142519D03*
Y1149999D03*
Y1146259D03*
Y1153740D03*
Y1157480D03*
Y1164960D03*
Y1172440D03*
Y1161220D03*
Y1168700D03*
Y1187401D03*
Y1179921D03*
Y1176180D03*
Y1183661D03*
Y1194881D03*
Y1202362D03*
Y1191141D03*
Y1198621D03*
Y1209842D03*
Y1217322D03*
Y1221062D03*
Y1213582D03*
Y1206102D03*
Y1224803D03*
Y1232283D03*
Y1236023D03*
Y1228543D03*
Y1243503D03*
Y1250984D03*
Y1239763D03*
Y1247243D03*
X1527559Y1075196D03*
X1520078D03*
X1523819D03*
X1527559Y1078936D03*
X1520078D03*
X1516338D03*
X1523819Y1082677D03*
Y1086417D03*
X1520078D03*
X1516338D03*
X1527559Y1090157D03*
X1523819D03*
X1520078D03*
X1516338D03*
X1527559Y1086417D03*
X1523819Y1078936D03*
X1520078Y1082677D03*
X1527559D03*
X1516338D03*
X1527559Y1093897D03*
X1520078D03*
X1516338D03*
X1527559Y1097637D03*
X1520078D03*
X1516338D03*
X1523819Y1101377D03*
Y1105117D03*
X1520078D03*
X1516338D03*
X1527559D03*
X1523819Y1097637D03*
X1520078Y1101377D03*
X1527559D03*
X1523819Y1093897D03*
X1516338Y1101377D03*
X1527559Y1108858D03*
X1523819D03*
X1520078Y1112598D03*
X1516338D03*
X1527559Y1116338D03*
X1523819D03*
X1520078Y1120078D03*
X1516338D03*
X1527559Y1123818D03*
X1523819D03*
X1520078Y1108858D03*
X1527559Y1112598D03*
X1520078Y1116338D03*
X1527559Y1120078D03*
X1520078Y1123818D03*
X1516338Y1108858D03*
X1523819Y1112598D03*
X1516338Y1116338D03*
X1523819Y1120078D03*
X1516338Y1123818D03*
X1520078Y1127558D03*
X1516338D03*
X1527559Y1131299D03*
X1523819D03*
X1520078Y1135039D03*
X1516338D03*
X1527559Y1138779D03*
X1523819D03*
X1527559Y1127558D03*
X1520078Y1131299D03*
X1527559Y1135039D03*
X1520078Y1138779D03*
X1523819Y1127558D03*
X1516338Y1131299D03*
X1523819Y1135039D03*
X1516338Y1138779D03*
X1527559Y1142519D03*
X1523819D03*
X1520078D03*
X1516338D03*
X1523819Y1146259D03*
X1520078D03*
X1516338D03*
X1527559Y1149999D03*
X1523819D03*
Y1153740D03*
X1520078D03*
X1516338D03*
X1527559Y1146259D03*
X1520078Y1149999D03*
X1516338D03*
X1527559Y1153740D03*
Y1157480D03*
X1523819D03*
Y1161220D03*
X1520078D03*
X1516338D03*
X1527559Y1164960D03*
X1523819D03*
Y1168700D03*
X1520078D03*
X1516338D03*
X1527559Y1172440D03*
X1523819D03*
X1520078Y1157480D03*
X1516338D03*
X1527559Y1161220D03*
X1520078Y1164960D03*
X1516338D03*
X1527559Y1168700D03*
X1520078Y1172440D03*
X1516338D03*
X1527559Y1183661D03*
X1523819D03*
X1520078D03*
X1516338D03*
X1520078Y1187401D03*
X1516338D03*
X1523819Y1176180D03*
X1520078D03*
X1516338D03*
X1527559Y1179921D03*
X1523819D03*
X1520078D03*
X1516338D03*
X1527559Y1176180D03*
Y1187401D03*
X1523819D03*
X1527559Y1191141D03*
X1523819D03*
X1520078Y1194881D03*
X1516338D03*
X1527559Y1198621D03*
X1523819D03*
X1520078Y1202362D03*
X1516338D03*
X1527559D03*
X1520078Y1198621D03*
X1527559Y1194881D03*
X1520078Y1191141D03*
X1523819Y1202362D03*
X1516338Y1198621D03*
X1523819Y1194881D03*
X1516338Y1191141D03*
X1527559Y1206102D03*
X1523819D03*
X1520078Y1209842D03*
X1516338D03*
X1527559Y1213582D03*
X1523819D03*
X1520078Y1217322D03*
X1516338D03*
X1527559Y1221062D03*
X1523819D03*
X1520078D03*
X1527559Y1217322D03*
X1520078Y1213582D03*
X1527559Y1209842D03*
X1520078Y1206102D03*
X1516338Y1221062D03*
X1523819Y1217322D03*
X1516338Y1213582D03*
X1523819Y1209842D03*
X1516338Y1206102D03*
X1523819Y1224803D03*
X1520078D03*
X1516338D03*
X1523819Y1228543D03*
X1527559Y1232283D03*
X1520078D03*
X1516338D03*
X1527559Y1236023D03*
X1520078D03*
X1516338D03*
X1527559Y1224803D03*
X1523819Y1232283D03*
X1520078Y1228543D03*
X1527559D03*
X1523819Y1236023D03*
X1516338Y1228543D03*
X1527559Y1239763D03*
X1523819D03*
Y1243503D03*
X1520078D03*
X1516338D03*
X1523819Y1247243D03*
X1527559Y1250984D03*
X1520078D03*
X1516338D03*
X1520078Y1239763D03*
X1516338D03*
X1527559Y1243503D03*
X1523819Y1250984D03*
X1520078Y1247243D03*
X1527559D03*
X1516338D03*
X1527559Y1254724D03*
X1520078D03*
X1523819D03*
X1542519Y1075196D03*
X1535039D03*
X1538779D03*
X1531299D03*
X1546259D03*
X1542519Y1078936D03*
X1535039D03*
X1546259Y1082677D03*
X1538779D03*
X1531299D03*
X1546259Y1086417D03*
X1538779D03*
X1531299D03*
X1546259Y1090157D03*
X1542519D03*
X1538779D03*
X1535039D03*
X1531299D03*
X1542519Y1086417D03*
X1538779Y1078936D03*
X1535039Y1086417D03*
X1531299Y1078936D03*
X1542519Y1082677D03*
X1535039D03*
X1546259Y1078936D03*
X1542519Y1093897D03*
X1535039D03*
X1542519Y1097637D03*
X1535039D03*
X1546259Y1101377D03*
X1538779D03*
X1531299D03*
X1546259Y1105117D03*
X1538779D03*
X1531299D03*
X1542519D03*
X1538779Y1097637D03*
X1535039Y1105117D03*
X1531299Y1097637D03*
X1542519Y1101377D03*
X1538779Y1093897D03*
X1535039Y1101377D03*
X1531299Y1093897D03*
X1546259Y1097637D03*
Y1093897D03*
Y1108858D03*
X1542519D03*
X1538779D03*
X1535039D03*
X1531299D03*
X1546259Y1112598D03*
X1542519D03*
X1531299D03*
X1538779Y1116338D03*
X1535039D03*
X1531299D03*
X1546259Y1120078D03*
X1542519D03*
X1531299D03*
X1538779Y1123818D03*
X1535039D03*
X1531299D03*
X1538779Y1112598D03*
X1546259Y1116338D03*
X1538779Y1120078D03*
X1546259Y1123818D03*
X1535039Y1112598D03*
X1542519Y1116338D03*
X1535039Y1120078D03*
X1542519Y1123818D03*
X1546259Y1127558D03*
X1542519D03*
X1531299D03*
X1538779Y1131299D03*
X1535039D03*
X1531299D03*
X1546259Y1135039D03*
X1542519D03*
X1531299D03*
X1538779Y1138779D03*
X1535039D03*
X1531299D03*
X1538779Y1127558D03*
X1546259Y1131299D03*
X1538779Y1135039D03*
X1546259Y1138779D03*
X1535039Y1127558D03*
X1542519Y1131299D03*
X1535039Y1135039D03*
X1542519Y1138779D03*
X1546259Y1142519D03*
X1542519D03*
X1538779D03*
X1535039D03*
X1531299D03*
X1546259Y1146259D03*
X1542519D03*
X1535039D03*
X1546259Y1149999D03*
X1535039D03*
X1531299D03*
X1546259Y1153740D03*
X1535039D03*
X1531299Y1146259D03*
X1542519Y1153740D03*
X1538779Y1149999D03*
X1542519D03*
X1538779Y1146259D03*
Y1153740D03*
X1531299D03*
X1546259Y1157480D03*
X1535039D03*
X1531299D03*
X1546259Y1161220D03*
X1535039D03*
X1546259Y1164960D03*
X1535039D03*
X1531299D03*
X1546259Y1168700D03*
X1535039D03*
X1546259Y1172440D03*
X1535039D03*
X1531299D03*
X1542519Y1164960D03*
Y1172440D03*
Y1168700D03*
X1538779Y1172440D03*
Y1168700D03*
Y1164960D03*
X1542519Y1157480D03*
Y1161220D03*
X1538779D03*
Y1157480D03*
X1531299Y1161220D03*
Y1168700D03*
X1546259Y1183661D03*
X1542519D03*
X1538779D03*
X1535039D03*
X1531299D03*
X1546259Y1187401D03*
X1542519D03*
X1531299D03*
X1546259Y1176180D03*
X1535039D03*
X1546259Y1179921D03*
X1542519D03*
X1538779D03*
X1535039D03*
X1531299D03*
X1538779Y1176180D03*
X1542519D03*
X1531299D03*
X1538779Y1187401D03*
X1535039D03*
X1538779Y1191141D03*
X1535039D03*
X1531299D03*
X1546259Y1194881D03*
X1542519D03*
X1531299D03*
X1538779Y1198621D03*
X1535039D03*
X1531299D03*
X1546259Y1202362D03*
X1542519D03*
X1531299D03*
X1538779D03*
X1546259Y1198621D03*
X1538779Y1194881D03*
X1546259Y1191141D03*
X1535039Y1202362D03*
X1542519Y1198621D03*
X1535039Y1194881D03*
X1542519Y1191141D03*
X1538779Y1206102D03*
X1535039D03*
X1531299D03*
X1546259Y1209842D03*
X1542519D03*
X1531299D03*
X1538779Y1213582D03*
X1535039D03*
X1531299D03*
X1546259Y1217322D03*
X1542519D03*
X1531299D03*
X1546259Y1221062D03*
X1542519D03*
X1538779D03*
X1535039D03*
X1531299D03*
X1538779Y1217322D03*
X1546259Y1213582D03*
X1538779Y1209842D03*
X1546259Y1206102D03*
X1535039Y1217322D03*
X1542519Y1213582D03*
X1535039Y1209842D03*
X1542519Y1206102D03*
X1546259Y1224803D03*
X1538779D03*
X1531299D03*
X1546259Y1228543D03*
X1538779D03*
X1531299D03*
X1542519Y1232283D03*
X1535039D03*
X1542519Y1236023D03*
X1535039D03*
X1538779Y1232283D03*
X1535039Y1224803D03*
X1531299Y1232283D03*
X1538779Y1236023D03*
X1535039Y1228543D03*
X1531299Y1236023D03*
X1542519Y1224803D03*
X1546259Y1232283D03*
X1542519Y1228543D03*
X1546259Y1236023D03*
Y1239763D03*
X1542519D03*
X1538779D03*
X1535039D03*
X1531299D03*
X1546259Y1243503D03*
X1538779D03*
X1531299D03*
X1546259Y1247243D03*
X1538779D03*
X1531299D03*
X1542519Y1250984D03*
X1535039D03*
X1538779D03*
X1535039Y1243503D03*
X1531299Y1250984D03*
X1535039Y1247243D03*
X1542519Y1243503D03*
X1546259Y1250984D03*
X1542519Y1247243D03*
Y1254724D03*
X1535039D03*
X1538779D03*
X1531299D03*
X1546259D03*
X1557480Y1075196D03*
X1550000D03*
X1553740D03*
X1561220D03*
X1557480Y1078936D03*
X1550000D03*
X1561220Y1082677D03*
X1553740D03*
X1561220Y1086417D03*
X1553740D03*
X1561220Y1090157D03*
X1557480D03*
X1553740D03*
X1550000D03*
Y1086417D03*
X1553740Y1078936D03*
X1557480Y1086417D03*
X1561220Y1078936D03*
X1550000Y1082677D03*
X1557480D03*
Y1093897D03*
X1550000D03*
X1557480Y1097637D03*
X1550000D03*
X1561220Y1101377D03*
X1553740D03*
X1561220Y1105117D03*
X1553740D03*
X1550000D03*
X1553740Y1097637D03*
X1557480Y1105117D03*
X1561220Y1097637D03*
X1550000Y1101377D03*
X1553740Y1093897D03*
X1557480Y1101377D03*
X1561220Y1093897D03*
Y1108858D03*
X1557480D03*
X1553740D03*
X1550000D03*
X1553740Y1112598D03*
X1550000D03*
X1553740Y1116338D03*
X1550000D03*
X1561220Y1120078D03*
X1557480D03*
X1553740D03*
X1550000D03*
X1561220Y1123818D03*
X1557480D03*
X1553740D03*
X1550000D03*
X1561220Y1116338D03*
X1557480D03*
Y1112598D03*
X1561220D03*
Y1127558D03*
X1557480D03*
X1553740D03*
X1550000D03*
X1561220Y1131299D03*
X1557480D03*
X1553740D03*
X1550000D03*
X1561220Y1135039D03*
X1557480D03*
X1553740D03*
X1550000D03*
X1561220Y1138779D03*
X1553740D03*
X1550000D03*
X1557480D03*
Y1149999D03*
X1561220Y1153740D03*
Y1142519D03*
X1557480D03*
X1553740D03*
X1550000D03*
X1561220Y1146259D03*
X1553740D03*
Y1149999D03*
Y1153740D03*
X1557480Y1146259D03*
X1550000D03*
Y1149999D03*
Y1153740D03*
X1561220Y1149999D03*
X1557480Y1153740D03*
Y1157480D03*
X1561220Y1161220D03*
X1557480Y1164960D03*
X1561220Y1168700D03*
X1557480Y1172440D03*
X1553740Y1157480D03*
X1550000D03*
X1553740Y1161220D03*
Y1164960D03*
Y1168700D03*
X1550000D03*
X1553740Y1172440D03*
X1550000D03*
Y1161220D03*
Y1164960D03*
X1561220Y1172440D03*
Y1157480D03*
X1557480Y1161220D03*
X1561220Y1164960D03*
X1557480Y1168700D03*
X1561220Y1176180D03*
X1557480Y1179921D03*
X1561220Y1183661D03*
X1553740D03*
X1550000D03*
X1561220Y1187401D03*
X1557480D03*
X1553740D03*
X1550000D03*
X1553740Y1176180D03*
Y1179921D03*
X1550000Y1176180D03*
Y1179921D03*
X1557480Y1183661D03*
Y1176180D03*
X1561220Y1179921D03*
Y1191141D03*
X1557480D03*
X1553740D03*
X1550000D03*
X1561220Y1194881D03*
X1557480D03*
X1553740D03*
X1550000D03*
X1561220Y1198621D03*
X1557480D03*
X1553740D03*
X1550000D03*
X1561220Y1202362D03*
X1557480D03*
X1553740D03*
X1550000D03*
X1561220Y1206102D03*
X1557480D03*
X1553740D03*
X1550000D03*
X1561220Y1209842D03*
X1557480D03*
X1553740D03*
X1550000D03*
X1557480Y1213582D03*
X1553740D03*
X1550000D03*
X1553740Y1217322D03*
X1550000D03*
X1561220Y1221062D03*
X1557480D03*
X1553740D03*
X1550000D03*
X1561220Y1217322D03*
X1557480D03*
X1561220Y1213582D03*
Y1224803D03*
X1553740D03*
X1561220Y1228543D03*
X1553740D03*
X1557480Y1232283D03*
X1550000D03*
X1557480Y1236023D03*
X1550000D03*
Y1224803D03*
X1553740Y1232283D03*
X1557480Y1224803D03*
X1561220Y1232283D03*
X1550000Y1228543D03*
X1553740Y1236023D03*
X1557480Y1228543D03*
X1561220Y1236023D03*
Y1239763D03*
X1557480D03*
X1553740D03*
X1550000D03*
X1561220Y1243503D03*
X1553740D03*
X1561220Y1247243D03*
X1553740D03*
X1557480Y1250984D03*
X1550000D03*
Y1243503D03*
X1553740Y1250984D03*
X1557480Y1243503D03*
X1561220Y1250984D03*
X1550000Y1247243D03*
X1557480D03*
Y1254724D03*
X1550000D03*
X1553740D03*
X1561220D03*
X1572441Y1075196D03*
X1564960D03*
X1568700D03*
X1576181D03*
X1572441Y1078936D03*
X1564960D03*
X1576181Y1082677D03*
X1568700D03*
X1576181Y1086417D03*
X1568700D03*
X1576181Y1090157D03*
X1572441D03*
X1568700D03*
X1564960D03*
Y1086417D03*
X1568700Y1078936D03*
X1572441Y1086417D03*
X1576181Y1078936D03*
X1564960Y1082677D03*
X1572441D03*
Y1093897D03*
X1564960D03*
X1572441Y1097637D03*
X1564960D03*
X1576181Y1101377D03*
X1568700D03*
X1576181Y1105117D03*
X1568700D03*
X1564960D03*
X1568700Y1097637D03*
X1572441Y1105117D03*
X1576181Y1097637D03*
X1564960Y1101377D03*
X1568700Y1093897D03*
X1572441Y1101377D03*
X1576181Y1093897D03*
Y1108858D03*
X1572441D03*
X1568700D03*
X1564960D03*
X1576181Y1120078D03*
X1572441D03*
X1568700D03*
X1564960D03*
X1576181Y1123818D03*
X1572441D03*
X1568700D03*
X1564960D03*
X1572441Y1112598D03*
X1576181Y1116338D03*
X1572441D03*
X1576181Y1112598D03*
X1564960Y1116338D03*
Y1112598D03*
X1568700Y1116338D03*
Y1112598D03*
X1576181Y1127558D03*
X1572441D03*
X1568700D03*
X1564960D03*
X1568700Y1131299D03*
X1576181Y1135039D03*
X1572441D03*
X1568700D03*
Y1138779D03*
X1564960D03*
X1576181Y1131299D03*
X1572441D03*
X1576181Y1138779D03*
X1572441D03*
X1564960Y1131299D03*
Y1135039D03*
X1576181Y1142519D03*
X1572441D03*
X1568700Y1146259D03*
X1576181Y1149999D03*
X1572441D03*
X1564960D03*
X1568700Y1153740D03*
X1576181Y1146259D03*
X1572441D03*
X1576181Y1153740D03*
X1572441D03*
X1564960Y1142519D03*
X1568700D03*
X1564960Y1146259D03*
X1568700Y1149999D03*
X1564960Y1153740D03*
X1572441Y1157480D03*
X1564960D03*
X1576181Y1161220D03*
X1568700D03*
X1572441Y1164960D03*
X1564960D03*
X1576181Y1168700D03*
X1568700D03*
X1572441Y1172440D03*
X1564960D03*
X1576181Y1157480D03*
X1568700D03*
X1572441Y1161220D03*
X1564960D03*
X1576181Y1164960D03*
X1568700D03*
X1572441Y1168700D03*
X1564960D03*
X1576181Y1172440D03*
X1568700D03*
Y1183661D03*
X1576181Y1187401D03*
X1572441D03*
X1568700D03*
X1564960D03*
X1568700Y1176180D03*
X1576181Y1179921D03*
X1572441D03*
X1564960D03*
X1576181Y1183661D03*
X1572441D03*
X1576181Y1176180D03*
X1572441D03*
X1564960Y1183661D03*
Y1176180D03*
X1568700Y1179921D03*
Y1191141D03*
X1576181Y1194881D03*
X1572441D03*
X1568700D03*
Y1198621D03*
X1576181Y1202362D03*
X1572441D03*
X1568700D03*
X1564960D03*
Y1191141D03*
X1576181Y1198621D03*
X1572441D03*
X1576181Y1191141D03*
X1572441D03*
X1564960Y1198621D03*
Y1194881D03*
X1576181Y1206102D03*
X1572441D03*
X1568700D03*
X1564960D03*
X1576181Y1209842D03*
X1572441D03*
X1568700D03*
X1564960D03*
Y1213582D03*
Y1217322D03*
X1576181Y1221062D03*
X1572441D03*
X1568700D03*
X1564960D03*
X1576181Y1213582D03*
X1572441D03*
X1576181Y1217322D03*
X1568700Y1213582D03*
X1572441Y1217322D03*
X1568700D03*
X1576181Y1224803D03*
X1568700D03*
X1576181Y1228543D03*
X1568700D03*
X1572441Y1232283D03*
X1564960D03*
X1572441Y1236023D03*
X1564960D03*
Y1224803D03*
X1568700Y1232283D03*
X1572441Y1224803D03*
X1576181Y1232283D03*
X1564960Y1228543D03*
X1568700Y1236023D03*
X1572441Y1228543D03*
X1576181Y1236023D03*
Y1239763D03*
X1572441D03*
X1568700D03*
X1564960D03*
X1576181Y1243503D03*
X1568700D03*
X1576181Y1247243D03*
X1568700D03*
X1572441Y1250984D03*
X1564960D03*
Y1243503D03*
X1568700Y1250984D03*
X1572441Y1243503D03*
X1576181Y1250984D03*
X1564960Y1247243D03*
X1572441D03*
Y1254724D03*
X1564960D03*
X1568700D03*
X1576181D03*
X1594882Y1075196D03*
X1587401D03*
X1579921D03*
X1583661D03*
X1591141D03*
X1594882Y1078936D03*
X1587401D03*
X1579921D03*
X1591141Y1082677D03*
X1583661D03*
X1591141Y1086417D03*
X1583661D03*
X1594882Y1090157D03*
X1591141D03*
X1587401D03*
X1583661D03*
X1579921D03*
Y1086417D03*
X1583661Y1078936D03*
X1587401Y1086417D03*
X1591141Y1078936D03*
X1594882Y1086417D03*
X1579921Y1082677D03*
X1587401D03*
X1594882D03*
Y1093897D03*
X1587401D03*
X1579921D03*
X1594882Y1097637D03*
X1587401D03*
X1579921D03*
X1591141Y1101377D03*
X1583661D03*
X1591141Y1105117D03*
X1583661D03*
X1579921D03*
X1583661Y1097637D03*
X1587401Y1105117D03*
X1591141Y1097637D03*
X1594882Y1105117D03*
X1579921Y1101377D03*
X1583661Y1093897D03*
X1587401Y1101377D03*
X1591141Y1093897D03*
X1594882Y1101377D03*
Y1108858D03*
X1591141D03*
X1587401D03*
X1583661D03*
X1579921D03*
X1587401Y1112598D03*
Y1116338D03*
X1594882Y1120078D03*
X1591141D03*
X1587401D03*
X1583661D03*
X1579921D03*
X1594882Y1123818D03*
X1591141D03*
X1587401D03*
X1583661D03*
X1579921D03*
X1594882Y1112598D03*
Y1116338D03*
X1591141D03*
Y1112598D03*
X1579921Y1116338D03*
Y1112598D03*
X1583661Y1116338D03*
Y1112598D03*
X1594882Y1127558D03*
X1591141D03*
X1587401D03*
X1583661D03*
X1579921D03*
X1594882Y1135039D03*
X1591141D03*
X1587401D03*
X1583661D03*
X1579921D03*
X1594882Y1131299D03*
X1591141D03*
X1587401D03*
X1583661D03*
X1579921D03*
X1594882Y1138779D03*
X1591141D03*
X1587401D03*
X1583661D03*
X1579921D03*
X1594882Y1142519D03*
X1591141D03*
X1587401D03*
X1583661D03*
X1579921D03*
X1594882Y1149999D03*
X1591141D03*
X1587401D03*
X1583661D03*
X1579921D03*
X1594882Y1146259D03*
X1591141D03*
X1587401D03*
X1583661D03*
X1579921D03*
X1594882Y1153740D03*
X1591141D03*
X1587401D03*
X1583661D03*
X1579921D03*
X1594882Y1157480D03*
X1587401D03*
X1579921D03*
X1591141Y1161220D03*
X1583661D03*
X1594882Y1164960D03*
X1587401D03*
X1579921D03*
X1591141Y1168700D03*
X1583661D03*
X1594882Y1172440D03*
X1587401D03*
X1579921D03*
X1591141Y1157480D03*
X1583661D03*
X1594882Y1161220D03*
X1587401D03*
X1579921D03*
X1591141Y1164960D03*
X1583661D03*
X1594882Y1168700D03*
X1587401D03*
X1579921D03*
X1591141Y1172440D03*
X1583661D03*
X1594882Y1187401D03*
X1591141D03*
X1587401D03*
X1583661D03*
X1579921D03*
X1594882Y1179921D03*
X1591141D03*
X1587401D03*
X1583661D03*
X1579921D03*
X1594882Y1183661D03*
X1591141D03*
X1587401D03*
X1583661D03*
X1579921D03*
X1594882Y1176180D03*
X1591141D03*
X1587401D03*
X1583661D03*
X1579921D03*
X1594882Y1194881D03*
X1591141D03*
X1587401D03*
X1583661D03*
X1579921D03*
X1594882Y1202362D03*
X1591141D03*
X1587401D03*
X1583661D03*
X1579921D03*
X1594882Y1198621D03*
X1591141D03*
X1587401D03*
X1583661D03*
X1579921D03*
X1594882Y1191141D03*
X1591141D03*
X1587401D03*
X1583661D03*
X1579921D03*
X1594882Y1206102D03*
X1591141D03*
X1587401D03*
X1583661D03*
X1579921D03*
X1594882Y1209842D03*
X1591141D03*
X1587401D03*
X1583661D03*
X1579921D03*
X1591141Y1213582D03*
Y1217322D03*
X1594882Y1221062D03*
X1591141D03*
X1587401D03*
X1583661D03*
X1579921D03*
X1594882Y1213582D03*
Y1217322D03*
X1583661Y1213582D03*
X1579921Y1217322D03*
X1587401D03*
X1579921Y1213582D03*
X1587401D03*
X1583661Y1217322D03*
X1591141Y1224803D03*
X1583661D03*
X1591141Y1228543D03*
X1583661D03*
X1594882Y1232283D03*
X1587401D03*
X1579921D03*
X1594882Y1236023D03*
X1587401D03*
X1579921D03*
X1587401Y1224803D03*
X1591141Y1232283D03*
X1594882Y1224803D03*
X1579921D03*
X1583661Y1232283D03*
X1587401Y1228543D03*
X1591141Y1236023D03*
X1594882Y1228543D03*
X1579921D03*
X1583661Y1236023D03*
X1594882Y1239763D03*
X1591141D03*
X1587401D03*
X1583661D03*
X1579921D03*
X1591141Y1243503D03*
X1583661D03*
X1591141Y1247243D03*
X1583661D03*
X1594882Y1250984D03*
X1587401D03*
X1579921D03*
X1587401Y1243503D03*
X1591141Y1250984D03*
X1594882Y1243503D03*
X1579921D03*
X1583661Y1250984D03*
X1587401Y1247243D03*
X1594882D03*
X1579921D03*
X1594882Y1254724D03*
X1587401D03*
X1579921D03*
X1591141D03*
X1583661D03*
X1609842Y1075196D03*
X1602362D03*
X1598622D03*
X1606102D03*
X1609842Y1078936D03*
X1602362D03*
X1606102Y1082677D03*
X1598622D03*
X1606102Y1086417D03*
X1598622D03*
X1609842Y1090157D03*
X1606102D03*
X1602362D03*
X1598622D03*
Y1078936D03*
X1602362Y1086417D03*
Y1082677D03*
X1609842Y1086417D03*
X1606102Y1078936D03*
X1609842Y1082677D03*
Y1093897D03*
X1602362D03*
X1609842Y1097637D03*
X1602362D03*
X1606102Y1101377D03*
X1598622D03*
X1606102Y1105117D03*
X1598622D03*
Y1097637D03*
X1602362Y1105117D03*
X1598622Y1093897D03*
X1602362Y1101377D03*
X1609842Y1105117D03*
X1606102Y1097637D03*
X1609842Y1101377D03*
X1606102Y1093897D03*
X1609842Y1108858D03*
X1606102D03*
X1602362D03*
X1598622D03*
X1602362Y1112598D03*
Y1116338D03*
X1609842Y1120078D03*
X1606102D03*
X1602362D03*
X1598622D03*
X1609842Y1123818D03*
X1606102D03*
X1602362D03*
X1598622D03*
Y1116338D03*
Y1112598D03*
X1609842Y1116338D03*
X1606102Y1112598D03*
Y1116338D03*
X1609842Y1112598D03*
Y1127558D03*
X1606102D03*
X1602362D03*
X1598622D03*
X1609842Y1135039D03*
X1606102D03*
X1602362D03*
X1598622D03*
X1609842Y1131299D03*
X1606102D03*
X1602362D03*
X1598622D03*
X1609842Y1138779D03*
X1606102D03*
X1602362D03*
X1598622D03*
X1609842Y1142519D03*
X1606102D03*
X1602362D03*
X1598622D03*
X1609842Y1149999D03*
X1606102D03*
X1602362D03*
X1598622D03*
X1609842Y1146259D03*
X1606102D03*
X1602362D03*
X1598622D03*
X1609842Y1153740D03*
X1606102D03*
X1602362D03*
X1598622D03*
X1609842Y1157480D03*
X1602362D03*
X1606102Y1161220D03*
X1598622D03*
X1609842Y1164960D03*
X1602362D03*
X1606102Y1168700D03*
X1598622D03*
X1609842Y1172440D03*
X1602362D03*
X1606102Y1157480D03*
X1598622D03*
X1609842Y1161220D03*
X1602362D03*
X1606102Y1164960D03*
X1598622D03*
X1609842Y1168700D03*
X1602362D03*
X1606102Y1172440D03*
X1598622D03*
X1609842Y1187401D03*
X1606102D03*
X1602362D03*
X1598622D03*
X1609842Y1179921D03*
X1606102D03*
X1602362D03*
X1598622D03*
X1609842Y1183661D03*
X1606102D03*
X1602362D03*
X1598622D03*
X1609842Y1176180D03*
X1606102D03*
X1602362D03*
X1598622D03*
X1609842Y1194881D03*
X1606102D03*
X1602362D03*
X1598622D03*
X1609842Y1202362D03*
X1606102D03*
X1602362D03*
X1598622D03*
X1609842Y1198621D03*
X1606102D03*
X1602362D03*
X1598622D03*
X1609842Y1191141D03*
X1606102D03*
X1602362D03*
X1598622D03*
X1609842Y1206102D03*
X1606102D03*
X1602362D03*
X1598622D03*
X1609842Y1209842D03*
X1606102D03*
X1602362D03*
X1598622D03*
X1609842Y1221062D03*
X1606102D03*
X1602362D03*
X1598622D03*
X1609842Y1217322D03*
X1602362Y1213582D03*
X1598622Y1217322D03*
Y1213582D03*
X1602362Y1217322D03*
X1606102D03*
Y1213582D03*
X1609842D03*
X1606102Y1224803D03*
X1598622D03*
X1606102Y1228543D03*
X1598622D03*
X1609842Y1232283D03*
X1602362D03*
X1609842Y1236023D03*
X1602362D03*
X1598622Y1232283D03*
Y1236023D03*
X1609842Y1224803D03*
X1606102Y1232283D03*
X1602362Y1224803D03*
X1609842Y1228543D03*
X1606102Y1236023D03*
X1602362Y1228543D03*
X1609842Y1239763D03*
X1606102D03*
X1602362D03*
X1598622D03*
X1606102Y1243503D03*
X1598622D03*
X1606102Y1247243D03*
X1598622D03*
X1609842Y1250984D03*
X1602362D03*
X1598622D03*
X1609842Y1243503D03*
X1606102Y1250984D03*
X1602362Y1243503D03*
X1609842Y1247243D03*
X1602362D03*
X1609842Y1254724D03*
X1602362D03*
X1598622D03*
X1606102D03*
X1624803Y1075196D03*
X1617322D03*
X1621063D03*
X1613582D03*
X1624803Y1078936D03*
X1617322D03*
X1621063Y1082677D03*
X1613582D03*
X1621063Y1086417D03*
X1613582D03*
X1624803Y1090157D03*
X1621063D03*
X1617322D03*
X1613582D03*
X1624803Y1086417D03*
X1621063Y1078936D03*
X1617322Y1086417D03*
X1613582Y1078936D03*
X1624803Y1082677D03*
X1617322D03*
X1624803Y1093897D03*
X1617322D03*
X1624803Y1097637D03*
X1617322D03*
X1621063Y1101377D03*
X1613582D03*
X1621063Y1105117D03*
X1613582D03*
X1624803D03*
X1621063Y1097637D03*
X1617322Y1105117D03*
X1613582Y1097637D03*
X1624803Y1101377D03*
X1621063Y1093897D03*
X1617322Y1101377D03*
X1613582Y1093897D03*
X1624803Y1108858D03*
X1621063D03*
X1617322D03*
X1613582D03*
X1624803Y1120078D03*
X1621063D03*
X1617322D03*
X1613582D03*
X1624803Y1123818D03*
X1621063D03*
X1617322D03*
X1613582D03*
X1624803Y1116338D03*
X1621063D03*
X1617322D03*
X1621063Y1112598D03*
X1617322D03*
X1613582Y1116338D03*
Y1112598D03*
X1624803D03*
Y1127558D03*
X1621063D03*
X1617322D03*
X1613582D03*
X1624803Y1135039D03*
X1621063D03*
X1617322D03*
X1613582D03*
X1624803Y1131299D03*
X1621063D03*
X1617322D03*
X1613582D03*
X1624803Y1138779D03*
X1621063D03*
X1617322D03*
X1613582D03*
X1624803Y1142519D03*
X1621063D03*
X1617322D03*
X1613582D03*
X1624803Y1149999D03*
X1621063D03*
X1617322D03*
X1613582D03*
X1624803Y1146259D03*
X1621063D03*
X1617322D03*
X1613582D03*
X1624803Y1153740D03*
X1621063D03*
X1617322D03*
X1613582D03*
X1624803Y1157480D03*
X1617322D03*
X1621063Y1161220D03*
X1613582D03*
X1624803Y1164960D03*
X1617322D03*
X1621063Y1168700D03*
X1613582D03*
X1624803Y1172440D03*
X1617322D03*
X1621063Y1157480D03*
X1613582D03*
X1624803Y1161220D03*
X1617322D03*
X1621063Y1164960D03*
X1613582D03*
X1624803Y1168700D03*
X1617322D03*
X1621063Y1172440D03*
X1613582D03*
X1624803Y1187401D03*
X1621063D03*
X1617322D03*
X1613582D03*
X1624803Y1179921D03*
X1621063D03*
X1617322D03*
X1613582D03*
X1624803Y1183661D03*
X1621063D03*
X1617322D03*
X1613582D03*
X1624803Y1176180D03*
X1621063D03*
X1617322D03*
X1613582D03*
X1624803Y1194881D03*
X1621063D03*
X1617322D03*
X1613582D03*
X1624803Y1202362D03*
X1621063D03*
X1617322D03*
X1613582D03*
X1624803Y1198621D03*
X1621063D03*
X1617322D03*
X1613582D03*
X1624803Y1191141D03*
X1621063D03*
X1617322D03*
X1613582D03*
X1624803Y1206102D03*
X1621063D03*
X1617322D03*
X1613582D03*
X1624803Y1209842D03*
X1621063D03*
X1617322D03*
X1613582D03*
X1624803Y1221062D03*
X1621063D03*
X1617322D03*
X1613582D03*
X1617322Y1213582D03*
X1621063D03*
Y1217322D03*
X1624803Y1213582D03*
X1613582D03*
X1617322Y1217322D03*
X1613582D03*
X1624803D03*
X1621063Y1224803D03*
X1613582D03*
X1621063Y1228543D03*
X1613582D03*
X1624803Y1232283D03*
X1617322D03*
X1624803Y1236023D03*
X1617322D03*
X1624803Y1224803D03*
X1621063Y1232283D03*
X1617322Y1224803D03*
X1613582Y1232283D03*
X1624803Y1228543D03*
X1621063Y1236023D03*
X1617322Y1228543D03*
X1613582Y1236023D03*
X1624803Y1239763D03*
X1621063D03*
X1617322D03*
X1613582D03*
X1621063Y1243503D03*
X1613582D03*
X1621063Y1247243D03*
X1613582D03*
X1624803Y1250984D03*
X1617322D03*
X1624803Y1243503D03*
X1621063Y1250984D03*
X1617322Y1243503D03*
X1613582Y1250984D03*
X1624803Y1247243D03*
X1617322D03*
X1624803Y1254724D03*
X1617322D03*
X1621063D03*
X1613582D03*
X1639763Y1075196D03*
X1632283D03*
X1643504D03*
X1636023D03*
X1628543D03*
X1639763Y1078936D03*
X1632283D03*
X1643504Y1082677D03*
X1636023D03*
X1628543D03*
X1643504Y1086417D03*
X1636023D03*
X1628543D03*
X1643504Y1090157D03*
X1639763D03*
X1636023D03*
X1632283D03*
X1628543D03*
X1643504Y1078936D03*
X1639763Y1086417D03*
X1636023Y1078936D03*
X1632283Y1086417D03*
X1628543Y1078936D03*
X1639763Y1082677D03*
X1632283D03*
X1639763Y1093897D03*
X1632283D03*
X1639763Y1097637D03*
X1632283D03*
X1643504Y1101377D03*
X1636023D03*
X1628543D03*
X1643504Y1105117D03*
X1636023D03*
X1628543D03*
X1643504Y1097637D03*
X1639763Y1105117D03*
X1636023Y1097637D03*
X1632283Y1105117D03*
X1628543Y1097637D03*
X1643504Y1093897D03*
X1639763Y1101377D03*
X1636023Y1093897D03*
X1632283Y1101377D03*
X1628543Y1093897D03*
X1643504Y1108858D03*
X1639763D03*
X1636023D03*
X1632283D03*
X1628543D03*
X1643504Y1120078D03*
X1639763D03*
X1636023D03*
X1632283D03*
X1628543D03*
X1643504Y1123818D03*
X1639763D03*
X1636023D03*
X1632283D03*
X1628543D03*
X1643504Y1116338D03*
X1636023D03*
Y1112598D03*
X1643504D03*
X1639763Y1116338D03*
X1628543D03*
X1632283Y1112598D03*
X1628543D03*
X1632283Y1116338D03*
X1639763Y1112598D03*
X1643504Y1127558D03*
X1639763D03*
X1636023D03*
X1632283D03*
X1628543D03*
X1639763Y1131299D03*
X1643504Y1135039D03*
X1639763D03*
X1636023D03*
X1632283D03*
X1628543D03*
X1639763Y1138779D03*
X1643504Y1131299D03*
Y1138779D03*
X1636023Y1131299D03*
X1632283D03*
X1628543D03*
X1636023Y1138779D03*
X1632283D03*
X1628543D03*
X1639763Y1142519D03*
X1636023D03*
X1632283D03*
X1628543D03*
X1639763Y1146259D03*
X1643504Y1149999D03*
X1639763D03*
X1636023D03*
X1632283D03*
X1628543D03*
X1643504Y1153740D03*
X1639763D03*
X1636023Y1146259D03*
X1632283D03*
X1628543D03*
X1636023Y1153740D03*
X1632283D03*
X1628543D03*
X1643504Y1142519D03*
Y1146259D03*
Y1157480D03*
X1639763D03*
X1632283D03*
X1643504Y1161220D03*
X1628543D03*
X1643504Y1164960D03*
X1632283D03*
X1643504Y1168700D03*
X1628543D03*
X1643504Y1172440D03*
X1639763D03*
X1632283D03*
X1639763Y1161220D03*
X1636023D03*
X1632283D03*
X1639763Y1164960D03*
X1636023D03*
X1639763Y1168700D03*
X1636023D03*
X1632283D03*
X1636023Y1157480D03*
X1628543D03*
Y1164960D03*
X1636023Y1172440D03*
X1628543D03*
X1639763Y1183661D03*
Y1187401D03*
X1636023D03*
X1632283D03*
X1628543D03*
X1639763Y1176180D03*
X1636023Y1179921D03*
X1632283D03*
X1628543D03*
X1636023Y1183661D03*
X1632283D03*
X1628543D03*
X1636023Y1176180D03*
X1632283D03*
X1628543D03*
X1639763Y1179921D03*
X1643504Y1183661D03*
Y1187401D03*
Y1179921D03*
Y1176180D03*
X1639763Y1191141D03*
X1643504Y1194881D03*
X1639763D03*
X1636023D03*
X1632283D03*
X1628543D03*
X1639763Y1198621D03*
X1643504Y1202362D03*
X1639763D03*
X1636023D03*
X1632283D03*
X1628543D03*
X1643504Y1198621D03*
Y1191141D03*
X1636023Y1198621D03*
X1632283D03*
X1628543D03*
X1636023Y1191141D03*
X1632283D03*
X1628543D03*
X1643504Y1206102D03*
X1639763D03*
X1636023D03*
X1632283D03*
X1628543D03*
X1643504Y1209842D03*
X1639763D03*
X1636023D03*
X1632283D03*
X1628543D03*
X1643504Y1221062D03*
X1639763D03*
X1636023D03*
X1632283D03*
X1628543D03*
X1639763Y1217322D03*
X1643504Y1213582D03*
X1632283D03*
X1628543Y1217322D03*
X1639763Y1213582D03*
X1636023D03*
Y1217322D03*
X1628543Y1213582D03*
X1643504Y1217322D03*
X1632283D03*
X1643504Y1224803D03*
X1636023D03*
X1628543D03*
X1643504Y1228543D03*
X1636023D03*
X1628543D03*
X1639763Y1232283D03*
X1632283D03*
X1639763Y1236023D03*
X1632283D03*
X1643504Y1232283D03*
X1639763Y1224803D03*
X1636023Y1232283D03*
X1632283Y1224803D03*
X1628543Y1232283D03*
X1643504Y1236023D03*
X1639763Y1228543D03*
X1636023Y1236023D03*
X1632283Y1228543D03*
X1628543Y1236023D03*
X1643504Y1239763D03*
X1639763D03*
X1636023D03*
X1632283D03*
X1628543D03*
X1643504Y1243503D03*
X1636023D03*
X1628543D03*
X1643504Y1247243D03*
X1636023D03*
X1628543D03*
X1639763Y1250984D03*
X1632283D03*
X1643504D03*
X1639763Y1243503D03*
X1636023Y1250984D03*
X1632283Y1243503D03*
X1628543Y1250984D03*
X1639763Y1247243D03*
X1632283D03*
X1639763Y1254724D03*
X1632283D03*
X1643504D03*
X1636023D03*
X1628543D03*
X1654724Y1075196D03*
X1647244D03*
X1658464D03*
X1650984D03*
X1654724Y1078936D03*
X1647244D03*
X1658464Y1082677D03*
X1650984D03*
X1658464Y1086417D03*
X1650984D03*
X1658464Y1090157D03*
X1654724D03*
X1650984D03*
X1647244D03*
X1658464Y1078936D03*
X1654724Y1086417D03*
X1650984Y1078936D03*
X1647244Y1086417D03*
X1654724Y1082677D03*
X1647244D03*
X1654724Y1093897D03*
X1647244D03*
X1654724Y1097637D03*
X1647244D03*
X1658464Y1101377D03*
X1650984D03*
X1658464Y1105117D03*
X1650984D03*
X1658464Y1097637D03*
X1654724Y1105117D03*
X1650984Y1097637D03*
X1647244Y1105117D03*
X1658464Y1093897D03*
X1654724Y1101377D03*
X1650984Y1093897D03*
X1647244Y1101377D03*
X1658464Y1108858D03*
X1654724D03*
X1650984D03*
X1647244D03*
X1650984Y1120078D03*
X1647244D03*
X1650984Y1123818D03*
X1647244D03*
X1654724Y1120078D03*
X1650984Y1112598D03*
Y1116338D03*
X1654724D03*
X1647244Y1112598D03*
X1654724Y1123818D03*
X1658464Y1116338D03*
Y1123818D03*
X1647244Y1116338D03*
X1658464Y1120078D03*
Y1112598D03*
X1654724D03*
X1650984Y1127558D03*
Y1131299D03*
Y1135039D03*
Y1138779D03*
X1647244D03*
Y1127558D03*
Y1135039D03*
Y1131299D03*
X1658464Y1127558D03*
Y1131299D03*
X1654724Y1127558D03*
Y1131299D03*
X1658464Y1138779D03*
X1654724Y1135039D03*
X1658464D03*
X1654724Y1138779D03*
X1650984Y1142519D03*
X1647244D03*
X1650984Y1146259D03*
X1647244D03*
X1650984Y1149999D03*
X1647244D03*
X1658464Y1153740D03*
X1654724D03*
X1650984D03*
X1647244D03*
X1654724Y1142519D03*
X1658464Y1149999D03*
X1654724D03*
Y1146259D03*
X1658464Y1142519D03*
Y1146259D03*
Y1157480D03*
X1650984D03*
X1658464Y1161220D03*
X1650984D03*
X1658464Y1164960D03*
X1650984D03*
X1658464Y1168700D03*
X1650984D03*
X1658464Y1172440D03*
X1650984D03*
X1654724Y1157480D03*
Y1161220D03*
Y1164960D03*
Y1168700D03*
Y1172440D03*
X1647244Y1157480D03*
Y1161220D03*
Y1164960D03*
Y1168700D03*
Y1172440D03*
X1654724Y1183661D03*
X1650984D03*
X1647244D03*
X1650984Y1187401D03*
X1647244D03*
X1658464Y1176180D03*
X1654724D03*
X1650984D03*
X1647244D03*
X1654724Y1179921D03*
X1647244D03*
X1658464Y1187401D03*
X1650984Y1179921D03*
X1654724Y1187401D03*
X1658464Y1179921D03*
Y1183661D03*
X1654724Y1191141D03*
X1650984D03*
X1647244D03*
X1650984Y1194881D03*
Y1198621D03*
Y1202362D03*
X1658464Y1191141D03*
X1647244Y1198621D03*
Y1202362D03*
Y1194881D03*
X1654724D03*
Y1202362D03*
X1658464Y1194881D03*
Y1202362D03*
Y1198621D03*
X1654724D03*
X1650984Y1206102D03*
Y1209842D03*
X1647244D03*
X1658464Y1221062D03*
X1654724D03*
X1650984D03*
X1647244D03*
Y1206102D03*
X1658464Y1217322D03*
X1654724Y1209842D03*
Y1213582D03*
X1647244Y1217322D03*
Y1213582D03*
X1650984D03*
X1654724Y1217322D03*
X1658464Y1213582D03*
Y1209842D03*
X1650984Y1217322D03*
X1654724Y1206102D03*
X1658464D03*
Y1224803D03*
X1650984D03*
X1658464Y1228543D03*
X1650984D03*
X1654724Y1232283D03*
X1647244D03*
X1654724Y1236023D03*
X1647244D03*
X1658464Y1232283D03*
X1654724Y1224803D03*
X1650984Y1232283D03*
X1647244Y1224803D03*
X1658464Y1236023D03*
X1654724Y1228543D03*
X1650984Y1236023D03*
X1647244Y1228543D03*
X1658464Y1239763D03*
X1654724D03*
X1650984D03*
X1647244D03*
X1658464Y1243503D03*
X1650984D03*
X1658464Y1247243D03*
X1650984D03*
X1654724Y1250984D03*
X1647244D03*
X1658464D03*
X1654724Y1243503D03*
X1650984Y1250984D03*
X1647244Y1243503D03*
X1654724Y1247243D03*
X1647244D03*
X1654724Y1254724D03*
X1647244D03*
X1658464D03*
X1650984D03*
X1669685Y1075196D03*
X1662204D03*
X1665945D03*
X1673425D03*
X1669685Y1078936D03*
X1662204D03*
X1673425Y1082677D03*
X1665945D03*
X1673425Y1086417D03*
X1665945D03*
X1673425Y1090157D03*
X1669685D03*
X1665945D03*
X1662204D03*
Y1086417D03*
Y1082677D03*
X1665945Y1078936D03*
X1669685Y1086417D03*
X1673425Y1078936D03*
X1669685Y1082677D03*
Y1093897D03*
X1662204D03*
X1669685Y1097637D03*
X1662204D03*
X1673425Y1101377D03*
X1665945D03*
X1673425Y1105117D03*
X1665945D03*
X1662204D03*
Y1101377D03*
X1665945Y1097637D03*
X1669685Y1105117D03*
X1673425Y1097637D03*
X1665945Y1093897D03*
X1669685Y1101377D03*
X1673425Y1093897D03*
Y1108858D03*
X1669685D03*
X1665945D03*
X1662204D03*
X1669685Y1112598D03*
X1665945D03*
X1662204D03*
X1673425Y1116338D03*
X1662204D03*
X1669685Y1120078D03*
X1665945D03*
X1662204D03*
X1673425Y1123818D03*
X1662204D03*
X1673425Y1112598D03*
X1665945Y1116338D03*
X1673425Y1120078D03*
X1665945Y1123818D03*
X1669685Y1116338D03*
Y1123818D03*
Y1127558D03*
X1665945D03*
X1662204D03*
X1673425Y1131299D03*
X1662204D03*
X1669685Y1135039D03*
X1665945D03*
X1662204D03*
X1673425Y1138779D03*
X1662204D03*
X1665945D03*
X1669685D03*
X1673425Y1127558D03*
X1665945Y1131299D03*
X1673425Y1135039D03*
X1669685Y1131299D03*
Y1142519D03*
X1665945D03*
X1662204D03*
X1673425Y1146259D03*
X1662204D03*
X1669685Y1149999D03*
X1665945D03*
X1662204D03*
X1673425Y1153740D03*
X1662204D03*
X1673425Y1142519D03*
X1665945Y1146259D03*
X1673425Y1149999D03*
X1665945Y1153740D03*
X1669685Y1146259D03*
Y1153740D03*
Y1157480D03*
X1665945D03*
X1662204D03*
X1673425Y1161220D03*
X1662204D03*
X1669685Y1164960D03*
X1665945D03*
X1662204D03*
X1673425Y1168700D03*
X1662204D03*
X1669685Y1172440D03*
X1665945D03*
X1662204D03*
X1673425Y1157480D03*
X1665945Y1161220D03*
X1673425Y1164960D03*
X1665945Y1168700D03*
X1673425Y1172440D03*
X1669685Y1161220D03*
Y1168700D03*
X1673425Y1183661D03*
X1662204D03*
X1669685Y1187401D03*
X1665945D03*
X1662204D03*
X1673425Y1176180D03*
X1662204D03*
X1669685Y1179921D03*
X1665945D03*
X1662204D03*
X1665945Y1176180D03*
X1673425Y1179921D03*
X1665945Y1183661D03*
X1673425Y1187401D03*
X1669685Y1176180D03*
Y1183661D03*
X1673425Y1191141D03*
X1662204D03*
X1669685Y1194881D03*
X1665945D03*
X1662204D03*
X1673425Y1198621D03*
X1662204D03*
X1669685Y1202362D03*
X1665945D03*
X1662204D03*
X1665945Y1191141D03*
X1673425Y1194881D03*
X1669685Y1191141D03*
X1673425Y1202362D03*
X1665945Y1198621D03*
X1669685D03*
X1673425Y1206102D03*
X1662204D03*
X1669685Y1209842D03*
X1665945D03*
X1662204D03*
X1673425Y1213582D03*
X1662204D03*
X1669685Y1217322D03*
X1665945D03*
X1662204D03*
X1673425Y1221062D03*
X1669685D03*
X1665945D03*
X1662204D03*
X1673425Y1217322D03*
X1665945Y1213582D03*
X1673425Y1209842D03*
X1665945Y1206102D03*
X1669685Y1213582D03*
Y1206102D03*
X1673425Y1224803D03*
X1665945D03*
X1673425Y1228543D03*
X1665945D03*
X1669685Y1232283D03*
X1662204D03*
X1669685Y1236023D03*
X1662204D03*
Y1224803D03*
X1665945Y1232283D03*
X1669685Y1224803D03*
X1673425Y1232283D03*
X1662204Y1228543D03*
X1665945Y1236023D03*
X1669685Y1228543D03*
X1673425Y1236023D03*
Y1239763D03*
X1669685D03*
X1665945D03*
X1662204D03*
X1673425Y1243503D03*
X1665945D03*
X1673425Y1247243D03*
X1665945D03*
X1669685Y1250984D03*
X1662204D03*
Y1243503D03*
X1665945Y1250984D03*
X1669685Y1243503D03*
X1673425Y1250984D03*
X1662204Y1247243D03*
X1669685D03*
Y1254724D03*
X1662204D03*
X1665945D03*
X1673425D03*
X1692126Y1075196D03*
X1684645D03*
X1677165D03*
X1688385D03*
X1680905D03*
X1692126Y1078936D03*
X1684645D03*
X1677165D03*
X1688385Y1082677D03*
X1680905D03*
X1692126Y1086417D03*
X1688385D03*
X1680905D03*
X1688385Y1090157D03*
X1684645D03*
X1680905D03*
X1677165D03*
X1692126D03*
X1688385Y1078936D03*
X1692126Y1082677D03*
X1677165Y1086417D03*
X1680905Y1078936D03*
X1684645Y1086417D03*
X1677165Y1082677D03*
X1684645D03*
X1692126Y1093897D03*
X1684645D03*
X1677165D03*
X1692126Y1097637D03*
X1684645D03*
X1677165D03*
X1688385Y1101377D03*
X1680905D03*
X1692126Y1105117D03*
X1688385D03*
X1680905D03*
X1688385Y1097637D03*
X1692126Y1101377D03*
X1677165Y1105117D03*
X1680905Y1097637D03*
X1684645Y1105117D03*
X1688385Y1093897D03*
X1677165Y1101377D03*
X1680905Y1093897D03*
X1684645Y1101377D03*
X1688385Y1108858D03*
X1684645D03*
X1680905D03*
X1677165D03*
X1692126Y1112598D03*
X1680905D03*
X1688385Y1116338D03*
X1684645D03*
X1680905D03*
X1677165D03*
X1692126Y1120078D03*
X1680905D03*
X1688385Y1123818D03*
X1684645D03*
X1680905D03*
X1677165D03*
Y1112598D03*
Y1120078D03*
X1692126Y1108858D03*
X1684645Y1112598D03*
X1692126Y1116338D03*
X1684645Y1120078D03*
X1692126Y1123818D03*
X1688385Y1112598D03*
Y1120078D03*
X1692126Y1127558D03*
X1680905D03*
X1688385Y1131299D03*
X1684645D03*
X1680905D03*
X1677165D03*
X1692126Y1135039D03*
X1680905D03*
X1688385Y1138779D03*
X1684645D03*
X1680905D03*
X1677165D03*
X1692126D03*
X1677165Y1127558D03*
Y1135039D03*
X1684645Y1127558D03*
X1692126Y1131299D03*
X1684645Y1135039D03*
X1688385Y1127558D03*
Y1135039D03*
X1692126Y1142519D03*
X1680905D03*
X1688385Y1146259D03*
X1684645D03*
X1680905D03*
X1677165D03*
X1692126Y1149999D03*
X1680905D03*
X1688385Y1153740D03*
X1684645D03*
X1680905D03*
X1677165D03*
Y1142519D03*
Y1149999D03*
X1684645Y1142519D03*
X1692126Y1146259D03*
X1684645Y1149999D03*
X1692126Y1153740D03*
X1688385Y1142519D03*
Y1149999D03*
X1692126Y1157480D03*
X1680905D03*
X1688385Y1161220D03*
X1684645D03*
X1680905D03*
X1677165D03*
X1692126Y1164960D03*
X1680905D03*
X1688385Y1168700D03*
X1684645D03*
X1680905D03*
X1677165D03*
X1692126Y1172440D03*
X1680905D03*
X1677165Y1157480D03*
Y1164960D03*
Y1172440D03*
X1684645Y1157480D03*
X1692126Y1161220D03*
X1684645Y1164960D03*
X1692126Y1168700D03*
X1684645Y1172440D03*
X1688385Y1157480D03*
Y1164960D03*
Y1172440D03*
Y1183661D03*
X1684645D03*
X1680905D03*
X1677165D03*
X1692126Y1187401D03*
X1680905D03*
X1688385Y1176180D03*
X1684645D03*
X1680905D03*
X1677165D03*
X1692126Y1179921D03*
X1680905D03*
X1677165D03*
Y1187401D03*
X1692126Y1176180D03*
X1684645Y1179921D03*
X1692126Y1183661D03*
X1684645Y1187401D03*
X1688385Y1179921D03*
Y1187401D03*
Y1191141D03*
X1684645D03*
X1680905D03*
X1677165D03*
X1692126Y1194881D03*
X1680905D03*
X1688385Y1198621D03*
X1684645D03*
X1680905D03*
X1677165D03*
X1692126Y1202362D03*
X1680905D03*
X1677165Y1194881D03*
X1692126Y1191141D03*
X1684645Y1194881D03*
X1688385D03*
X1677165Y1202362D03*
X1684645D03*
X1692126Y1198621D03*
X1688385Y1202362D03*
Y1206102D03*
X1684645D03*
X1680905D03*
X1677165D03*
X1692126Y1209842D03*
X1680905D03*
X1688385Y1213582D03*
X1684645D03*
X1680905D03*
X1677165D03*
X1692126Y1217322D03*
X1680905D03*
X1688385Y1221062D03*
X1684645D03*
X1680905D03*
X1677165D03*
Y1217322D03*
Y1209842D03*
X1692126Y1221062D03*
X1684645Y1217322D03*
X1692126Y1213582D03*
X1684645Y1209842D03*
X1692126Y1206102D03*
X1688385Y1217322D03*
Y1209842D03*
X1692126Y1224803D03*
X1688385D03*
X1680905D03*
X1688385Y1228543D03*
X1680905D03*
X1692126Y1232283D03*
X1684645D03*
X1677165D03*
X1692126Y1236023D03*
X1684645D03*
X1677165D03*
Y1224803D03*
X1680905Y1232283D03*
X1684645Y1224803D03*
X1688385Y1232283D03*
X1692126Y1228543D03*
X1677165D03*
X1680905Y1236023D03*
X1684645Y1228543D03*
X1688385Y1236023D03*
Y1239763D03*
X1684645D03*
X1680905D03*
X1677165D03*
X1692126Y1243503D03*
X1688385D03*
X1680905D03*
X1688385Y1247243D03*
X1680905D03*
X1692126Y1250984D03*
X1684645D03*
X1677165D03*
X1692126Y1239763D03*
X1677165Y1243503D03*
X1680905Y1250984D03*
X1684645Y1243503D03*
X1688385Y1250984D03*
X1692126Y1247243D03*
X1677165D03*
X1684645D03*
X1692126Y1254724D03*
X1684645D03*
X1677165D03*
X1680905D03*
X1688385D03*
X1695866Y1078936D03*
Y1086417D03*
Y1090157D03*
Y1082677D03*
Y1093897D03*
Y1097637D03*
Y1105117D03*
Y1101377D03*
Y1112598D03*
Y1120078D03*
Y1108858D03*
Y1116338D03*
Y1123818D03*
Y1127558D03*
Y1135039D03*
Y1138779D03*
Y1131299D03*
Y1142519D03*
Y1149999D03*
Y1146259D03*
Y1153740D03*
Y1157480D03*
Y1164960D03*
Y1172440D03*
Y1161220D03*
Y1168700D03*
Y1187401D03*
Y1179921D03*
Y1176180D03*
Y1183661D03*
Y1194881D03*
Y1202362D03*
Y1191141D03*
Y1198621D03*
Y1209842D03*
Y1217322D03*
Y1221062D03*
Y1213582D03*
Y1206102D03*
Y1224803D03*
Y1232283D03*
Y1236023D03*
Y1228543D03*
Y1243503D03*
Y1250984D03*
Y1239763D03*
Y1247243D03*
G54D226*
X942586Y1475447D03*
G54D52*
X35158Y1504318D03*
X33189D03*
X31221D03*
X29252D03*
X27284D03*
X25315D03*
Y1538964D03*
X27284D03*
X29252D03*
X31221D03*
X33189D03*
X35158D03*
X50906Y1504318D03*
X48937D03*
X46969D03*
X45000D03*
X43032D03*
X41063D03*
X39095D03*
X37126D03*
Y1538964D03*
X39095D03*
X41063D03*
X43032D03*
X45000D03*
X46969D03*
X48937D03*
X50906D03*
X54843Y1504318D03*
X52874D03*
Y1538964D03*
X54843D03*
G54D173*
X687146Y759581D03*
Y762140D03*
Y764699D03*
Y774936D03*
Y777495D03*
Y767258D03*
Y769818D03*
Y772377D03*
X709194Y759581D03*
Y762140D03*
Y764699D03*
Y774936D03*
Y777495D03*
Y767258D03*
Y769818D03*
Y772377D03*
G54D35*
X15424Y1041679D03*
X28810D03*
X37157D03*
X50543D03*
X437627Y1234726D03*
X451013D03*
X476336D03*
X489722D03*
X862114Y1050682D03*
X875500D03*
X897233D03*
X883847D03*
X926091D03*
X947824D03*
X939477D03*
X961210D03*
X1351801Y1234726D03*
X1365187D03*
X1390510D03*
X1403896D03*
X1770071Y1051168D03*
X1783457D03*
X1791804D03*
X1805190D03*
G54D164*
X501821Y359214D03*
Y356655D03*
Y361773D03*
Y366891D03*
Y372010D03*
Y377128D03*
Y364332D03*
Y369450D03*
Y374569D03*
Y379687D03*
Y382246D03*
Y384805D03*
X523869Y356655D03*
Y359214D03*
Y372010D03*
Y366891D03*
Y361773D03*
Y374569D03*
Y369450D03*
Y364332D03*
Y377128D03*
Y384805D03*
Y382246D03*
Y379687D03*
X1404362Y326437D03*
Y331555D03*
Y336673D03*
Y341792D03*
Y328996D03*
Y334114D03*
Y339232D03*
Y344351D03*
Y346910D03*
Y349469D03*
Y352028D03*
Y354587D03*
X1426410Y326437D03*
Y341792D03*
Y336673D03*
Y331555D03*
Y344351D03*
Y339232D03*
Y334114D03*
Y328996D03*
Y354587D03*
Y352028D03*
Y349469D03*
Y346910D03*
X1506457Y326325D03*
Y323766D03*
Y328884D03*
Y334002D03*
Y339121D03*
Y344239D03*
Y331443D03*
Y336561D03*
Y341680D03*
Y346798D03*
Y349357D03*
Y351916D03*
X1528505Y323766D03*
Y326325D03*
Y339121D03*
Y334002D03*
Y328884D03*
Y341680D03*
Y336561D03*
Y331443D03*
Y344239D03*
Y351916D03*
Y349357D03*
Y346798D03*
G54D254*
X1803917Y823898D03*
G54D182*
X770472Y1490945D03*
X820079Y388583D03*
X1020866D03*
X1070472Y1490945D03*
G54D137*
X414519Y1251852D03*
Y1264254D03*
X512830Y1251852D03*
Y1264254D03*
X1328693Y1251852D03*
Y1264254D03*
X1427004Y1251852D03*
Y1264254D03*
G54D26*
X12422Y214006D03*
Y207006D03*
X27201Y155151D03*
Y162151D03*
X48949Y826718D03*
Y833718D03*
X50602Y971296D03*
Y978296D03*
X70236Y281155D03*
Y274155D03*
X62733Y531055D03*
Y538055D03*
X61555Y971296D03*
Y978296D03*
X57909Y985176D03*
Y992176D03*
X68342Y985014D03*
Y992014D03*
X70658Y215535D03*
Y222535D03*
X72643Y448919D03*
Y455919D03*
X72564Y484311D03*
Y491311D03*
X114784Y214006D03*
Y207006D03*
X123599Y112672D03*
Y119672D03*
X145882Y586056D03*
Y579056D03*
X152882Y586056D03*
Y579056D03*
X173020Y215535D03*
Y222535D03*
X172598Y281155D03*
Y274155D03*
X225961Y112672D03*
Y119672D03*
X217146Y214006D03*
Y207006D03*
X275382Y215535D03*
Y222535D03*
X274960Y281155D03*
Y274155D03*
X328323Y112672D03*
Y119672D03*
X319508Y214006D03*
Y207006D03*
X317549Y419937D03*
Y426937D03*
Y439431D03*
Y446431D03*
X362042Y441402D03*
Y434402D03*
X358933Y488017D03*
Y481017D03*
X377744Y215535D03*
Y222535D03*
X377322Y281155D03*
Y274155D03*
X371919Y441002D03*
Y448002D03*
X379919Y441002D03*
Y448002D03*
X399853Y391802D03*
Y398802D03*
X405121Y930778D03*
X397121D03*
X405121Y937778D03*
X397121D03*
X400004Y1198971D03*
Y1191971D03*
X413121Y930778D03*
X421121D03*
X413121Y937778D03*
X421121D03*
X426934Y1198971D03*
Y1191971D03*
X431764Y507650D03*
Y500650D03*
X453864Y1198971D03*
Y1191971D03*
X469509Y214006D03*
Y207006D03*
X473206Y1198971D03*
Y1191971D03*
X478324Y112672D03*
Y119672D03*
X500136Y1198971D03*
Y1191971D03*
X519819Y531055D03*
Y538055D03*
X527745Y215535D03*
Y222535D03*
X527323Y281155D03*
Y274155D03*
X527729Y445919D03*
Y452919D03*
X529650Y484311D03*
Y491311D03*
X527066Y1198971D03*
Y1191971D03*
X571871Y214006D03*
Y207006D03*
X566003Y940807D03*
Y947807D03*
X580686Y112672D03*
Y119672D03*
X602968Y586056D03*
Y579056D03*
X609968Y586056D03*
Y579056D03*
X630107Y215535D03*
Y222535D03*
X629685Y281155D03*
Y274155D03*
X683048Y112672D03*
Y119672D03*
X674233Y214006D03*
Y207006D03*
X732469Y215535D03*
Y222535D03*
X732047Y281155D03*
Y274155D03*
X776595Y214006D03*
Y207006D03*
X780434Y419937D03*
Y426937D03*
X773434Y419937D03*
Y426937D03*
X785410Y112672D03*
Y119672D03*
X816019Y476017D03*
Y483017D03*
X834831Y215535D03*
Y222535D03*
X834409Y281155D03*
Y274155D03*
X858882Y467675D03*
Y460675D03*
X866135Y985334D03*
Y992334D03*
X859242Y985334D03*
Y992334D03*
X852117Y985334D03*
Y992334D03*
X874882Y467675D03*
Y460675D03*
X866882Y467675D03*
Y460675D03*
X895179Y408143D03*
Y415143D03*
X907953Y998291D03*
Y1005291D03*
X927261Y199177D03*
Y192177D03*
X935410Y112672D03*
Y119672D03*
X955165Y996486D03*
Y1003486D03*
X948285Y996437D03*
Y1003437D03*
X976906Y531055D03*
Y538055D03*
X979129Y997259D03*
Y1004259D03*
X967028Y996535D03*
Y1003535D03*
X984831Y215535D03*
Y222535D03*
X984409Y281155D03*
Y274155D03*
X986816Y448919D03*
Y455919D03*
X986737Y484311D03*
Y491311D03*
X1007619Y937822D03*
Y944822D03*
X1037772Y112672D03*
Y119672D03*
X1028957Y214006D03*
Y207006D03*
X1060055Y586056D03*
Y579056D03*
X1067055Y586056D03*
Y579056D03*
X1087193Y215535D03*
Y222535D03*
X1086771Y281155D03*
Y274155D03*
X1140134Y112672D03*
Y119672D03*
X1131319Y214006D03*
Y207006D03*
X1189555Y215535D03*
Y222535D03*
X1189133Y281155D03*
Y274155D03*
X1233681Y214006D03*
Y207006D03*
X1231722Y419937D03*
Y426937D03*
Y439431D03*
Y446431D03*
X1242496Y112672D03*
Y119672D03*
X1276215Y441402D03*
Y434402D03*
X1286092Y441002D03*
Y448002D03*
X1273106Y488017D03*
Y481017D03*
X1291917Y215535D03*
Y222535D03*
X1291495Y281155D03*
Y274155D03*
X1294092Y441002D03*
Y448002D03*
X1314026Y391802D03*
Y398802D03*
X1314178Y1198971D03*
Y1191971D03*
X1341108Y1198971D03*
Y1191971D03*
X1368038Y1198971D03*
Y1191971D03*
X1383682Y214006D03*
Y207006D03*
X1392497Y112672D03*
Y119672D03*
X1387380Y1198971D03*
Y1191971D03*
X1414310Y1198971D03*
Y1191971D03*
X1433993Y531055D03*
Y538055D03*
X1441918Y215535D03*
Y222535D03*
X1441496Y281155D03*
Y274155D03*
X1441903Y445919D03*
Y452919D03*
X1443824Y484311D03*
Y491311D03*
X1441240Y1198971D03*
Y1191971D03*
X1494859Y112672D03*
Y119672D03*
X1486044Y214006D03*
Y207006D03*
X1517142Y586056D03*
Y579056D03*
X1524142Y586056D03*
Y579056D03*
X1544280Y215535D03*
Y222535D03*
X1543858Y281155D03*
Y274155D03*
X1597221Y112672D03*
Y119672D03*
X1588406Y214006D03*
Y207006D03*
X1646642Y215535D03*
Y222535D03*
X1646220Y281155D03*
Y274155D03*
X1690768Y214006D03*
Y207006D03*
X1688809Y419937D03*
Y426937D03*
Y439431D03*
Y446431D03*
X1699583Y112672D03*
Y119672D03*
X1743179Y441002D03*
X1733302Y441402D03*
Y434402D03*
X1743179Y448002D03*
X1730193Y488017D03*
Y481017D03*
X1749004Y215535D03*
Y222535D03*
X1748582Y281155D03*
Y274155D03*
X1751179Y441002D03*
Y448002D03*
X1771113Y391802D03*
Y398802D03*
X1782263Y968660D03*
Y975660D03*
X1804012Y997858D03*
Y1004858D03*
X1817965Y997858D03*
Y1004858D03*
X1811133Y997858D03*
Y1004858D03*
X1824814Y997895D03*
Y1004895D03*
G54D17*
X8460Y111710D03*
X16728D03*
X8460Y128836D03*
X16728D03*
X202994Y64722D03*
X211262D03*
X202994Y81848D03*
X211262D03*
X305356Y64722D03*
Y81848D03*
X313624Y64722D03*
Y81848D03*
X360982Y1146842D03*
X352714D03*
X360982Y1163968D03*
X352714D03*
X557719Y64722D03*
X565987D03*
X557719Y81848D03*
X565987D03*
X660081Y64722D03*
X668349D03*
X660081Y81848D03*
X668349D03*
X762443Y64722D03*
Y81848D03*
X770711Y64722D03*
Y81848D03*
X809801Y1146842D03*
Y1163968D03*
X830829Y935779D03*
Y952905D03*
X818069Y1146842D03*
Y1163968D03*
X839097Y935779D03*
Y952905D03*
X864805Y64722D03*
Y81848D03*
X873073Y64722D03*
Y81848D03*
X1014805Y64722D03*
X1023073D03*
X1014805Y81848D03*
X1023073D03*
X1117167Y64722D03*
Y81848D03*
X1125435Y64722D03*
Y81848D03*
X1219529Y64722D03*
Y81848D03*
X1227797Y64722D03*
Y81848D03*
X1266887Y1146842D03*
Y1163968D03*
X1275155Y1146842D03*
Y1163968D03*
X1471892Y64722D03*
X1480160D03*
X1471892Y81848D03*
X1480160D03*
X1574254Y64722D03*
Y81848D03*
X1582522Y64722D03*
Y81848D03*
X1594312Y1479190D03*
Y1496316D03*
X1602580Y1479190D03*
Y1496316D03*
X1676616Y64722D03*
Y81848D03*
X1684884Y64722D03*
Y81848D03*
X1723974Y1146842D03*
Y1163968D03*
X1732242Y1146842D03*
Y1163968D03*
X1778978Y64722D03*
X1787246D03*
X1778978Y81848D03*
X1787246D03*
G54D119*
X360727Y458603D03*
X466821Y473078D03*
X817813Y452603D03*
X1274900Y458603D03*
X1731987D03*
G54D62*
X42893Y619311D03*
X46436D03*
X49979D03*
X53523D03*
X499979D03*
X503522D03*
X507065D03*
X510609D03*
X957066D03*
X960609D03*
X964152D03*
X967696D03*
X1414153D03*
X1417696D03*
X1421239D03*
X1424783D03*
G54D191*
X832961Y311852D03*
Y314411D03*
Y316970D03*
Y319529D03*
Y322088D03*
Y324648D03*
Y327207D03*
Y332325D03*
Y329766D03*
Y334884D03*
X855993Y311852D03*
Y327207D03*
Y324648D03*
Y322088D03*
Y319529D03*
Y316970D03*
Y314411D03*
Y334884D03*
Y332325D03*
Y329766D03*
X1298246Y750962D03*
Y753521D03*
Y756080D03*
Y758639D03*
Y761198D03*
Y763758D03*
Y766317D03*
Y768876D03*
Y771435D03*
Y773994D03*
X1321278Y750962D03*
Y766317D03*
Y763758D03*
Y761198D03*
Y758639D03*
Y756080D03*
Y753521D03*
Y773994D03*
Y771435D03*
Y768876D03*
X1350984Y563984D03*
Y566543D03*
Y569102D03*
Y571661D03*
Y574220D03*
Y576780D03*
Y579339D03*
Y581898D03*
Y584457D03*
Y587016D03*
Y610484D03*
Y613043D03*
Y615602D03*
Y618161D03*
Y620720D03*
Y623280D03*
Y625839D03*
Y628398D03*
Y630957D03*
Y633516D03*
Y654984D03*
Y657543D03*
Y660102D03*
Y662661D03*
Y665220D03*
Y667780D03*
Y670339D03*
Y672898D03*
Y675457D03*
Y678016D03*
Y701984D03*
Y704543D03*
Y707102D03*
Y709661D03*
Y712220D03*
Y714780D03*
Y717339D03*
Y719898D03*
Y722457D03*
Y725016D03*
X1374016Y571661D03*
Y569102D03*
Y566543D03*
Y563984D03*
Y587016D03*
Y584457D03*
Y579339D03*
Y576780D03*
Y574220D03*
Y581898D03*
Y620720D03*
Y618161D03*
Y615602D03*
Y613043D03*
Y610484D03*
Y633516D03*
Y630957D03*
Y625839D03*
Y623280D03*
Y628398D03*
Y667780D03*
Y665220D03*
Y662661D03*
Y660102D03*
Y657543D03*
Y654984D03*
Y678016D03*
Y675457D03*
Y670339D03*
Y672898D03*
Y701984D03*
Y717339D03*
Y714780D03*
Y712220D03*
Y709661D03*
Y707102D03*
Y704543D03*
Y725016D03*
Y722457D03*
Y719898D03*
X1441984Y686484D03*
Y689043D03*
Y691602D03*
Y694161D03*
Y696720D03*
Y699280D03*
Y701839D03*
Y704398D03*
Y706957D03*
Y709516D03*
Y730484D03*
Y733043D03*
Y735602D03*
Y738161D03*
Y740720D03*
Y743280D03*
Y745839D03*
Y748398D03*
Y750957D03*
Y753516D03*
X1465016Y701839D03*
Y699280D03*
Y696720D03*
Y694161D03*
Y691602D03*
Y689043D03*
Y686484D03*
Y709516D03*
Y706957D03*
Y704398D03*
Y733043D03*
Y730484D03*
Y750957D03*
Y745839D03*
Y743280D03*
Y740720D03*
Y738161D03*
Y735602D03*
Y748398D03*
Y753516D03*
X1458984Y771984D03*
Y774543D03*
Y777102D03*
Y779661D03*
Y782220D03*
Y784780D03*
Y787339D03*
Y789898D03*
Y792457D03*
Y795016D03*
Y815984D03*
Y818543D03*
Y821102D03*
Y823661D03*
Y826220D03*
Y828780D03*
Y831339D03*
Y833898D03*
Y836457D03*
Y839016D03*
X1482016Y782220D03*
Y779661D03*
Y777102D03*
Y774543D03*
Y771984D03*
Y795016D03*
Y792457D03*
Y787339D03*
Y784780D03*
Y789898D03*
Y815984D03*
Y831339D03*
Y828780D03*
Y826220D03*
Y823661D03*
Y821102D03*
Y818543D03*
Y839016D03*
Y836457D03*
Y833898D03*
G54D218*
X932117Y806210D03*
Y802470D03*
G54D128*
X409284Y745280D03*
X407316D03*
X405347D03*
X403379D03*
X401410D03*
X399442D03*
X397473D03*
X395505D03*
X393536D03*
X423064D03*
X421095D03*
X419127D03*
X417158D03*
X415190D03*
X413221D03*
X411253D03*
X1772142Y877880D03*
X1770173D03*
X1768205D03*
X1766236D03*
X1789858D03*
X1787890D03*
X1785921D03*
X1783953D03*
X1781984D03*
X1780016D03*
X1778047D03*
X1776079D03*
X1774110D03*
X1795764D03*
X1793795D03*
X1791827D03*
G54D245*
X1091661Y1521648D03*
Y1540152D03*
X1099339Y1521648D03*
X1096780D03*
X1094220D03*
Y1540152D03*
X1096780D03*
X1099339D03*
G54D71*
X45558Y1199141D03*
X411135Y883491D03*
X437890Y626268D03*
X889248Y1208144D03*
X953225D03*
X1797205Y1208630D03*
G54D227*
X942586Y1499857D03*
G54D146*
X423674Y430898D03*
X919000Y447239D03*
X1337847Y430898D03*
X1794934D03*
G54D236*
X989651Y1556274D03*
X1015635D03*
G54D209*
X909360Y230906D03*
Y274606D03*
G54D155*
X440114Y339287D03*
Y337713D03*
Y344012D03*
Y332988D03*
Y342437D03*
Y340862D03*
Y336138D03*
Y334563D03*
Y331413D03*
Y329839D03*
Y347161D03*
Y345587D03*
X1342699Y342379D03*
Y340805D03*
Y336080D03*
Y343954D03*
Y339230D03*
Y337655D03*
Y334505D03*
Y332931D03*
Y347104D03*
Y350253D03*
Y348679D03*
Y345529D03*
G54D80*
X62549Y833614D03*
X579603Y947703D03*
X1001337Y842261D03*
X1021219Y944718D03*
X1795863Y975556D03*
G54D53*
X51043Y60709D03*
Y150197D03*
X153405Y60709D03*
Y150197D03*
X190325Y455492D03*
Y503760D03*
Y583957D03*
Y636752D03*
X255767Y60709D03*
Y150197D03*
X279360Y368760D03*
Y421555D03*
Y501752D03*
Y550020D03*
X358129Y60709D03*
Y150197D03*
X508130Y60709D03*
Y150197D03*
X610492Y60709D03*
Y150197D03*
X647411Y455492D03*
Y503760D03*
Y583957D03*
Y636752D03*
X712854Y60709D03*
Y150197D03*
X736446Y368760D03*
Y421555D03*
Y501752D03*
Y550020D03*
X815216Y60709D03*
Y150197D03*
X965216Y60709D03*
Y150197D03*
X1067578Y60709D03*
Y150197D03*
X1104498Y455492D03*
Y503760D03*
Y583957D03*
Y636752D03*
X1169940Y60709D03*
Y150197D03*
X1193533Y368760D03*
Y421555D03*
Y501752D03*
Y550020D03*
X1272302Y60709D03*
Y150197D03*
X1422303Y60709D03*
Y150197D03*
X1524665Y60709D03*
Y150197D03*
X1561585Y455492D03*
Y503760D03*
Y583957D03*
Y636752D03*
X1627027Y60709D03*
Y150197D03*
X1650620Y368760D03*
Y421555D03*
Y501752D03*
Y550020D03*
X1729389Y60709D03*
Y150197D03*
G54D44*
X27130Y219149D03*
X129492D03*
X231854D03*
X334216D03*
X384382Y389638D03*
X484217Y219149D03*
X586579D03*
X688941D03*
X791303D03*
X879708Y402979D03*
X941969Y204320D03*
X1043665Y219149D03*
X1146027D03*
X1248389D03*
X1298555Y389638D03*
X1398390Y219149D03*
X1500752D03*
X1603114D03*
X1705476D03*
X1755642Y389638D03*
G54D129*
X408300Y762800D03*
X1781000Y895400D03*
G54D228*
X953192Y-31798D03*
X978036Y-70978D03*
X1231336D03*
X1236692Y-31928D03*
X1487836Y-70978D03*
X1523192Y-32058D03*
X1742336Y-70978D03*
X1807692Y-32188D03*
G54D183*
X766516Y1622460D03*
X759036D03*
Y1633090D03*
X762776D03*
X766516D03*
X782289Y1623876D03*
X786029Y1614546D03*
X789769Y1623876D03*
G54D27*
X18463Y247292D03*
Y253198D03*
Y267292D03*
Y273198D03*
X25549Y247292D03*
Y253198D03*
Y267292D03*
Y273198D03*
X82918Y146461D03*
Y152367D03*
X84679Y1009260D03*
Y1015166D03*
X90004Y146461D03*
Y152367D03*
X91765Y1009260D03*
Y1015166D03*
X127911Y247292D03*
X120825D03*
Y253198D03*
X127911D03*
X192366Y146461D03*
X185280D03*
Y152367D03*
X192366D03*
X230273Y247292D03*
X223187D03*
Y253198D03*
X230273D03*
X294728Y146461D03*
X287642D03*
Y152367D03*
X294728D03*
X325549Y247292D03*
Y253198D03*
X332635Y247292D03*
Y253198D03*
X408758Y468607D03*
Y474513D03*
X415844Y468607D03*
Y474513D03*
X437643Y146461D03*
Y152367D03*
X444729Y146461D03*
Y152367D03*
X482636Y247292D03*
X475550D03*
Y253198D03*
X482636D03*
X540005Y146461D03*
Y152367D03*
X547091Y146461D03*
Y152367D03*
X548852Y1009260D03*
X541766D03*
Y1015166D03*
X548852D03*
X584998Y247292D03*
X577912D03*
Y253198D03*
X584998D03*
X649453Y146461D03*
X642367D03*
Y152367D03*
X649453D03*
X680274Y247292D03*
Y253198D03*
X687360Y247292D03*
Y253198D03*
X744729Y146461D03*
Y152367D03*
X751815Y146461D03*
Y152367D03*
X782636Y247292D03*
Y253198D03*
X789722Y247292D03*
Y253198D03*
X879997Y480350D03*
X872911D03*
Y486256D03*
X879997D03*
X894729Y146461D03*
Y152367D03*
X901815Y146461D03*
Y152367D03*
X1004177Y146461D03*
X997091D03*
Y152367D03*
X1004177D03*
X1005938Y1009260D03*
X998852D03*
Y1015166D03*
X1005938D03*
X1042084Y247292D03*
X1034998D03*
Y253198D03*
X1042084D03*
X1106539Y146461D03*
X1099453D03*
Y152367D03*
X1106539D03*
X1137360Y247292D03*
Y253198D03*
X1144446Y247292D03*
Y253198D03*
X1201815Y146461D03*
Y152367D03*
X1208901Y146461D03*
Y152367D03*
X1246808Y247292D03*
X1239722D03*
Y253198D03*
X1246808D03*
X1267792Y902371D03*
Y908277D03*
X1274878Y902371D03*
Y908277D03*
X1330017Y468607D03*
X1322931D03*
Y474513D03*
X1330017D03*
X1351816Y146461D03*
Y152367D03*
X1358902Y146461D03*
Y152367D03*
X1396809Y247292D03*
X1389723D03*
Y253198D03*
X1396809D03*
X1421368Y1537432D03*
Y1543338D03*
X1428454D03*
Y1537432D03*
X1420995Y1558072D03*
X1428081D03*
X1420995Y1563978D03*
X1428081D03*
X1461264Y146461D03*
X1454178D03*
Y152367D03*
X1461264D03*
X1463025Y1009260D03*
X1455939D03*
Y1015166D03*
X1463025D03*
X1492085Y247292D03*
Y253198D03*
X1499171Y247292D03*
Y253198D03*
X1556540Y146461D03*
Y152367D03*
X1563626Y146461D03*
Y152367D03*
X1594447Y247292D03*
Y253198D03*
X1601533Y247292D03*
Y253198D03*
X1627155Y699930D03*
Y705836D03*
Y717830D03*
X1627455Y732430D03*
X1627155Y723736D03*
X1627455Y738336D03*
Y750630D03*
Y756536D03*
X1623741Y780736D03*
Y774830D03*
X1616655D03*
Y780736D03*
X1623541Y793436D03*
Y787530D03*
X1616455D03*
Y793436D03*
X1623241Y807536D03*
Y801630D03*
X1616155D03*
Y807536D03*
X1623341Y815730D03*
X1616255D03*
X1623341Y821636D03*
X1616255D03*
X1634241Y699930D03*
Y705836D03*
Y717830D03*
X1634541Y732430D03*
X1634241Y723736D03*
X1634541Y738336D03*
Y750630D03*
Y756536D03*
X1658902Y146461D03*
Y152367D03*
X1665988Y146461D03*
Y152367D03*
X1703895Y247292D03*
X1696809D03*
Y253198D03*
X1703895D03*
X1787104Y468607D03*
X1780018D03*
Y474513D03*
X1787104D03*
X1790264Y1446668D03*
Y1440762D03*
X1783178D03*
Y1446668D03*
X1790141Y1478858D03*
Y1472952D03*
X1783055D03*
Y1478858D03*
G54D54*
X41988Y83425D03*
Y81063D03*
Y78701D03*
Y76339D03*
Y73977D03*
Y99961D03*
Y97599D03*
Y95236D03*
Y92874D03*
Y90512D03*
Y88150D03*
Y85788D03*
Y116496D03*
Y114134D03*
Y111772D03*
Y109410D03*
Y107047D03*
Y104685D03*
Y102323D03*
Y133032D03*
Y130670D03*
Y128307D03*
Y125945D03*
Y123583D03*
Y121221D03*
Y118859D03*
Y137756D03*
Y135394D03*
X60098Y83425D03*
Y81063D03*
Y78701D03*
Y76339D03*
Y73977D03*
Y99961D03*
Y97599D03*
Y95236D03*
Y92874D03*
Y90512D03*
Y88150D03*
Y85788D03*
Y116496D03*
Y114134D03*
Y111772D03*
Y109410D03*
Y107047D03*
Y104685D03*
Y102323D03*
Y133032D03*
Y130670D03*
Y128307D03*
Y125945D03*
Y123583D03*
Y121221D03*
Y118859D03*
Y137756D03*
Y135394D03*
X144350Y83425D03*
Y81063D03*
Y78701D03*
Y76339D03*
Y73977D03*
Y99961D03*
Y97599D03*
Y95236D03*
Y92874D03*
Y90512D03*
Y88150D03*
Y85788D03*
Y116496D03*
Y114134D03*
Y111772D03*
Y109410D03*
Y107047D03*
Y104685D03*
Y102323D03*
Y133032D03*
Y130670D03*
Y128307D03*
Y125945D03*
Y123583D03*
Y121221D03*
Y118859D03*
Y137756D03*
Y135394D03*
X162460Y83425D03*
Y81063D03*
Y78701D03*
Y76339D03*
Y73977D03*
Y99961D03*
Y97599D03*
Y95236D03*
Y92874D03*
Y90512D03*
Y88150D03*
Y85788D03*
Y116496D03*
Y114134D03*
Y111772D03*
Y109410D03*
Y107047D03*
Y104685D03*
Y102323D03*
Y133032D03*
Y130670D03*
Y128307D03*
Y125945D03*
Y123583D03*
Y121221D03*
Y118859D03*
Y137756D03*
Y135394D03*
X246712Y83425D03*
Y81063D03*
Y78701D03*
Y76339D03*
Y73977D03*
Y99961D03*
Y97599D03*
Y95236D03*
Y92874D03*
Y90512D03*
Y88150D03*
Y85788D03*
Y116496D03*
Y114134D03*
Y111772D03*
Y109410D03*
Y107047D03*
Y104685D03*
Y102323D03*
Y133032D03*
Y130670D03*
Y128307D03*
Y125945D03*
Y123583D03*
Y121221D03*
Y118859D03*
Y137756D03*
Y135394D03*
X264822Y83425D03*
Y81063D03*
Y78701D03*
Y76339D03*
Y73977D03*
Y99961D03*
Y97599D03*
Y95236D03*
Y92874D03*
Y90512D03*
Y88150D03*
Y85788D03*
Y116496D03*
Y114134D03*
Y111772D03*
Y109410D03*
Y107047D03*
Y104685D03*
Y102323D03*
Y133032D03*
Y130670D03*
Y128307D03*
Y125945D03*
Y123583D03*
Y121221D03*
Y118859D03*
Y137756D03*
Y135394D03*
X349074Y83425D03*
Y81063D03*
Y78701D03*
Y76339D03*
Y73977D03*
Y99961D03*
Y97599D03*
Y95236D03*
Y92874D03*
Y90512D03*
Y88150D03*
Y85788D03*
Y116496D03*
Y114134D03*
Y111772D03*
Y109410D03*
Y107047D03*
Y104685D03*
Y102323D03*
Y133032D03*
Y130670D03*
Y128307D03*
Y125945D03*
Y123583D03*
Y121221D03*
Y118859D03*
Y137756D03*
Y135394D03*
X367184Y83425D03*
Y81063D03*
Y78701D03*
Y76339D03*
Y73977D03*
Y99961D03*
Y97599D03*
Y95236D03*
Y92874D03*
Y90512D03*
Y88150D03*
Y85788D03*
Y116496D03*
Y114134D03*
Y111772D03*
Y109410D03*
Y107047D03*
Y104685D03*
Y102323D03*
Y133032D03*
Y130670D03*
Y128307D03*
Y125945D03*
Y123583D03*
Y121221D03*
Y118859D03*
Y137756D03*
Y135394D03*
X499075Y83425D03*
Y81063D03*
Y78701D03*
Y76339D03*
Y73977D03*
Y99961D03*
Y97599D03*
Y95236D03*
Y92874D03*
Y90512D03*
Y88150D03*
Y85788D03*
Y116496D03*
Y114134D03*
Y111772D03*
Y109410D03*
Y107047D03*
Y104685D03*
Y102323D03*
Y133032D03*
Y130670D03*
Y128307D03*
Y125945D03*
Y123583D03*
Y121221D03*
Y118859D03*
Y137756D03*
Y135394D03*
X517185Y83425D03*
Y81063D03*
Y78701D03*
Y76339D03*
Y73977D03*
Y99961D03*
Y97599D03*
Y95236D03*
Y92874D03*
Y90512D03*
Y88150D03*
Y85788D03*
Y116496D03*
Y114134D03*
Y111772D03*
Y109410D03*
Y107047D03*
Y104685D03*
Y102323D03*
Y133032D03*
Y130670D03*
Y128307D03*
Y125945D03*
Y123583D03*
Y121221D03*
Y118859D03*
Y137756D03*
Y135394D03*
X601437Y83425D03*
Y81063D03*
Y78701D03*
Y76339D03*
Y73977D03*
Y99961D03*
Y97599D03*
Y95236D03*
Y92874D03*
Y90512D03*
Y88150D03*
Y85788D03*
Y116496D03*
Y114134D03*
Y111772D03*
Y109410D03*
Y107047D03*
Y104685D03*
Y102323D03*
Y133032D03*
Y130670D03*
Y128307D03*
Y125945D03*
Y123583D03*
Y121221D03*
Y118859D03*
Y137756D03*
Y135394D03*
X619547Y83425D03*
Y81063D03*
Y78701D03*
Y76339D03*
Y73977D03*
Y99961D03*
Y97599D03*
Y95236D03*
Y92874D03*
Y90512D03*
Y88150D03*
Y85788D03*
Y116496D03*
Y114134D03*
Y111772D03*
Y109410D03*
Y107047D03*
Y104685D03*
Y102323D03*
Y133032D03*
Y130670D03*
Y128307D03*
Y125945D03*
Y123583D03*
Y121221D03*
Y118859D03*
Y137756D03*
Y135394D03*
X703799Y83425D03*
Y81063D03*
Y78701D03*
Y76339D03*
Y73977D03*
Y99961D03*
Y97599D03*
Y95236D03*
Y92874D03*
Y90512D03*
Y88150D03*
Y85788D03*
Y116496D03*
Y114134D03*
Y111772D03*
Y109410D03*
Y107047D03*
Y104685D03*
Y102323D03*
Y133032D03*
Y130670D03*
Y128307D03*
Y125945D03*
Y123583D03*
Y121221D03*
Y118859D03*
Y137756D03*
Y135394D03*
X721909Y83425D03*
Y81063D03*
Y78701D03*
Y76339D03*
Y73977D03*
Y99961D03*
Y97599D03*
Y95236D03*
Y92874D03*
Y90512D03*
Y88150D03*
Y85788D03*
Y116496D03*
Y114134D03*
Y111772D03*
Y109410D03*
Y107047D03*
Y104685D03*
Y102323D03*
Y133032D03*
Y130670D03*
Y128307D03*
Y125945D03*
Y123583D03*
Y121221D03*
Y118859D03*
Y137756D03*
Y135394D03*
X806161Y83425D03*
Y81063D03*
Y78701D03*
Y76339D03*
Y73977D03*
Y99961D03*
Y97599D03*
Y95236D03*
Y92874D03*
Y90512D03*
Y88150D03*
Y85788D03*
Y116496D03*
Y114134D03*
Y111772D03*
Y109410D03*
Y107047D03*
Y104685D03*
Y102323D03*
Y133032D03*
Y130670D03*
Y128307D03*
Y125945D03*
Y123583D03*
Y121221D03*
Y118859D03*
Y137756D03*
Y135394D03*
X824271Y83425D03*
Y81063D03*
Y78701D03*
Y76339D03*
Y73977D03*
Y99961D03*
Y97599D03*
Y95236D03*
Y92874D03*
Y90512D03*
Y88150D03*
Y85788D03*
Y116496D03*
Y114134D03*
Y111772D03*
Y109410D03*
Y107047D03*
Y104685D03*
Y102323D03*
Y133032D03*
Y130670D03*
Y128307D03*
Y125945D03*
Y123583D03*
Y121221D03*
Y118859D03*
Y137756D03*
Y135394D03*
X956161Y83425D03*
Y81063D03*
Y78701D03*
Y76339D03*
Y73977D03*
Y99961D03*
Y97599D03*
Y95236D03*
Y92874D03*
Y90512D03*
Y88150D03*
Y85788D03*
Y116496D03*
Y114134D03*
Y111772D03*
Y109410D03*
Y107047D03*
Y104685D03*
Y102323D03*
Y133032D03*
Y130670D03*
Y128307D03*
Y125945D03*
Y123583D03*
Y121221D03*
Y118859D03*
Y137756D03*
Y135394D03*
X974271Y83425D03*
Y81063D03*
Y78701D03*
Y76339D03*
Y73977D03*
Y99961D03*
Y97599D03*
Y95236D03*
Y92874D03*
Y90512D03*
Y88150D03*
Y85788D03*
Y116496D03*
Y114134D03*
Y111772D03*
Y109410D03*
Y107047D03*
Y104685D03*
Y102323D03*
Y133032D03*
Y130670D03*
Y128307D03*
Y125945D03*
Y123583D03*
Y121221D03*
Y118859D03*
Y137756D03*
Y135394D03*
X1058523Y83425D03*
Y81063D03*
Y78701D03*
Y76339D03*
Y73977D03*
Y99961D03*
Y97599D03*
Y95236D03*
Y92874D03*
Y90512D03*
Y88150D03*
Y85788D03*
Y116496D03*
Y114134D03*
Y111772D03*
Y109410D03*
Y107047D03*
Y104685D03*
Y102323D03*
Y133032D03*
Y130670D03*
Y128307D03*
Y125945D03*
Y123583D03*
Y121221D03*
Y118859D03*
Y137756D03*
Y135394D03*
X1076633Y83425D03*
Y81063D03*
Y78701D03*
Y76339D03*
Y73977D03*
Y99961D03*
Y97599D03*
Y95236D03*
Y92874D03*
Y90512D03*
Y88150D03*
Y85788D03*
Y116496D03*
Y114134D03*
Y111772D03*
Y109410D03*
Y107047D03*
Y104685D03*
Y102323D03*
Y133032D03*
Y130670D03*
Y128307D03*
Y125945D03*
Y123583D03*
Y121221D03*
Y118859D03*
Y137756D03*
Y135394D03*
X1160885Y83425D03*
Y81063D03*
Y78701D03*
Y76339D03*
Y73977D03*
Y99961D03*
Y97599D03*
Y95236D03*
Y92874D03*
Y90512D03*
Y88150D03*
Y85788D03*
Y116496D03*
Y114134D03*
Y111772D03*
Y109410D03*
Y107047D03*
Y104685D03*
Y102323D03*
Y133032D03*
Y130670D03*
Y128307D03*
Y125945D03*
Y123583D03*
Y121221D03*
Y118859D03*
Y137756D03*
Y135394D03*
X1178995Y83425D03*
Y81063D03*
Y78701D03*
Y76339D03*
Y73977D03*
Y99961D03*
Y97599D03*
Y95236D03*
Y92874D03*
Y90512D03*
Y88150D03*
Y85788D03*
Y116496D03*
Y114134D03*
Y111772D03*
Y109410D03*
Y107047D03*
Y104685D03*
Y102323D03*
Y133032D03*
Y130670D03*
Y128307D03*
Y125945D03*
Y123583D03*
Y121221D03*
Y118859D03*
Y137756D03*
Y135394D03*
X1263247Y83425D03*
Y81063D03*
Y78701D03*
Y76339D03*
Y73977D03*
Y99961D03*
Y97599D03*
Y95236D03*
Y92874D03*
Y90512D03*
Y88150D03*
Y85788D03*
Y116496D03*
Y114134D03*
Y111772D03*
Y109410D03*
Y107047D03*
Y104685D03*
Y102323D03*
Y133032D03*
Y130670D03*
Y128307D03*
Y125945D03*
Y123583D03*
Y121221D03*
Y118859D03*
Y137756D03*
Y135394D03*
X1281357Y83425D03*
Y81063D03*
Y78701D03*
Y76339D03*
Y73977D03*
Y99961D03*
Y97599D03*
Y95236D03*
Y92874D03*
Y90512D03*
Y88150D03*
Y85788D03*
Y116496D03*
Y114134D03*
Y111772D03*
Y109410D03*
Y107047D03*
Y104685D03*
Y102323D03*
Y133032D03*
Y130670D03*
Y128307D03*
Y125945D03*
Y123583D03*
Y121221D03*
Y118859D03*
Y137756D03*
Y135394D03*
X1413248Y83425D03*
Y81063D03*
Y78701D03*
Y76339D03*
Y73977D03*
Y99961D03*
Y97599D03*
Y95236D03*
Y92874D03*
Y90512D03*
Y88150D03*
Y85788D03*
Y116496D03*
Y114134D03*
Y111772D03*
Y109410D03*
Y107047D03*
Y104685D03*
Y102323D03*
Y133032D03*
Y130670D03*
Y128307D03*
Y125945D03*
Y123583D03*
Y121221D03*
Y118859D03*
Y137756D03*
Y135394D03*
X1431358Y83425D03*
Y81063D03*
Y78701D03*
Y76339D03*
Y73977D03*
Y99961D03*
Y97599D03*
Y95236D03*
Y92874D03*
Y90512D03*
Y88150D03*
Y85788D03*
Y116496D03*
Y114134D03*
Y111772D03*
Y109410D03*
Y107047D03*
Y104685D03*
Y102323D03*
Y133032D03*
Y130670D03*
Y128307D03*
Y125945D03*
Y123583D03*
Y121221D03*
Y118859D03*
Y137756D03*
Y135394D03*
X1515610Y83425D03*
Y81063D03*
Y78701D03*
Y76339D03*
Y73977D03*
Y99961D03*
Y97599D03*
Y95236D03*
Y92874D03*
Y90512D03*
Y88150D03*
Y85788D03*
Y116496D03*
Y114134D03*
Y111772D03*
Y109410D03*
Y107047D03*
Y104685D03*
Y102323D03*
Y133032D03*
Y130670D03*
Y128307D03*
Y125945D03*
Y123583D03*
Y121221D03*
Y118859D03*
Y137756D03*
Y135394D03*
X1533720Y83425D03*
Y81063D03*
Y78701D03*
Y76339D03*
Y73977D03*
Y99961D03*
Y97599D03*
Y95236D03*
Y92874D03*
Y90512D03*
Y88150D03*
Y85788D03*
Y116496D03*
Y114134D03*
Y111772D03*
Y109410D03*
Y107047D03*
Y104685D03*
Y102323D03*
Y133032D03*
Y130670D03*
Y128307D03*
Y125945D03*
Y123583D03*
Y121221D03*
Y118859D03*
Y137756D03*
Y135394D03*
X1617972Y83425D03*
Y81063D03*
Y78701D03*
Y76339D03*
Y73977D03*
Y99961D03*
Y97599D03*
Y95236D03*
Y92874D03*
Y90512D03*
Y88150D03*
Y85788D03*
Y116496D03*
Y114134D03*
Y111772D03*
Y109410D03*
Y107047D03*
Y104685D03*
Y102323D03*
Y133032D03*
Y130670D03*
Y128307D03*
Y125945D03*
Y123583D03*
Y121221D03*
Y118859D03*
Y137756D03*
Y135394D03*
X1636082Y83425D03*
Y81063D03*
Y78701D03*
Y76339D03*
Y73977D03*
Y99961D03*
Y97599D03*
Y95236D03*
Y92874D03*
Y90512D03*
Y88150D03*
Y85788D03*
Y116496D03*
Y114134D03*
Y111772D03*
Y109410D03*
Y107047D03*
Y104685D03*
Y102323D03*
Y133032D03*
Y130670D03*
Y128307D03*
Y125945D03*
Y123583D03*
Y121221D03*
Y118859D03*
Y137756D03*
Y135394D03*
X1720334Y83425D03*
Y81063D03*
Y78701D03*
Y76339D03*
Y73977D03*
Y99961D03*
Y97599D03*
Y95236D03*
Y92874D03*
Y90512D03*
Y88150D03*
Y85788D03*
Y116496D03*
Y114134D03*
Y111772D03*
Y109410D03*
Y107047D03*
Y104685D03*
Y102323D03*
Y133032D03*
Y130670D03*
Y128307D03*
Y125945D03*
Y123583D03*
Y121221D03*
Y118859D03*
Y137756D03*
Y135394D03*
X1738444Y83425D03*
Y81063D03*
Y78701D03*
Y76339D03*
Y73977D03*
Y99961D03*
Y97599D03*
Y95236D03*
Y92874D03*
Y90512D03*
Y88150D03*
Y85788D03*
Y116496D03*
Y114134D03*
Y111772D03*
Y109410D03*
Y107047D03*
Y104685D03*
Y102323D03*
Y133032D03*
Y130670D03*
Y128307D03*
Y125945D03*
Y123583D03*
Y121221D03*
Y118859D03*
Y137756D03*
Y135394D03*
G54D192*
X836701Y758161D03*
Y760720D03*
Y763280D03*
Y765839D03*
Y776161D03*
Y778720D03*
Y781280D03*
Y783839D03*
Y794161D03*
Y796720D03*
Y799280D03*
Y801839D03*
Y812161D03*
Y814720D03*
Y817280D03*
Y819839D03*
X854299Y765839D03*
Y763280D03*
Y760720D03*
Y758161D03*
Y781280D03*
Y778720D03*
Y776161D03*
Y783839D03*
Y799280D03*
Y796720D03*
Y794161D03*
Y801839D03*
Y814720D03*
Y812161D03*
Y819839D03*
Y817280D03*
G54D246*
X1150912Y324148D03*
Y329148D03*
Y334148D03*
Y339148D03*
X1171712Y324148D03*
Y334148D03*
Y339148D03*
Y329148D03*
G54D81*
X59134Y875295D03*
Y870295D03*
Y880295D03*
Y885295D03*
Y890295D03*
Y895295D03*
Y905295D03*
Y900295D03*
X96930Y875295D03*
Y880295D03*
Y870295D03*
Y885295D03*
Y890295D03*
Y895295D03*
Y905295D03*
Y900295D03*
X516074Y875295D03*
Y870295D03*
Y880295D03*
Y885295D03*
Y890295D03*
Y895295D03*
Y905295D03*
Y900295D03*
X553870Y875295D03*
Y880295D03*
Y870295D03*
Y885295D03*
Y890295D03*
Y895295D03*
Y905295D03*
Y900295D03*
X972833Y870295D03*
Y875295D03*
Y880295D03*
Y885295D03*
Y890295D03*
Y895295D03*
Y900295D03*
Y905295D03*
X1010629Y880295D03*
Y875295D03*
Y870295D03*
Y895295D03*
Y890295D03*
Y885295D03*
Y905295D03*
Y900295D03*
X1430247Y875295D03*
Y870295D03*
Y880295D03*
Y885295D03*
Y890295D03*
Y895295D03*
Y905295D03*
Y900295D03*
X1468043Y875295D03*
Y880295D03*
Y870295D03*
Y885295D03*
Y890295D03*
Y895295D03*
Y905295D03*
Y900295D03*
G54D255*
X1817323Y1567323D03*
G54D90*
X78447Y273540D03*
X180809D03*
X283171D03*
X385533D03*
X535534D03*
X637896D03*
X740258D03*
X842620D03*
X992620D03*
X1094982D03*
X1197344D03*
X1299706D03*
X1449707D03*
X1552069D03*
X1654431D03*
X1756793D03*
G54D45*
X34292Y601811D03*
Y607311D03*
X40092Y601811D03*
Y607311D03*
X82715Y656990D03*
X88515D03*
X96871Y1027663D03*
X109164Y1005353D03*
X103364D03*
X102671Y1027663D03*
X115533Y1103108D03*
Y1115708D03*
Y1128308D03*
Y1140908D03*
Y1153508D03*
Y1166108D03*
Y1178708D03*
X127179Y1010371D03*
X132979D03*
X127179Y1022971D03*
X132979D03*
X121333Y1103108D03*
X133954Y1110308D03*
X128154D03*
X133954Y1122908D03*
X128154D03*
X121333Y1115708D03*
X133954Y1135508D03*
X128154D03*
X121333Y1128308D03*
Y1140908D03*
X133954Y1148108D03*
X128154D03*
X121333Y1153508D03*
X133954Y1160708D03*
X128154D03*
X133954Y1173308D03*
X128154D03*
X121333Y1166108D03*
X133954Y1185908D03*
X128154D03*
X121333Y1178708D03*
X145600Y1017571D03*
X139800D03*
X145600Y1030171D03*
X139800D03*
X400728Y344439D03*
X406528D03*
Y349939D03*
X400728D03*
X399300Y793800D03*
X405100D03*
X456439Y1247517D03*
X462239D03*
X491378Y601811D03*
Y607311D03*
X489835Y1037680D03*
X497178Y601811D03*
Y607311D03*
X495735Y1037680D03*
X534624Y774889D03*
X540424D03*
X549304Y846389D03*
X555104D03*
X553958Y1027663D03*
X566251Y1005353D03*
X560451D03*
X559758Y1027663D03*
X572620Y1103108D03*
Y1115708D03*
Y1128308D03*
Y1140908D03*
Y1153508D03*
Y1166108D03*
Y1178708D03*
X584266Y1010371D03*
Y1022971D03*
X578420Y1103108D03*
Y1115708D03*
X585241Y1110308D03*
Y1122908D03*
Y1135508D03*
X578420Y1128308D03*
Y1140908D03*
X585241Y1148108D03*
X578420Y1153508D03*
X585241Y1160708D03*
Y1173308D03*
X578420Y1166108D03*
X585241Y1185908D03*
X578420Y1178708D03*
X590066Y1010371D03*
X602687Y1017571D03*
X596887D03*
X590066Y1022971D03*
X602687Y1030171D03*
X596887D03*
X591041Y1110308D03*
Y1122908D03*
Y1135508D03*
Y1148108D03*
Y1160708D03*
Y1173308D03*
Y1185908D03*
X948465Y601811D03*
X954265D03*
Y607311D03*
X948465D03*
X1011044Y1027663D03*
X1023337Y1005353D03*
X1017537D03*
X1016844Y1027663D03*
X1041352Y1010371D03*
Y1022971D03*
X1029706Y1103108D03*
X1035506D03*
X1029706Y1115708D03*
X1035506D03*
X1042327Y1110308D03*
Y1122908D03*
X1029706Y1140908D03*
X1035506D03*
X1029706Y1128308D03*
X1035506D03*
X1042327Y1135508D03*
X1029706Y1153508D03*
X1035506D03*
X1042327Y1148108D03*
X1029706Y1166108D03*
X1035506D03*
X1042327Y1160708D03*
Y1173308D03*
X1029706Y1178708D03*
X1035506D03*
X1042327Y1185908D03*
X1047152Y1010371D03*
Y1022971D03*
X1059773Y1017571D03*
X1053973D03*
X1059773Y1030171D03*
X1053973D03*
X1048127Y1110308D03*
Y1122908D03*
Y1135508D03*
Y1148108D03*
Y1160708D03*
Y1173308D03*
Y1185908D03*
X1303313Y351454D03*
Y356954D03*
X1309113Y351454D03*
Y356954D03*
X1405552Y601811D03*
X1411352D03*
Y607311D03*
X1405552D03*
X1409909Y1037680D03*
X1404009D03*
X1480424Y1005353D03*
X1474624D03*
X1468131Y1027663D03*
X1473931D03*
X1498439Y1010371D03*
Y1022971D03*
X1486793Y1103108D03*
X1492593D03*
X1486793Y1115708D03*
X1492593D03*
X1486793Y1128308D03*
X1492593D03*
X1486793Y1140908D03*
X1492593D03*
X1486793Y1153508D03*
X1492593D03*
X1486793Y1166108D03*
X1492593D03*
X1486793Y1178708D03*
X1492593D03*
X1499383Y902240D03*
X1505183D03*
X1514063Y973740D03*
X1504239Y1010371D03*
Y1022971D03*
X1511060Y1017571D03*
Y1030171D03*
X1505214Y1122908D03*
X1499414D03*
X1505214Y1110308D03*
X1499414D03*
X1505214Y1135508D03*
X1499414D03*
X1505214Y1148108D03*
X1499414D03*
X1505214Y1173308D03*
X1499414D03*
X1505214Y1160708D03*
X1499414D03*
X1505214Y1185908D03*
X1499414D03*
X1519863Y973740D03*
X1516860Y1017571D03*
Y1030171D03*
X1777250Y929249D03*
X1783050D03*
X1802965Y1075688D03*
X1808765D03*
G54D63*
X39743Y617343D03*
Y621279D03*
X418161Y432227D03*
Y434195D03*
Y436164D03*
Y438133D03*
Y440101D03*
Y442069D03*
Y444038D03*
Y446007D03*
Y447975D03*
X429185Y438133D03*
Y442069D03*
Y434195D03*
Y440101D03*
Y436164D03*
Y446007D03*
Y444038D03*
Y447975D03*
X496829Y617343D03*
Y621279D03*
X913487Y448568D03*
Y450536D03*
Y452505D03*
Y454474D03*
Y456442D03*
Y458410D03*
Y460379D03*
Y462348D03*
Y464316D03*
X924511Y454474D03*
Y450536D03*
Y456442D03*
Y452505D03*
Y458410D03*
Y462348D03*
Y460379D03*
Y464316D03*
X953916Y617343D03*
Y621279D03*
X1332334Y432227D03*
Y434195D03*
Y436164D03*
Y438133D03*
Y440101D03*
Y442069D03*
Y444038D03*
Y446007D03*
Y447975D03*
X1343358Y438133D03*
Y442069D03*
Y434195D03*
Y440101D03*
Y436164D03*
Y446007D03*
Y444038D03*
Y447975D03*
X1411003Y617343D03*
Y621279D03*
X1789421Y432227D03*
Y434195D03*
Y436164D03*
Y438133D03*
Y440101D03*
Y442069D03*
Y444038D03*
Y446007D03*
Y447975D03*
X1800445Y438133D03*
Y442069D03*
Y434195D03*
Y440101D03*
Y436164D03*
Y446007D03*
Y444038D03*
Y447975D03*
G54D36*
X24792Y1072879D03*
Y1091383D03*
X62945Y170686D03*
Y189190D03*
X165307Y170686D03*
Y189190D03*
X267669Y170686D03*
Y189190D03*
X370031Y170686D03*
Y189190D03*
X414809Y951287D03*
Y969791D03*
X520032Y170686D03*
Y189190D03*
X622394Y170686D03*
Y189190D03*
X724756Y170686D03*
Y189190D03*
X827118Y170686D03*
Y189190D03*
X871249Y1081804D03*
Y1100308D03*
X935382Y1081609D03*
Y1100113D03*
X977118Y170686D03*
Y189190D03*
X1079480Y170686D03*
Y189190D03*
X1181842Y170686D03*
Y189190D03*
X1284204Y170686D03*
Y189190D03*
X1434205Y170686D03*
Y189190D03*
X1536567Y170686D03*
Y189190D03*
X1638929Y170686D03*
Y189190D03*
X1741291Y170686D03*
Y189190D03*
X1779439Y1082446D03*
Y1100950D03*
G54D72*
X45755Y1204259D03*
Y1202684D03*
Y1201110D03*
Y1210558D03*
Y1208984D03*
Y1207409D03*
Y1205834D03*
X410938Y872074D03*
Y873648D03*
Y875223D03*
Y876798D03*
Y878373D03*
Y879948D03*
Y881522D03*
X438087Y636111D03*
Y634536D03*
Y632961D03*
Y631386D03*
Y629811D03*
Y628237D03*
Y637685D03*
X889445Y1219561D03*
Y1217987D03*
Y1216412D03*
Y1214837D03*
Y1213262D03*
Y1211687D03*
Y1210113D03*
X953422Y1219561D03*
Y1217987D03*
Y1216412D03*
Y1214837D03*
Y1213262D03*
Y1211687D03*
Y1210113D03*
X1797402Y1220047D03*
Y1218473D03*
Y1216898D03*
Y1215323D03*
Y1213748D03*
Y1212173D03*
Y1210599D03*
G54D138*
X397498Y1539978D03*
Y1538009D03*
Y1541947D03*
Y1545883D03*
Y1543915D03*
Y1549821D03*
Y1547852D03*
X416494Y1543915D03*
Y1541947D03*
Y1538009D03*
Y1545883D03*
Y1539978D03*
Y1547852D03*
Y1549821D03*
X911845Y359317D03*
Y357348D03*
Y361286D03*
Y369160D03*
Y367191D03*
Y365222D03*
Y363254D03*
X930841Y357348D03*
Y359317D03*
Y363254D03*
Y361286D03*
Y367191D03*
Y365222D03*
Y369160D03*
G54D18*
X13874Y111710D03*
X11314D03*
X13874Y128836D03*
X11314D03*
X208408Y64722D03*
X205848D03*
X208408Y81848D03*
X205848D03*
X310770Y64722D03*
X308210D03*
X310770Y81848D03*
X308210D03*
X355568Y1146842D03*
X358128D03*
X355568Y1163968D03*
X358128D03*
X563133Y64722D03*
X560573D03*
X563133Y81848D03*
X560573D03*
X665495Y64722D03*
X662935D03*
X665495Y81848D03*
X662935D03*
X765297Y64722D03*
Y81848D03*
X767857Y64722D03*
Y81848D03*
X812655Y1146842D03*
X815215D03*
X812655Y1163968D03*
X815215D03*
X836243Y935779D03*
X833683D03*
Y952905D03*
X836243D03*
X870219Y64722D03*
X867659D03*
X870219Y81848D03*
X867659D03*
X1020219Y64722D03*
X1017659D03*
X1020219Y81848D03*
X1017659D03*
X1122581Y64722D03*
X1120021D03*
X1122581Y81848D03*
X1120021D03*
X1224943Y64722D03*
X1222383D03*
X1224943Y81848D03*
X1222383D03*
X1269741Y1146842D03*
Y1163968D03*
X1272301Y1146842D03*
Y1163968D03*
X1477306Y64722D03*
X1474746D03*
X1477306Y81848D03*
X1474746D03*
X1577108Y64722D03*
Y81848D03*
X1579668Y64722D03*
Y81848D03*
X1599726Y1479190D03*
X1597166D03*
X1599726Y1496316D03*
X1597166D03*
X1682030Y64722D03*
X1679470D03*
X1682030Y81848D03*
X1679470D03*
X1726828Y1146842D03*
X1729388D03*
X1726828Y1163968D03*
X1729388D03*
X1784392Y64722D03*
X1781832D03*
X1784392Y81848D03*
X1781832D03*
G54D237*
X1022350Y331915D03*
G54D219*
X943716Y861015D03*
Y857865D03*
G54D156*
X429086Y432227D03*
X924412Y448568D03*
X1343259Y432227D03*
X1800346D03*
G54D174*
X710406Y-26826D03*
Y-36826D03*
D03*
Y-26826D03*
X735406D03*
Y-36826D03*
D03*
Y-26826D03*
X830406Y-76006D03*
D03*
Y-66006D03*
D03*
X855406Y-76006D03*
D03*
Y-66006D03*
D03*
X939542Y-36798D03*
Y-26798D03*
D03*
Y-36798D03*
X964386Y-75978D03*
D03*
Y-65978D03*
D03*
X964542Y-36798D03*
Y-26798D03*
D03*
Y-36798D03*
X989386Y-75978D03*
D03*
Y-65978D03*
D03*
X993906Y-46826D03*
Y-36826D03*
D03*
Y-26826D03*
X1018906Y-46826D03*
Y-36826D03*
D03*
Y-26826D03*
X1063906Y-76006D03*
Y-86006D03*
Y-76006D03*
Y-66006D03*
X1088906Y-76006D03*
Y-86006D03*
Y-76006D03*
Y-66006D03*
X1217686Y-85978D03*
Y-75978D03*
D03*
Y-65978D03*
X1223042Y-46928D03*
Y-36928D03*
Y-26928D03*
Y-36928D03*
X1242686Y-85978D03*
Y-75978D03*
D03*
Y-65978D03*
X1248042Y-46928D03*
Y-36928D03*
Y-26928D03*
Y-36928D03*
X1280406Y-46956D03*
Y-36956D03*
D03*
Y-26956D03*
X1305406Y-46956D03*
Y-36956D03*
D03*
Y-26956D03*
X1320406Y-76006D03*
Y-86006D03*
Y-76006D03*
Y-66006D03*
X1345406Y-76006D03*
Y-86006D03*
Y-76006D03*
Y-66006D03*
X1474186Y-85978D03*
Y-75978D03*
D03*
Y-65978D03*
X1499186Y-85978D03*
Y-75978D03*
D03*
Y-65978D03*
X1509542Y-47058D03*
Y-37058D03*
Y-27058D03*
Y-37058D03*
X1534542Y-47058D03*
Y-37058D03*
Y-27058D03*
Y-37058D03*
X1564906Y-47086D03*
Y-37086D03*
D03*
Y-27086D03*
X1574906Y-76006D03*
Y-86006D03*
Y-76006D03*
Y-66006D03*
X1589906Y-47086D03*
Y-37086D03*
D03*
Y-27086D03*
X1599906Y-76006D03*
Y-86006D03*
Y-76006D03*
Y-66006D03*
X1728686Y-85978D03*
Y-75978D03*
D03*
Y-65978D03*
X1753686Y-85978D03*
Y-75978D03*
D03*
Y-65978D03*
X1794042Y-47188D03*
Y-37188D03*
Y-27188D03*
Y-37188D03*
X1819042Y-47188D03*
Y-37188D03*
Y-27188D03*
Y-37188D03*
G54D147*
X424040Y532429D03*
Y549751D03*
X447704Y532429D03*
Y549751D03*
G54D165*
X513666Y696458D03*
Y690553D03*
X521540Y688584D03*
X517603Y690553D03*
X519571D03*
X513666Y700395D03*
X515634Y690553D03*
X521540D03*
X513666Y692521D03*
Y694490D03*
Y698427D03*
X511697Y696458D03*
Y698427D03*
X519571Y688584D03*
X517603D03*
X515634D03*
X513666D03*
X511697Y700395D03*
Y688584D03*
Y690553D03*
Y692521D03*
Y694490D03*
X517603Y708269D03*
X513666Y702364D03*
Y708269D03*
X521540D03*
X513666Y704332D03*
Y706301D03*
X519571Y708269D03*
X515634D03*
X511697Y702364D03*
Y704332D03*
Y706301D03*
Y708269D03*
Y710238D03*
X513666D03*
X515634D03*
X517603D03*
X519571D03*
X521540D03*
X531382Y696458D03*
Y692521D03*
X529414Y690553D03*
X525477D03*
X531382D03*
Y700395D03*
X527445Y690553D03*
X523508D03*
X531382Y694490D03*
Y698427D03*
X533351Y700395D03*
Y698427D03*
Y696458D03*
Y694490D03*
Y692521D03*
Y690553D03*
Y688584D03*
X531382D03*
X529414D03*
X527445D03*
X525477D03*
X523508D03*
X525477Y708269D03*
X533351Y702364D03*
X529414Y708269D03*
X531382Y706301D03*
Y702364D03*
Y708269D03*
Y704332D03*
X527445Y708269D03*
X523508D03*
Y710238D03*
X525477D03*
X527445D03*
X529414D03*
X531382D03*
X533351D03*
Y708269D03*
Y706301D03*
Y704332D03*
G54D256*
G01X-20602Y-468335D02*
Y-543335D01*
X479398D01*
Y-468335D01*
X-20602D01*
G01X-8602Y-533335D02*
Y-538335D01*
G01X-10059Y-533335D02*
X-7145D01*
G01X-2235Y-538335D02*
X-4769D01*
Y-533335D01*
X-2235D01*
G01X-3249Y-535752D02*
X-4769D01*
G01X331Y-533335D02*
Y-538335D01*
X2865D01*
G01X6698Y-538502D02*
X6571Y-538418D01*
Y-538252D01*
X6698Y-538168D01*
X6825Y-538252D01*
Y-538418D01*
X6698Y-538502D01*
G01Y-536252D02*
X6571Y-536168D01*
Y-536002D01*
X6698Y-535918D01*
X6825Y-536002D01*
Y-536168D01*
X6698Y-536252D01*
G01X11481Y-540002D02*
X10848Y-539168D01*
X10531Y-538335D01*
Y-535002D01*
X10848Y-534168D01*
X11481Y-533335D01*
G01X16898D02*
X16391Y-533502D01*
X16011Y-533918D01*
X15758Y-534418D01*
X15568Y-535085D01*
X15505Y-535835D01*
X15568Y-536585D01*
X15758Y-537252D01*
X16011Y-537752D01*
X16391Y-538168D01*
X16898Y-538335D01*
X17405Y-538168D01*
X17785Y-537752D01*
X18038Y-537252D01*
X18228Y-536585D01*
X18291Y-535835D01*
X18228Y-535085D01*
X18038Y-534418D01*
X17785Y-533918D01*
X17405Y-533502D01*
X16898Y-533335D01*
G01X20605Y-537335D02*
X20985Y-537918D01*
X21491Y-538252D01*
X22061Y-538335D01*
X22568Y-538252D01*
X23075Y-537835D01*
X23391Y-537335D01*
X23455Y-536835D01*
X23328Y-536252D01*
X22885Y-535835D01*
X22441Y-535668D01*
X21871D01*
G01X22441D02*
X22821Y-535418D01*
X23138Y-535002D01*
X23265Y-534502D01*
X23138Y-534002D01*
X22821Y-533585D01*
X22251Y-533335D01*
X21681Y-533418D01*
X21111Y-533752D01*
G01X27415Y-540002D02*
X28048Y-539168D01*
X28365Y-538335D01*
Y-535002D01*
X28048Y-534168D01*
X27415Y-533335D01*
G01X30805Y-537335D02*
X31185Y-537918D01*
X31691Y-538252D01*
X32261Y-538335D01*
X32768Y-538252D01*
X33275Y-537835D01*
X33591Y-537335D01*
X33655Y-536835D01*
X33528Y-536252D01*
X33085Y-535835D01*
X32641Y-535668D01*
X32071D01*
G01X32641D02*
X33021Y-535418D01*
X33338Y-535002D01*
X33465Y-534502D01*
X33338Y-534002D01*
X33021Y-533585D01*
X32451Y-533335D01*
X31881Y-533418D01*
X31311Y-533752D01*
G01X36095Y-534168D02*
X36475Y-533668D01*
X36918Y-533418D01*
X37425Y-533335D01*
X38058Y-533502D01*
X38501Y-533918D01*
X38628Y-534418D01*
X38565Y-534918D01*
X38311Y-535335D01*
X37045Y-536168D01*
X36475Y-536752D01*
X36095Y-537585D01*
X35968Y-538335D01*
X38628D01*
G01X42271D02*
X42398Y-537252D01*
X42588Y-536335D01*
X42841Y-535502D01*
X43158Y-534585D01*
X43665Y-533335D01*
X41131D01*
G01X46675Y-536668D02*
X48321D01*
G01X51395Y-534168D02*
X51775Y-533668D01*
X52218Y-533418D01*
X52725Y-533335D01*
X53358Y-533502D01*
X53801Y-533918D01*
X53928Y-534418D01*
X53865Y-534918D01*
X53611Y-535335D01*
X52345Y-536168D01*
X51775Y-536752D01*
X51395Y-537585D01*
X51268Y-538335D01*
X53928D01*
G01X56305Y-537335D02*
X56685Y-537918D01*
X57191Y-538252D01*
X57761Y-538335D01*
X58268Y-538252D01*
X58775Y-537835D01*
X59091Y-537335D01*
X59155Y-536835D01*
X59028Y-536252D01*
X58585Y-535835D01*
X58141Y-535668D01*
X57571D01*
G01X58141D02*
X58521Y-535418D01*
X58838Y-535002D01*
X58965Y-534502D01*
X58838Y-534002D01*
X58521Y-533585D01*
X57951Y-533335D01*
X57381Y-533418D01*
X56811Y-533752D01*
G01X63558Y-538335D02*
Y-533335D01*
X61215Y-536918D01*
X64381D01*
G01X66505Y-537585D02*
X66885Y-538002D01*
X67328Y-538252D01*
X67898Y-538335D01*
X68468Y-538168D01*
X68911Y-537835D01*
X69228Y-537252D01*
X69291Y-536585D01*
X69165Y-535918D01*
X68848Y-535502D01*
X68405Y-535168D01*
X67961Y-535085D01*
X67518Y-535168D01*
X66948Y-535502D01*
X67138Y-533335D01*
X68848D01*
G01X76895Y-538335D02*
Y-533335D01*
X79301D01*
G01X78415Y-535752D02*
X76895D01*
G01X81615Y-538335D02*
X83198Y-533335D01*
X84781Y-538335D01*
G01X84211Y-536585D02*
X82185D01*
G01X86968Y-538335D02*
X89628Y-533335D01*
G01X86968D02*
X89628Y-538335D01*
G01X93398Y-538502D02*
X93271Y-538418D01*
Y-538252D01*
X93398Y-538168D01*
X93525Y-538252D01*
Y-538418D01*
X93398Y-538502D01*
G01Y-536252D02*
X93271Y-536168D01*
Y-536002D01*
X93398Y-535918D01*
X93525Y-536002D01*
Y-536168D01*
X93398Y-536252D01*
G01X98181Y-540002D02*
X97548Y-539168D01*
X97231Y-538335D01*
Y-535002D01*
X97548Y-534168D01*
X98181Y-533335D01*
G01X103598D02*
X103091Y-533502D01*
X102711Y-533918D01*
X102458Y-534418D01*
X102268Y-535085D01*
X102205Y-535835D01*
X102268Y-536585D01*
X102458Y-537252D01*
X102711Y-537752D01*
X103091Y-538168D01*
X103598Y-538335D01*
X104105Y-538168D01*
X104485Y-537752D01*
X104738Y-537252D01*
X104928Y-536585D01*
X104991Y-535835D01*
X104928Y-535085D01*
X104738Y-534418D01*
X104485Y-533918D01*
X104105Y-533502D01*
X103598Y-533335D01*
G01X107305Y-537335D02*
X107685Y-537918D01*
X108191Y-538252D01*
X108761Y-538335D01*
X109268Y-538252D01*
X109775Y-537835D01*
X110091Y-537335D01*
X110155Y-536835D01*
X110028Y-536252D01*
X109585Y-535835D01*
X109141Y-535668D01*
X108571D01*
G01X109141D02*
X109521Y-535418D01*
X109838Y-535002D01*
X109965Y-534502D01*
X109838Y-534002D01*
X109521Y-533585D01*
X108951Y-533335D01*
X108381Y-533418D01*
X107811Y-533752D01*
G01X114115Y-540002D02*
X114748Y-539168D01*
X115065Y-538335D01*
Y-535002D01*
X114748Y-534168D01*
X114115Y-533335D01*
G01X117505Y-537335D02*
X117885Y-537918D01*
X118391Y-538252D01*
X118961Y-538335D01*
X119468Y-538252D01*
X119975Y-537835D01*
X120291Y-537335D01*
X120355Y-536835D01*
X120228Y-536252D01*
X119785Y-535835D01*
X119341Y-535668D01*
X118771D01*
G01X119341D02*
X119721Y-535418D01*
X120038Y-535002D01*
X120165Y-534502D01*
X120038Y-534002D01*
X119721Y-533585D01*
X119151Y-533335D01*
X118581Y-533418D01*
X118011Y-533752D01*
G01X122921Y-537752D02*
X123365Y-538168D01*
X123871Y-538335D01*
X124378Y-538168D01*
X124821Y-537668D01*
X125138Y-536918D01*
X125265Y-536168D01*
Y-535252D01*
X125138Y-534502D01*
X124821Y-533835D01*
X124441Y-533502D01*
X123998Y-533335D01*
X123491Y-533502D01*
X123111Y-533835D01*
X122858Y-534335D01*
X122731Y-535002D01*
X122858Y-535585D01*
X123175Y-536168D01*
X123555Y-536502D01*
X123998Y-536585D01*
X124505Y-536418D01*
X124885Y-536002D01*
X125265Y-535252D01*
G01X128971Y-538335D02*
X129098Y-537252D01*
X129288Y-536335D01*
X129541Y-535502D01*
X129858Y-534585D01*
X130365Y-533335D01*
X127831D01*
G01X133375Y-536668D02*
X135021D01*
G01X137905Y-537335D02*
X138285Y-537918D01*
X138791Y-538252D01*
X139361Y-538335D01*
X139868Y-538252D01*
X140375Y-537835D01*
X140691Y-537335D01*
X140755Y-536835D01*
X140628Y-536252D01*
X140185Y-535835D01*
X139741Y-535668D01*
X139171D01*
G01X139741D02*
X140121Y-535418D01*
X140438Y-535002D01*
X140565Y-534502D01*
X140438Y-534002D01*
X140121Y-533585D01*
X139551Y-533335D01*
X138981Y-533418D01*
X138411Y-533752D01*
G01X143195Y-536252D02*
X143638Y-535668D01*
X144018Y-535335D01*
X144525Y-535168D01*
X144968Y-535335D01*
X145285Y-535668D01*
X145538Y-536168D01*
X145601Y-536752D01*
X145538Y-537252D01*
X145285Y-537752D01*
X144905Y-538168D01*
X144461Y-538335D01*
X143955Y-538168D01*
X143511Y-537668D01*
X143258Y-536918D01*
X143195Y-536085D01*
X143321Y-535002D01*
X143511Y-534418D01*
X143828Y-533835D01*
X144271Y-533418D01*
X144715Y-533335D01*
X145158Y-533502D01*
X145475Y-533918D01*
G01X149498Y-538335D02*
Y-533335D01*
X148738Y-534335D01*
G01Y-538335D02*
X150258D01*
G01X155358D02*
Y-533335D01*
X153015Y-536918D01*
X156181D01*
G01X174398Y-468335D02*
Y-543335D01*
G01Y-518335D02*
X277398D01*
Y-493335D01*
G01X174398D02*
X277398D01*
G01Y-468335D02*
Y-543335D01*
G01X279398Y-468335D02*
Y-543335D01*
G01X284905Y-528335D02*
Y-523335D01*
X286171D01*
X286678Y-523585D01*
X287058Y-523918D01*
X287375Y-524418D01*
X287628Y-525002D01*
X287691Y-525835D01*
X287628Y-526668D01*
X287375Y-527252D01*
X287058Y-527752D01*
X286678Y-528085D01*
X286171Y-528335D01*
X284905D01*
G01X289815D02*
X291398Y-523335D01*
X292981Y-528335D01*
G01X292411Y-526585D02*
X290385D01*
G01X296498Y-523335D02*
Y-528335D01*
G01X295041Y-523335D02*
X297955D01*
G01X302865Y-528335D02*
X300331D01*
Y-523335D01*
X302865D01*
G01X301851Y-525752D02*
X300331D01*
G01X306698Y-528502D02*
X306571Y-528418D01*
Y-528252D01*
X306698Y-528168D01*
X306825Y-528252D01*
Y-528418D01*
X306698Y-528502D01*
G01Y-526252D02*
X306571Y-526168D01*
Y-526002D01*
X306698Y-525918D01*
X306825Y-526002D01*
Y-526168D01*
X306698Y-526252D01*
G01X279398Y-518335D02*
X479398D01*
G01X285031Y-503335D02*
Y-498335D01*
X286551D01*
X287058Y-498585D01*
X287438Y-499168D01*
X287565Y-499835D01*
X287438Y-500502D01*
X287121Y-501002D01*
X286551Y-501252D01*
X285031D01*
G01X290258Y-503502D02*
X292538Y-498335D01*
G01X295041Y-503335D02*
Y-498335D01*
X297955Y-503335D01*
Y-498335D01*
G01X301598Y-503502D02*
X301471Y-503418D01*
Y-503252D01*
X301598Y-503168D01*
X301725Y-503252D01*
Y-503418D01*
X301598Y-503502D01*
G01Y-501252D02*
X301471Y-501168D01*
Y-501002D01*
X301598Y-500918D01*
X301725Y-501002D01*
Y-501168D01*
X301598Y-501252D01*
G01X279398Y-493335D02*
X479398D01*
G01X285031Y-478335D02*
Y-473335D01*
X286551D01*
X287058Y-473585D01*
X287438Y-474168D01*
X287565Y-474835D01*
X287438Y-475502D01*
X287121Y-476002D01*
X286551Y-476252D01*
X285031D01*
G01X290131Y-478335D02*
Y-473335D01*
X291715D01*
X292221Y-473585D01*
X292538Y-473918D01*
X292665Y-474585D01*
X292538Y-475252D01*
X292158Y-475668D01*
X291715Y-475918D01*
X290131D01*
G01X291715D02*
X292665Y-478335D01*
G01X296498D02*
X295991Y-478252D01*
X295548Y-477918D01*
X295168Y-477418D01*
X294915Y-476835D01*
X294788Y-476168D01*
Y-475502D01*
X294915Y-474835D01*
X295168Y-474252D01*
X295548Y-473752D01*
X295991Y-473418D01*
X296498Y-473335D01*
X297005Y-473418D01*
X297448Y-473752D01*
X297828Y-474252D01*
X298081Y-474835D01*
X298208Y-475502D01*
Y-476168D01*
X298081Y-476835D01*
X297828Y-477418D01*
X297448Y-477918D01*
X297005Y-478252D01*
X296498Y-478335D01*
G01X300331Y-477335D02*
X300648Y-477835D01*
X301028Y-478168D01*
X301471Y-478335D01*
X301978Y-478168D01*
X302358Y-477835D01*
X302738Y-477335D01*
X302865Y-476668D01*
Y-473335D01*
G01X307965Y-478335D02*
X305431D01*
Y-473335D01*
X307965D01*
G01X306951Y-475752D02*
X305431D01*
G01X313191Y-473752D02*
X312811Y-473502D01*
X312368Y-473335D01*
X311861D01*
X311291Y-473585D01*
X310848Y-474002D01*
X310531Y-474502D01*
X310278Y-475335D01*
X310215Y-476085D01*
X310341Y-476835D01*
X310531Y-477335D01*
X310911Y-477835D01*
X311355Y-478168D01*
X311798Y-478335D01*
X312241D01*
X312685Y-478168D01*
X313065Y-477918D01*
X313381Y-477585D01*
G01X316898Y-473335D02*
Y-478335D01*
G01X315441Y-473335D02*
X318355D01*
G01X321998Y-478502D02*
X321871Y-478418D01*
Y-478252D01*
X321998Y-478168D01*
X322125Y-478252D01*
Y-478418D01*
X321998Y-478502D01*
G01Y-476252D02*
X321871Y-476168D01*
Y-476002D01*
X321998Y-475918D01*
X322125Y-476002D01*
Y-476168D01*
X321998Y-476252D01*
G01X394258Y-543563D02*
Y-518563D01*
G01X397031Y-520835D02*
Y-525835D01*
X399565D01*
G01X402638Y-520835D02*
X404158D01*
G01X403398D02*
Y-525835D01*
G01X402638D02*
X404158D01*
G01X409005Y-523168D02*
X409258Y-522918D01*
X409448Y-522502D01*
X409575Y-521918D01*
X409448Y-521418D01*
X409195Y-521085D01*
X408751Y-520835D01*
X407041D01*
Y-525835D01*
X409131D01*
X409575Y-525502D01*
X409828Y-525002D01*
X409955Y-524418D01*
X409828Y-523835D01*
X409448Y-523335D01*
X409005Y-523168D01*
X407041D01*
G01X413598Y-526002D02*
X413471Y-525918D01*
Y-525752D01*
X413598Y-525668D01*
X413725Y-525752D01*
Y-525918D01*
X413598Y-526002D01*
G01Y-523752D02*
X413471Y-523668D01*
Y-523502D01*
X413598Y-523418D01*
X413725Y-523502D01*
Y-523668D01*
X413598Y-523752D01*
G01X437258Y-518563D02*
Y-543563D01*
G01X437398Y-518335D02*
Y-543335D01*
G01X441298Y-520835D02*
Y-525835D01*
G01X439841Y-520835D02*
X442755D01*
G01X446398Y-525835D02*
X446018Y-525752D01*
X445638Y-525418D01*
X445385Y-524835D01*
X445258Y-524168D01*
X445385Y-523502D01*
X445638Y-522918D01*
X446018Y-522585D01*
X446398Y-522502D01*
X446778Y-522585D01*
X447158Y-522918D01*
X447411Y-523502D01*
X447475Y-524168D01*
X447411Y-524835D01*
X447158Y-525418D01*
X446778Y-525752D01*
X446398Y-525835D01*
G01X451498D02*
X451118Y-525752D01*
X450738Y-525418D01*
X450485Y-524835D01*
X450358Y-524168D01*
X450485Y-523502D01*
X450738Y-522918D01*
X451118Y-522585D01*
X451498Y-522502D01*
X451878Y-522585D01*
X452258Y-522918D01*
X452511Y-523502D01*
X452575Y-524168D01*
X452511Y-524835D01*
X452258Y-525418D01*
X451878Y-525752D01*
X451498Y-525835D01*
G01X456598D02*
Y-520835D01*
G01X461698Y-526002D02*
X461571Y-525918D01*
Y-525752D01*
X461698Y-525668D01*
X461825Y-525752D01*
Y-525918D01*
X461698Y-526002D01*
G01Y-523752D02*
X461571Y-523668D01*
Y-523502D01*
X461698Y-523418D01*
X461825Y-523502D01*
Y-523668D01*
X461698Y-523752D01*
G01X437398Y-493335D02*
Y-518335D01*
G01X440031Y-500835D02*
Y-495835D01*
X441615D01*
X442121Y-496085D01*
X442438Y-496418D01*
X442565Y-497085D01*
X442438Y-497752D01*
X442058Y-498168D01*
X441615Y-498418D01*
X440031D01*
G01X441615D02*
X442565Y-500835D01*
G01X447665D02*
X445131D01*
Y-495835D01*
X447665D01*
G01X446651Y-498252D02*
X445131D01*
G01X449915Y-495835D02*
X451498Y-500835D01*
X453081Y-495835D01*
G01X456598Y-501002D02*
X456471Y-500918D01*
Y-500752D01*
X456598Y-500668D01*
X456725Y-500752D01*
Y-500918D01*
X456598Y-501002D01*
G01Y-498752D02*
X456471Y-498668D01*
Y-498502D01*
X456598Y-498418D01*
X456725Y-498502D01*
Y-498668D01*
X456598Y-498752D01*
G01X445411Y-546502D02*
X445518Y-546377D01*
X445598Y-546168D01*
X445651Y-545877D01*
X445598Y-545627D01*
X445491Y-545460D01*
X445305Y-545335D01*
X444585D01*
Y-547835D01*
X445465D01*
X445651Y-547668D01*
X445758Y-547418D01*
X445811Y-547127D01*
X445758Y-546835D01*
X445598Y-546585D01*
X445411Y-546502D01*
X444585D01*
G01X447878Y-547835D02*
Y-546168D01*
G01Y-546460D02*
X447771Y-546293D01*
X447611Y-546210D01*
X447425Y-546168D01*
X447238Y-546252D01*
X447078Y-546418D01*
X446971Y-546668D01*
X446918Y-547002D01*
X446971Y-547335D01*
X447078Y-547585D01*
X447238Y-547752D01*
X447425Y-547835D01*
X447611Y-547793D01*
X447771Y-547668D01*
X447878Y-547502D01*
G01X449198Y-547543D02*
X449331Y-547710D01*
X449518Y-547835D01*
X449678D01*
X449838Y-547752D01*
X449945Y-547627D01*
X449998Y-547460D01*
X449971Y-547210D01*
X449865Y-547085D01*
X449385Y-546835D01*
X449278Y-546543D01*
X449331Y-546335D01*
X449438Y-546210D01*
X449598Y-546168D01*
X449758Y-546210D01*
X449918Y-546335D01*
G01X451398Y-546710D02*
X452251D01*
X452171Y-546418D01*
X452038Y-546252D01*
X451851Y-546168D01*
X451665Y-546210D01*
X451505Y-546335D01*
X451398Y-546627D01*
X451345Y-546877D01*
Y-547127D01*
X451398Y-547377D01*
X451531Y-547627D01*
X451691Y-547793D01*
X451878Y-547835D01*
X452065Y-547752D01*
X452251Y-547502D01*
G01X453518Y-547835D02*
Y-545335D01*
G01Y-546585D02*
X453651Y-546335D01*
X453811Y-546210D01*
X453971Y-546168D01*
X454211Y-546252D01*
X454371Y-546418D01*
X454478Y-546710D01*
Y-547043D01*
X454425Y-547377D01*
X454318Y-547627D01*
X454131Y-547793D01*
X453971Y-547835D01*
X453811Y-547793D01*
X453651Y-547668D01*
X453518Y-547460D01*
G01X456198Y-547835D02*
X456038Y-547793D01*
X455878Y-547627D01*
X455771Y-547335D01*
X455718Y-547002D01*
X455771Y-546668D01*
X455878Y-546377D01*
X456038Y-546210D01*
X456198Y-546168D01*
X456358Y-546210D01*
X456518Y-546377D01*
X456625Y-546668D01*
X456651Y-547002D01*
X456625Y-547335D01*
X456518Y-547627D01*
X456358Y-547793D01*
X456198Y-547835D01*
G01X458878D02*
Y-546168D01*
G01Y-546460D02*
X458771Y-546293D01*
X458611Y-546210D01*
X458425Y-546168D01*
X458238Y-546252D01*
X458078Y-546418D01*
X457971Y-546668D01*
X457918Y-547002D01*
X457971Y-547335D01*
X458078Y-547585D01*
X458238Y-547752D01*
X458425Y-547835D01*
X458611Y-547793D01*
X458771Y-547668D01*
X458878Y-547502D01*
G01X460225Y-547835D02*
Y-546168D01*
G01Y-546502D02*
X460358Y-546335D01*
X460491Y-546210D01*
X460678Y-546168D01*
X460811Y-546210D01*
X460971Y-546335D01*
G01X463278Y-545335D02*
Y-547835D01*
G01Y-547460D02*
X463171Y-547668D01*
X463011Y-547793D01*
X462825Y-547835D01*
X462611Y-547752D01*
X462451Y-547543D01*
X462345Y-547293D01*
X462318Y-547002D01*
X462345Y-546710D01*
X462451Y-546460D01*
X462611Y-546252D01*
X462825Y-546168D01*
X463011Y-546210D01*
X463145Y-546293D01*
X463278Y-546460D01*
G01X466665Y-547835D02*
Y-545335D01*
X467331D01*
X467545Y-545460D01*
X467678Y-545627D01*
X467731Y-545960D01*
X467678Y-546293D01*
X467518Y-546502D01*
X467331Y-546627D01*
X466665D01*
G01X467331D02*
X467731Y-547835D01*
G01X468998Y-546710D02*
X469851D01*
X469771Y-546418D01*
X469638Y-546252D01*
X469451Y-546168D01*
X469265Y-546210D01*
X469105Y-546335D01*
X468998Y-546627D01*
X468945Y-546877D01*
Y-547127D01*
X468998Y-547377D01*
X469131Y-547627D01*
X469291Y-547793D01*
X469478Y-547835D01*
X469665Y-547752D01*
X469851Y-547502D01*
G01X471118Y-546168D02*
X471598Y-547835D01*
X472078Y-546168D01*
G01X473798Y-547918D02*
X473745Y-547877D01*
Y-547793D01*
X473798Y-547752D01*
X473851Y-547793D01*
Y-547877D01*
X473798Y-547918D01*
G01X475545Y-547543D02*
X475731Y-547752D01*
X475945Y-547835D01*
X476158Y-547752D01*
X476345Y-547502D01*
X476478Y-547127D01*
X476531Y-546752D01*
Y-546293D01*
X476478Y-545918D01*
X476345Y-545585D01*
X476185Y-545418D01*
X475998Y-545335D01*
X475785Y-545418D01*
X475625Y-545585D01*
X475518Y-545835D01*
X475465Y-546168D01*
X475518Y-546460D01*
X475651Y-546752D01*
X475811Y-546918D01*
X475998Y-546960D01*
X476211Y-546877D01*
X476371Y-546668D01*
X476531Y-546293D01*
G01X478411Y-546502D02*
X478518Y-546377D01*
X478598Y-546168D01*
X478651Y-545877D01*
X478598Y-545627D01*
X478491Y-545460D01*
X478305Y-545335D01*
X477585D01*
Y-547835D01*
X478465D01*
X478651Y-547668D01*
X478758Y-547418D01*
X478811Y-547127D01*
X478758Y-546835D01*
X478598Y-546585D01*
X478411Y-546502D01*
X477585D01*
G01X-1490433Y-1677216D02*
Y3837819D01*
X4496476D01*
Y-1677216D01*
X-1490433D01*
G01X-7782Y-515685D02*
X-6215D01*
Y-517575D01*
X-6685Y-518205D01*
X-7234Y-518625D01*
X-8017Y-518835D01*
X-8800Y-518625D01*
X-9349Y-518205D01*
X-9819Y-517575D01*
X-10132Y-516840D01*
X-10289Y-516000D01*
Y-515265D01*
X-10132Y-514635D01*
X-9819Y-513900D01*
X-9349Y-513270D01*
X-8879Y-512850D01*
X-8252Y-512535D01*
X-7704D01*
X-7077Y-512745D01*
X-6607Y-513165D01*
G01X-3675Y-512535D02*
Y-517050D01*
X-3362Y-517995D01*
X-2735Y-518625D01*
X-1952Y-518835D01*
X-1169Y-518625D01*
X-542Y-517995D01*
X-229Y-517050D01*
Y-512535D01*
G01X3408D02*
X5288D01*
G01X4348D02*
Y-518835D01*
G01X3408D02*
X5288D01*
G01X9003Y-517995D02*
X9630Y-518520D01*
X10335Y-518835D01*
X10961D01*
X11588Y-518520D01*
X12058Y-517995D01*
X12293Y-517260D01*
X12136Y-516525D01*
X11745Y-515895D01*
X11040Y-515475D01*
X10100Y-515265D01*
X9551Y-514845D01*
X9316Y-514110D01*
X9473Y-513375D01*
X9865Y-512850D01*
X10413Y-512535D01*
X10961D01*
X11510Y-512745D01*
X11980Y-513270D01*
G01X15303Y-518835D02*
Y-512535D01*
G01X18593D02*
Y-518835D01*
G01Y-515685D02*
X15303D01*
G01X21290Y-518835D02*
X23248Y-512535D01*
X25206Y-518835D01*
G01X24501Y-516630D02*
X21995D01*
G01X27746Y-518835D02*
Y-512535D01*
X31350Y-518835D01*
Y-512535D01*
G01X40425Y-518835D02*
Y-512535D01*
X41991D01*
X42618Y-512850D01*
X43088Y-513270D01*
X43480Y-513900D01*
X43793Y-514635D01*
X43871Y-515685D01*
X43793Y-516735D01*
X43480Y-517470D01*
X43088Y-518100D01*
X42618Y-518520D01*
X41991Y-518835D01*
X40425D01*
G01X47508Y-512535D02*
X49388D01*
G01X48448D02*
Y-518835D01*
G01X47508D02*
X49388D01*
G01X53103Y-517995D02*
X53730Y-518520D01*
X54435Y-518835D01*
X55061D01*
X55688Y-518520D01*
X56158Y-517995D01*
X56393Y-517260D01*
X56236Y-516525D01*
X55845Y-515895D01*
X55140Y-515475D01*
X54200Y-515265D01*
X53651Y-514845D01*
X53416Y-514110D01*
X53573Y-513375D01*
X53965Y-512850D01*
X54513Y-512535D01*
X55061D01*
X55610Y-512745D01*
X56080Y-513270D01*
G01X61048Y-512535D02*
Y-518835D01*
G01X59246Y-512535D02*
X62850D01*
G01X67348Y-519045D02*
X67191Y-518940D01*
Y-518730D01*
X67348Y-518625D01*
X67505Y-518730D01*
Y-518940D01*
X67348Y-519045D01*
G01X73491Y-519990D02*
X73805Y-518625D01*
G01X79948Y-512535D02*
Y-518835D01*
G01X78146Y-512535D02*
X81750D01*
G01X84290Y-518835D02*
X86248Y-512535D01*
X88206Y-518835D01*
G01X87501Y-516630D02*
X84995D01*
G01X92548Y-518835D02*
X91921Y-518730D01*
X91373Y-518310D01*
X90903Y-517680D01*
X90590Y-516945D01*
X90433Y-516105D01*
Y-515265D01*
X90590Y-514425D01*
X90903Y-513690D01*
X91373Y-513060D01*
X91921Y-512640D01*
X92548Y-512535D01*
X93175Y-512640D01*
X93723Y-513060D01*
X94193Y-513690D01*
X94506Y-514425D01*
X94663Y-515265D01*
Y-516105D01*
X94506Y-516945D01*
X94193Y-517680D01*
X93723Y-518310D01*
X93175Y-518730D01*
X92548Y-518835D01*
G01X98848D02*
Y-516000D01*
X97281Y-512535D01*
G01X100415D02*
X98848Y-516000D01*
G01X103425Y-512535D02*
Y-517050D01*
X103738Y-517995D01*
X104365Y-518625D01*
X105148Y-518835D01*
X105931Y-518625D01*
X106558Y-517995D01*
X106871Y-517050D01*
Y-512535D01*
G01X109490Y-518835D02*
X111448Y-512535D01*
X113406Y-518835D01*
G01X112701Y-516630D02*
X110195D01*
G01X115946Y-518835D02*
Y-512535D01*
X119550Y-518835D01*
Y-512535D01*
G01X-6529Y-523060D02*
X-6999Y-522745D01*
X-7547Y-522535D01*
X-8174D01*
X-8879Y-522850D01*
X-9427Y-523375D01*
X-9819Y-524005D01*
X-10132Y-525055D01*
X-10210Y-526000D01*
X-10054Y-526945D01*
X-9819Y-527575D01*
X-9349Y-528205D01*
X-8800Y-528625D01*
X-8252Y-528835D01*
X-7704D01*
X-7155Y-528625D01*
X-6685Y-528310D01*
X-6294Y-527890D01*
G01X-2892Y-522535D02*
X-1012D01*
G01X-1952D02*
Y-528835D01*
G01X-2892D02*
X-1012D01*
G01X4348Y-522535D02*
Y-528835D01*
G01X2546Y-522535D02*
X6150D01*
G01X10648Y-528835D02*
Y-526000D01*
X9081Y-522535D01*
G01X12215D02*
X10648Y-526000D01*
G01X21525Y-527575D02*
X21995Y-528310D01*
X22621Y-528730D01*
X23326Y-528835D01*
X23953Y-528730D01*
X24580Y-528205D01*
X24971Y-527575D01*
X25050Y-526945D01*
X24893Y-526210D01*
X24345Y-525685D01*
X23796Y-525475D01*
X23091D01*
G01X23796D02*
X24266Y-525160D01*
X24658Y-524635D01*
X24815Y-524005D01*
X24658Y-523375D01*
X24266Y-522850D01*
X23561Y-522535D01*
X22856Y-522640D01*
X22151Y-523060D01*
G01X27825Y-527575D02*
X28295Y-528310D01*
X28921Y-528730D01*
X29626Y-528835D01*
X30253Y-528730D01*
X30880Y-528205D01*
X31271Y-527575D01*
X31350Y-526945D01*
X31193Y-526210D01*
X30645Y-525685D01*
X30096Y-525475D01*
X29391D01*
G01X30096D02*
X30566Y-525160D01*
X30958Y-524635D01*
X31115Y-524005D01*
X30958Y-523375D01*
X30566Y-522850D01*
X29861Y-522535D01*
X29156Y-522640D01*
X28451Y-523060D01*
G01X34125Y-527575D02*
X34595Y-528310D01*
X35221Y-528730D01*
X35926Y-528835D01*
X36553Y-528730D01*
X37180Y-528205D01*
X37571Y-527575D01*
X37650Y-526945D01*
X37493Y-526210D01*
X36945Y-525685D01*
X36396Y-525475D01*
X35691D01*
G01X36396D02*
X36866Y-525160D01*
X37258Y-524635D01*
X37415Y-524005D01*
X37258Y-523375D01*
X36866Y-522850D01*
X36161Y-522535D01*
X35456Y-522640D01*
X34751Y-523060D01*
G01X41991Y-528835D02*
X42148Y-527470D01*
X42383Y-526315D01*
X42696Y-525265D01*
X43088Y-524110D01*
X43715Y-522535D01*
X40581D01*
G01X48291Y-528835D02*
X48448Y-527470D01*
X48683Y-526315D01*
X48996Y-525265D01*
X49388Y-524110D01*
X50015Y-522535D01*
X46881D01*
G01X54591Y-529990D02*
X54905Y-528625D01*
G01X61048Y-522535D02*
Y-528835D01*
G01X59246Y-522535D02*
X62850D01*
G01X65390Y-528835D02*
X67348Y-522535D01*
X69306Y-528835D01*
G01X68601Y-526630D02*
X66095D01*
G01X72708Y-522535D02*
X74588D01*
G01X73648D02*
Y-528835D01*
G01X72708D02*
X74588D01*
G01X77598Y-522535D02*
X78695Y-528835D01*
X79948Y-522535D01*
X81201Y-528835D01*
X82298Y-522535D01*
G01X84290Y-528835D02*
X86248Y-522535D01*
X88206Y-528835D01*
G01X87501Y-526630D02*
X84995D01*
G01X90746Y-528835D02*
Y-522535D01*
X94350Y-528835D01*
Y-522535D01*
G01X104756Y-530935D02*
X103973Y-529885D01*
X103581Y-528835D01*
Y-524635D01*
X103973Y-523585D01*
X104756Y-522535D01*
G01X116181Y-528835D02*
Y-522535D01*
X118140D01*
X118766Y-522850D01*
X119158Y-523270D01*
X119315Y-524110D01*
X119158Y-524950D01*
X118688Y-525475D01*
X118140Y-525790D01*
X116181D01*
G01X118140D02*
X119315Y-528835D01*
G01X124048Y-529045D02*
X123891Y-528940D01*
Y-528730D01*
X124048Y-528625D01*
X124205Y-528730D01*
Y-528940D01*
X124048Y-529045D01*
G01X130348Y-528835D02*
X129721Y-528730D01*
X129173Y-528310D01*
X128703Y-527680D01*
X128390Y-526945D01*
X128233Y-526105D01*
Y-525265D01*
X128390Y-524425D01*
X128703Y-523690D01*
X129173Y-523060D01*
X129721Y-522640D01*
X130348Y-522535D01*
X130975Y-522640D01*
X131523Y-523060D01*
X131993Y-523690D01*
X132306Y-524425D01*
X132463Y-525265D01*
Y-526105D01*
X132306Y-526945D01*
X131993Y-527680D01*
X131523Y-528310D01*
X130975Y-528730D01*
X130348Y-528835D01*
G01X136648Y-529045D02*
X136491Y-528940D01*
Y-528730D01*
X136648Y-528625D01*
X136805Y-528730D01*
Y-528940D01*
X136648Y-529045D01*
G01X144671Y-523060D02*
X144201Y-522745D01*
X143653Y-522535D01*
X143026D01*
X142321Y-522850D01*
X141773Y-523375D01*
X141381Y-524005D01*
X141068Y-525055D01*
X140990Y-526000D01*
X141146Y-526945D01*
X141381Y-527575D01*
X141851Y-528205D01*
X142400Y-528625D01*
X142948Y-528835D01*
X143496D01*
X144045Y-528625D01*
X144515Y-528310D01*
X144906Y-527890D01*
G01X149248Y-529045D02*
X149091Y-528940D01*
Y-528730D01*
X149248Y-528625D01*
X149405Y-528730D01*
Y-528940D01*
X149248Y-529045D01*
G01X155940Y-530935D02*
X156723Y-529885D01*
X157115Y-528835D01*
Y-524635D01*
X156723Y-523585D01*
X155940Y-522535D01*
G01X-10054Y-508835D02*
Y-502535D01*
X-6450Y-508835D01*
Y-502535D01*
G01X-1952Y-508835D02*
X-2579Y-508730D01*
X-3127Y-508310D01*
X-3597Y-507680D01*
X-3910Y-506945D01*
X-4067Y-506105D01*
Y-505265D01*
X-3910Y-504425D01*
X-3597Y-503690D01*
X-3127Y-503060D01*
X-2579Y-502640D01*
X-1952Y-502535D01*
X-1325Y-502640D01*
X-777Y-503060D01*
X-307Y-503690D01*
X6Y-504425D01*
X163Y-505265D01*
Y-506105D01*
X6Y-506945D01*
X-307Y-507680D01*
X-777Y-508310D01*
X-1325Y-508730D01*
X-1952Y-508835D01*
G01X4348Y-509045D02*
X4191Y-508940D01*
Y-508730D01*
X4348Y-508625D01*
X4505Y-508730D01*
Y-508940D01*
X4348Y-509045D01*
G01X9160Y-503585D02*
X9630Y-502955D01*
X10178Y-502640D01*
X10805Y-502535D01*
X11588Y-502745D01*
X12136Y-503270D01*
X12293Y-503900D01*
X12215Y-504530D01*
X11901Y-505055D01*
X10335Y-506105D01*
X9630Y-506840D01*
X9160Y-507890D01*
X9003Y-508835D01*
X12293D01*
G01X16948D02*
Y-502535D01*
X16008Y-503795D01*
G01Y-508835D02*
X17888D01*
G01X23248D02*
Y-502535D01*
X22308Y-503795D01*
G01Y-508835D02*
X24188D01*
G01X29391Y-509990D02*
X29705Y-508625D01*
G01X33498Y-502535D02*
X34595Y-508835D01*
X35848Y-502535D01*
X37101Y-508835D01*
X38198Y-502535D01*
G01X43715Y-508835D02*
X40581D01*
Y-502535D01*
X43715D01*
G01X42461Y-505580D02*
X40581D01*
G01X46646Y-508835D02*
Y-502535D01*
X50250Y-508835D01*
Y-502535D01*
G01X53103Y-508835D02*
Y-502535D01*
G01X56393D02*
Y-508835D01*
G01Y-505685D02*
X53103D01*
G01X59325Y-502535D02*
Y-507050D01*
X59638Y-507995D01*
X60265Y-508625D01*
X61048Y-508835D01*
X61831Y-508625D01*
X62458Y-507995D01*
X62771Y-507050D01*
Y-502535D01*
G01X65390Y-508835D02*
X67348Y-502535D01*
X69306Y-508835D01*
G01X68601Y-506630D02*
X66095D01*
G01X78460Y-503585D02*
X78930Y-502955D01*
X79478Y-502640D01*
X80105Y-502535D01*
X80888Y-502745D01*
X81436Y-503270D01*
X81593Y-503900D01*
X81515Y-504530D01*
X81201Y-505055D01*
X79635Y-506105D01*
X78930Y-506840D01*
X78460Y-507890D01*
X78303Y-508835D01*
X81593D01*
G01X84446D02*
Y-502535D01*
X88050Y-508835D01*
Y-502535D01*
G01X90825Y-508835D02*
Y-502535D01*
X92391D01*
X93018Y-502850D01*
X93488Y-503270D01*
X93880Y-503900D01*
X94193Y-504635D01*
X94271Y-505685D01*
X94193Y-506735D01*
X93880Y-507470D01*
X93488Y-508100D01*
X93018Y-508520D01*
X92391Y-508835D01*
X90825D01*
G01X103581D02*
Y-502535D01*
X105540D01*
X106166Y-502850D01*
X106558Y-503270D01*
X106715Y-504110D01*
X106558Y-504950D01*
X106088Y-505475D01*
X105540Y-505790D01*
X103581D01*
G01X105540D02*
X106715Y-508835D01*
G01X109725D02*
Y-502535D01*
X111291D01*
X111918Y-502850D01*
X112388Y-503270D01*
X112780Y-503900D01*
X113093Y-504635D01*
X113171Y-505685D01*
X113093Y-506735D01*
X112780Y-507470D01*
X112388Y-508100D01*
X111918Y-508520D01*
X111291Y-508835D01*
X109725D01*
G01X117748Y-509045D02*
X117591Y-508940D01*
Y-508730D01*
X117748Y-508625D01*
X117905Y-508730D01*
Y-508940D01*
X117748Y-509045D01*
G01X14048Y-498135D02*
X11528Y-497718D01*
X9323Y-496052D01*
X7433Y-493552D01*
X6173Y-490635D01*
X5543Y-487302D01*
Y-483968D01*
X6173Y-480635D01*
X7433Y-477718D01*
X9323Y-475219D01*
X11528Y-473552D01*
X14048Y-473135D01*
X16568Y-473552D01*
X18773Y-475219D01*
X20663Y-477718D01*
X21923Y-480635D01*
X22553Y-483968D01*
Y-487302D01*
X21923Y-490635D01*
X20663Y-493552D01*
X18773Y-496052D01*
X16568Y-497718D01*
X14048Y-498135D01*
G01X16568Y-491468D02*
X20348Y-498135D01*
G01X33893Y-481469D02*
Y-493135D01*
X35153Y-496052D01*
X37043Y-497718D01*
X39248Y-498135D01*
X41453Y-497718D01*
X43343Y-496052D01*
X44603Y-493135D01*
G01Y-498135D02*
Y-481469D01*
G01X70118Y-498135D02*
Y-481469D01*
G01Y-484385D02*
X68858Y-482719D01*
X66968Y-481885D01*
X64763Y-481469D01*
X62558Y-482302D01*
X60668Y-483968D01*
X59408Y-486469D01*
X58778Y-489802D01*
X59408Y-493135D01*
X60668Y-495636D01*
X62558Y-497302D01*
X64763Y-498135D01*
X66968Y-497718D01*
X68858Y-496469D01*
X70118Y-494802D01*
G01X84293Y-498135D02*
Y-481469D01*
G01Y-485635D02*
X85553Y-483552D01*
X87443Y-481885D01*
X89963Y-481469D01*
X92168Y-481885D01*
X94058Y-483552D01*
X95003Y-486469D01*
Y-498135D01*
G01X114848Y-473135D02*
Y-498135D01*
G01X110438Y-481469D02*
X119258D01*
G01X145718Y-498135D02*
Y-481469D01*
G01Y-484385D02*
X144458Y-482719D01*
X142568Y-481885D01*
X140363Y-481469D01*
X138158Y-482302D01*
X136268Y-483968D01*
X135008Y-486469D01*
X134378Y-489802D01*
X135008Y-493135D01*
X136268Y-495636D01*
X138158Y-497302D01*
X140363Y-498135D01*
X142568Y-497718D01*
X144458Y-496469D01*
X145718Y-494802D01*
G01X185398Y-477835D02*
Y-485835D01*
X189398D01*
G01X197198D02*
Y-480502D01*
G01Y-481435D02*
X196798Y-480902D01*
X196198Y-480635D01*
X195498Y-480502D01*
X194798Y-480768D01*
X194198Y-481302D01*
X193798Y-482102D01*
X193598Y-483168D01*
X193798Y-484235D01*
X194198Y-485035D01*
X194798Y-485568D01*
X195498Y-485835D01*
X196198Y-485702D01*
X196798Y-485302D01*
X197198Y-484769D01*
G01X201298Y-488235D02*
X201898Y-488502D01*
X202698Y-488235D01*
X203198Y-487702D01*
X203598Y-487035D01*
X204198Y-484902D01*
X205498Y-480502D01*
G01X202298D02*
X204198Y-484902D01*
G01X209898Y-482235D02*
X213098D01*
X212798Y-481302D01*
X212298Y-480768D01*
X211598Y-480502D01*
X210898Y-480635D01*
X210298Y-481035D01*
X209898Y-481968D01*
X209698Y-482769D01*
Y-483568D01*
X209898Y-484368D01*
X210398Y-485168D01*
X210998Y-485702D01*
X211698Y-485835D01*
X212398Y-485568D01*
X213098Y-484769D01*
G01X217998Y-485835D02*
Y-480502D01*
G01Y-481568D02*
X218498Y-481035D01*
X218998Y-480635D01*
X219698Y-480502D01*
X220198Y-480635D01*
X220798Y-481035D01*
G01X211398Y-535835D02*
Y-532235D01*
X209398Y-527835D01*
G01X213398D02*
X211398Y-532235D01*
G01X217698Y-530502D02*
Y-534235D01*
X218098Y-535168D01*
X218698Y-535702D01*
X219398Y-535835D01*
X220098Y-535702D01*
X220698Y-535168D01*
X221098Y-534235D01*
G01Y-535835D02*
Y-530502D01*
G01X225698Y-535835D02*
Y-530502D01*
G01Y-531835D02*
X226098Y-531168D01*
X226698Y-530635D01*
X227498Y-530502D01*
X228198Y-530635D01*
X228798Y-531168D01*
X229098Y-532102D01*
Y-535835D01*
G01X237198D02*
Y-530502D01*
G01Y-531435D02*
X236798Y-530902D01*
X236198Y-530635D01*
X235498Y-530502D01*
X234798Y-530768D01*
X234198Y-531302D01*
X233798Y-532102D01*
X233598Y-533168D01*
X233798Y-534235D01*
X234198Y-535035D01*
X234798Y-535568D01*
X235498Y-535835D01*
X236198Y-535702D01*
X236798Y-535302D01*
X237198Y-534769D01*
G01X198798Y-510835D02*
Y-502835D01*
X201398Y-509502D01*
X203998Y-502835D01*
Y-510835D01*
G01X206898D02*
X209398Y-502835D01*
X211898Y-510835D01*
G01X210998Y-508035D02*
X207798D01*
G01X215298Y-509769D02*
X216098Y-510435D01*
X216998Y-510835D01*
X217798D01*
X218598Y-510435D01*
X219198Y-509769D01*
X219498Y-508835D01*
X219298Y-507902D01*
X218798Y-507102D01*
X217898Y-506568D01*
X216698Y-506302D01*
X215998Y-505768D01*
X215698Y-504835D01*
X215898Y-503902D01*
X216398Y-503235D01*
X217098Y-502835D01*
X217798D01*
X218498Y-503102D01*
X219098Y-503768D01*
G01X223198Y-510835D02*
Y-502835D01*
G01X226998D02*
X223198Y-507769D01*
G01X227598Y-510835D02*
X224898Y-505502D01*
G01X232098Y-508168D02*
X234698D01*
G01X241398Y-502835D02*
Y-510835D01*
G01X239098Y-502835D02*
X243698D01*
G01X249398Y-510835D02*
X248598Y-510702D01*
X247898Y-510168D01*
X247298Y-509368D01*
X246898Y-508435D01*
X246698Y-507368D01*
Y-506302D01*
X246898Y-505235D01*
X247298Y-504302D01*
X247898Y-503502D01*
X248598Y-502968D01*
X249398Y-502835D01*
X250198Y-502968D01*
X250898Y-503502D01*
X251498Y-504302D01*
X251898Y-505235D01*
X252098Y-506302D01*
Y-507368D01*
X251898Y-508435D01*
X251498Y-509368D01*
X250898Y-510168D01*
X250198Y-510702D01*
X249398Y-510835D01*
G01X255398D02*
Y-502835D01*
X257798D01*
X258598Y-503235D01*
X259198Y-504168D01*
X259398Y-505235D01*
X259198Y-506302D01*
X258698Y-507102D01*
X257798Y-507502D01*
X255398D01*
G01X311998Y-529168D02*
X312598Y-528368D01*
X313298Y-527968D01*
X314098Y-527835D01*
X315098Y-528102D01*
X315798Y-528768D01*
X315998Y-529568D01*
X315898Y-530369D01*
X315498Y-531035D01*
X313498Y-532368D01*
X312598Y-533302D01*
X311998Y-534635D01*
X311798Y-535835D01*
X315998D01*
G01X321898Y-527835D02*
X321098Y-528102D01*
X320498Y-528768D01*
X320098Y-529568D01*
X319798Y-530635D01*
X319698Y-531835D01*
X319798Y-533035D01*
X320098Y-534102D01*
X320498Y-534902D01*
X321098Y-535568D01*
X321898Y-535835D01*
X322698Y-535568D01*
X323298Y-534902D01*
X323698Y-534102D01*
X323998Y-533035D01*
X324098Y-531835D01*
X323998Y-530635D01*
X323698Y-529568D01*
X323298Y-528768D01*
X322698Y-528102D01*
X321898Y-527835D01*
G01X327998Y-529168D02*
X328598Y-528368D01*
X329298Y-527968D01*
X330098Y-527835D01*
X331098Y-528102D01*
X331798Y-528768D01*
X331998Y-529568D01*
X331898Y-530369D01*
X331498Y-531035D01*
X329498Y-532368D01*
X328598Y-533302D01*
X327998Y-534635D01*
X327798Y-535835D01*
X331998D01*
G01X335698Y-534235D02*
X336298Y-535168D01*
X337098Y-535702D01*
X337998Y-535835D01*
X338798Y-535702D01*
X339598Y-535035D01*
X340098Y-534235D01*
X340198Y-533435D01*
X339998Y-532502D01*
X339298Y-531835D01*
X338598Y-531568D01*
X337698D01*
G01X338598D02*
X339198Y-531168D01*
X339698Y-530502D01*
X339898Y-529702D01*
X339698Y-528902D01*
X339198Y-528235D01*
X338298Y-527835D01*
X337398Y-527968D01*
X336498Y-528502D01*
G01X344098Y-536102D02*
X347698Y-527835D01*
G01X353898D02*
X353098Y-528102D01*
X352498Y-528768D01*
X352098Y-529568D01*
X351798Y-530635D01*
X351698Y-531835D01*
X351798Y-533035D01*
X352098Y-534102D01*
X352498Y-534902D01*
X353098Y-535568D01*
X353898Y-535835D01*
X354698Y-535568D01*
X355298Y-534902D01*
X355698Y-534102D01*
X355998Y-533035D01*
X356098Y-531835D01*
X355998Y-530635D01*
X355698Y-529568D01*
X355298Y-528768D01*
X354698Y-528102D01*
X353898Y-527835D01*
G01X361898Y-535835D02*
Y-527835D01*
X360698Y-529435D01*
G01Y-535835D02*
X363098D01*
G01X368098Y-536102D02*
X371698Y-527835D01*
G01X377898D02*
X377098Y-528102D01*
X376498Y-528768D01*
X376098Y-529568D01*
X375798Y-530635D01*
X375698Y-531835D01*
X375798Y-533035D01*
X376098Y-534102D01*
X376498Y-534902D01*
X377098Y-535568D01*
X377898Y-535835D01*
X378698Y-535568D01*
X379298Y-534902D01*
X379698Y-534102D01*
X379998Y-533035D01*
X380098Y-531835D01*
X379998Y-530635D01*
X379698Y-529568D01*
X379298Y-528768D01*
X378698Y-528102D01*
X377898Y-527835D01*
G01X384198Y-534902D02*
X384898Y-535568D01*
X385698Y-535835D01*
X386498Y-535568D01*
X387198Y-534769D01*
X387698Y-533568D01*
X387898Y-532368D01*
Y-530902D01*
X387698Y-529702D01*
X387198Y-528635D01*
X386598Y-528102D01*
X385898Y-527835D01*
X385098Y-528102D01*
X384498Y-528635D01*
X384098Y-529435D01*
X383898Y-530502D01*
X384098Y-531435D01*
X384598Y-532368D01*
X385198Y-532902D01*
X385898Y-533035D01*
X386698Y-532769D01*
X387298Y-532102D01*
X387898Y-530902D01*
G01X311698Y-510835D02*
Y-502835D01*
X313698D01*
X314498Y-503235D01*
X315098Y-503768D01*
X315598Y-504568D01*
X315998Y-505502D01*
X316098Y-506835D01*
X315998Y-508168D01*
X315598Y-509102D01*
X315098Y-509902D01*
X314498Y-510435D01*
X313698Y-510835D01*
X311698D01*
G01X319398D02*
X321898Y-502835D01*
X324398Y-510835D01*
G01X323498Y-508035D02*
X320298D01*
G01X329898Y-502835D02*
X329098Y-503102D01*
X328498Y-503768D01*
X328098Y-504568D01*
X327798Y-505635D01*
X327698Y-506835D01*
X327798Y-508035D01*
X328098Y-509102D01*
X328498Y-509902D01*
X329098Y-510568D01*
X329898Y-510835D01*
X330698Y-510568D01*
X331298Y-509902D01*
X331698Y-509102D01*
X331998Y-508035D01*
X332098Y-506835D01*
X331998Y-505635D01*
X331698Y-504568D01*
X331298Y-503768D01*
X330698Y-503102D01*
X329898Y-502835D01*
G01X335998Y-510835D02*
Y-502835D01*
X339798D01*
G01X338398Y-506702D02*
X335998D01*
G01X345898Y-502835D02*
X345098Y-503102D01*
X344498Y-503768D01*
X344098Y-504568D01*
X343798Y-505635D01*
X343698Y-506835D01*
X343798Y-508035D01*
X344098Y-509102D01*
X344498Y-509902D01*
X345098Y-510568D01*
X345898Y-510835D01*
X346698Y-510568D01*
X347298Y-509902D01*
X347698Y-509102D01*
X347998Y-508035D01*
X348098Y-506835D01*
X347998Y-505635D01*
X347698Y-504568D01*
X347298Y-503768D01*
X346698Y-503102D01*
X345898Y-502835D01*
G01X353898D02*
Y-510835D01*
G01X351598Y-502835D02*
X356198D01*
G01X363898Y-510835D02*
X359898D01*
Y-502835D01*
X363898D01*
G01X362298Y-506702D02*
X359898D01*
G01X370698Y-506568D02*
X371098Y-506168D01*
X371398Y-505502D01*
X371598Y-504568D01*
X371398Y-503768D01*
X370998Y-503235D01*
X370298Y-502835D01*
X367598D01*
Y-510835D01*
X370898D01*
X371598Y-510302D01*
X371998Y-509502D01*
X372198Y-508568D01*
X371998Y-507635D01*
X371398Y-506835D01*
X370698Y-506568D01*
X367598D01*
G01X376698Y-502835D02*
X379098D01*
G01X377898D02*
Y-510835D01*
G01X376698D02*
X379098D01*
G01X383998D02*
Y-502835D01*
X387798D01*
G01X386398Y-506702D02*
X383998D01*
G01X393898Y-502835D02*
X393098Y-503102D01*
X392498Y-503768D01*
X392098Y-504568D01*
X391798Y-505635D01*
X391698Y-506835D01*
X391798Y-508035D01*
X392098Y-509102D01*
X392498Y-509902D01*
X393098Y-510568D01*
X393898Y-510835D01*
X394698Y-510568D01*
X395298Y-509902D01*
X395698Y-509102D01*
X395998Y-508035D01*
X396098Y-506835D01*
X395998Y-505635D01*
X395698Y-504568D01*
X395298Y-503768D01*
X394698Y-503102D01*
X393898Y-502835D01*
G01X329498Y-485835D02*
Y-477835D01*
X333298D01*
G01X331898Y-481702D02*
X329498D01*
G01X339398Y-477835D02*
X338598Y-478102D01*
X337998Y-478768D01*
X337598Y-479568D01*
X337298Y-480635D01*
X337198Y-481835D01*
X337298Y-483035D01*
X337598Y-484102D01*
X337998Y-484902D01*
X338598Y-485568D01*
X339398Y-485835D01*
X340198Y-485568D01*
X340798Y-484902D01*
X341198Y-484102D01*
X341498Y-483035D01*
X341598Y-481835D01*
X341498Y-480635D01*
X341198Y-479568D01*
X340798Y-478768D01*
X340198Y-478102D01*
X339398Y-477835D01*
G01X347398D02*
Y-485835D01*
G01X345098Y-477835D02*
X349698D01*
G01X352398Y-488502D02*
X358398D01*
G01X361898Y-482235D02*
X365098D01*
X364798Y-481302D01*
X364298Y-480768D01*
X363598Y-480502D01*
X362898Y-480635D01*
X362298Y-481035D01*
X361898Y-481968D01*
X361698Y-482769D01*
Y-483568D01*
X361898Y-484368D01*
X362398Y-485168D01*
X362998Y-485702D01*
X363698Y-485835D01*
X364398Y-485568D01*
X365098Y-484769D01*
G01X369898Y-480502D02*
X372898Y-485835D01*
G01Y-480502D02*
X369898Y-485835D01*
G01X377598Y-488502D02*
Y-480502D01*
G01Y-481702D02*
X378098Y-481035D01*
X378598Y-480635D01*
X379398Y-480502D01*
X380098Y-480635D01*
X380798Y-481302D01*
X381098Y-482235D01*
X381198Y-483168D01*
X381098Y-484102D01*
X380798Y-485035D01*
X380198Y-485568D01*
X379398Y-485835D01*
X378698Y-485702D01*
X377998Y-485302D01*
X377598Y-484769D01*
G01X389198Y-485835D02*
Y-480502D01*
G01Y-481435D02*
X388798Y-480902D01*
X388198Y-480635D01*
X387498Y-480502D01*
X386798Y-480768D01*
X386198Y-481302D01*
X385798Y-482102D01*
X385598Y-483168D01*
X385798Y-484235D01*
X386198Y-485035D01*
X386798Y-485568D01*
X387498Y-485835D01*
X388198Y-485702D01*
X388798Y-485302D01*
X389198Y-484769D01*
G01X393698Y-485835D02*
Y-480502D01*
G01Y-481835D02*
X394098Y-481168D01*
X394698Y-480635D01*
X395498Y-480502D01*
X396198Y-480635D01*
X396798Y-481168D01*
X397098Y-482102D01*
Y-485835D01*
G01X405198Y-477835D02*
Y-485835D01*
G01Y-484635D02*
X404798Y-485302D01*
X404198Y-485702D01*
X403498Y-485835D01*
X402698Y-485568D01*
X402098Y-484902D01*
X401698Y-484102D01*
X401598Y-483168D01*
X401698Y-482235D01*
X402098Y-481435D01*
X402698Y-480768D01*
X403498Y-480502D01*
X404198Y-480635D01*
X404698Y-480902D01*
X405198Y-481435D01*
G01X409898Y-482235D02*
X413098D01*
X412798Y-481302D01*
X412298Y-480768D01*
X411598Y-480502D01*
X410898Y-480635D01*
X410298Y-481035D01*
X409898Y-481968D01*
X409698Y-482769D01*
Y-483568D01*
X409898Y-484368D01*
X410398Y-485168D01*
X410998Y-485702D01*
X411698Y-485835D01*
X412398Y-485568D01*
X413098Y-484769D01*
G01X417998Y-485835D02*
Y-480502D01*
G01Y-481568D02*
X418498Y-481035D01*
X418998Y-480635D01*
X419698Y-480502D01*
X420198Y-480635D01*
X420798Y-481035D01*
G01X424398Y-488502D02*
X430398D01*
G01X433598Y-485835D02*
Y-477835D01*
G01Y-481835D02*
X434098Y-481035D01*
X434698Y-480635D01*
X435298Y-480502D01*
X436198Y-480768D01*
X436798Y-481302D01*
X437198Y-482235D01*
Y-483302D01*
X436998Y-484368D01*
X436598Y-485168D01*
X435898Y-485702D01*
X435298Y-485835D01*
X434698Y-485702D01*
X434098Y-485302D01*
X433598Y-484635D01*
G01X445198Y-477835D02*
Y-485835D01*
G01Y-484635D02*
X444798Y-485302D01*
X444198Y-485702D01*
X443498Y-485835D01*
X442698Y-485568D01*
X442098Y-484902D01*
X441698Y-484102D01*
X441598Y-483168D01*
X441698Y-482235D01*
X442098Y-481435D01*
X442698Y-480768D01*
X443498Y-480502D01*
X444198Y-480635D01*
X444698Y-480902D01*
X445198Y-481435D01*
G01X400398Y-538835D02*
Y-530835D01*
X399198Y-532435D01*
G01Y-538835D02*
X401598D01*
G01X406498Y-535502D02*
X407198Y-534568D01*
X407798Y-534035D01*
X408598Y-533768D01*
X409298Y-534035D01*
X409798Y-534568D01*
X410198Y-535368D01*
X410298Y-536302D01*
X410198Y-537102D01*
X409798Y-537902D01*
X409198Y-538568D01*
X408498Y-538835D01*
X407698Y-538568D01*
X406998Y-537769D01*
X406598Y-536568D01*
X406498Y-535235D01*
X406698Y-533502D01*
X406998Y-532568D01*
X407498Y-531635D01*
X408198Y-530968D01*
X408898Y-530835D01*
X409598Y-531102D01*
X410098Y-531768D01*
G01X416398Y-539102D02*
X416198Y-538968D01*
Y-538702D01*
X416398Y-538568D01*
X416598Y-538702D01*
Y-538968D01*
X416398Y-539102D01*
G01X422498Y-535502D02*
X423198Y-534568D01*
X423798Y-534035D01*
X424598Y-533768D01*
X425298Y-534035D01*
X425798Y-534568D01*
X426198Y-535368D01*
X426298Y-536302D01*
X426198Y-537102D01*
X425798Y-537902D01*
X425198Y-538568D01*
X424498Y-538835D01*
X423698Y-538568D01*
X422998Y-537769D01*
X422598Y-536568D01*
X422498Y-535235D01*
X422698Y-533502D01*
X422998Y-532568D01*
X423498Y-531635D01*
X424198Y-530968D01*
X424898Y-530835D01*
X425598Y-531102D01*
X426098Y-531768D01*
G01X445398Y-538835D02*
Y-530835D01*
X444198Y-532435D01*
G01Y-538835D02*
X446598D01*
G01X453198D02*
X453398Y-537102D01*
X453698Y-535635D01*
X454098Y-534302D01*
X454598Y-532835D01*
X455398Y-530835D01*
X451398D01*
G01X461398Y-539102D02*
X461198Y-538968D01*
Y-538702D01*
X461398Y-538568D01*
X461598Y-538702D01*
Y-538968D01*
X461398Y-539102D01*
G01X467498Y-532168D02*
X468098Y-531368D01*
X468798Y-530968D01*
X469598Y-530835D01*
X470598Y-531102D01*
X471298Y-531768D01*
X471498Y-532568D01*
X471398Y-533369D01*
X470998Y-534035D01*
X468998Y-535368D01*
X468098Y-536302D01*
X467498Y-537635D01*
X467298Y-538835D01*
X471498D01*
G01X465498Y-513835D02*
Y-505835D01*
X469298D01*
G01X467898Y-509702D02*
X465498D01*
G54D19*
X6305Y105001D03*
X13806Y242078D03*
X9836Y248371D03*
X13806Y262078D03*
X9836Y268371D03*
X9206Y1496782D03*
X6548Y1556883D03*
X22912Y51296D03*
Y55305D03*
X26820Y67527D03*
Y63527D03*
Y59527D03*
X24930Y106495D03*
X29448Y177448D03*
X21614Y206864D03*
X20785Y242078D03*
Y262078D03*
X30447Y250599D03*
Y270599D03*
X23570Y292608D03*
X31786Y281272D03*
X28490Y536726D03*
Y531726D03*
Y552726D03*
Y540726D03*
Y544726D03*
X30208Y629311D03*
Y625311D03*
X45417Y177606D03*
X38321Y478982D03*
Y483982D03*
Y487982D03*
Y499982D03*
Y491982D03*
X40615Y597393D03*
X47270Y631212D03*
X50240Y1072761D03*
X40707Y1093757D03*
X39543Y1248448D03*
X56265Y847718D03*
X68751Y843118D03*
X64600Y1091656D03*
X58301Y1213720D03*
X62419Y1544571D03*
X74291Y151540D03*
X77750Y168697D03*
X77945Y191941D03*
X79914Y224321D03*
X80292Y571614D03*
Y575614D03*
X69035Y575841D03*
X78830Y686107D03*
X94902Y149768D03*
X101838Y192665D03*
Y196665D03*
X101933Y204864D03*
X116168Y242078D03*
X112198Y252371D03*
X127301Y106495D03*
X123976Y206864D03*
X123147Y242078D03*
X132809Y250599D03*
X144204Y554555D03*
Y558555D03*
Y562555D03*
X151116Y382600D03*
Y463600D03*
X150484Y595588D03*
Y591588D03*
X150516Y603600D03*
X150484Y599588D03*
X150516Y611600D03*
Y619600D03*
X150484Y607588D03*
X150516Y615600D03*
Y623600D03*
Y627600D03*
Y637969D03*
Y641974D03*
X176653Y151540D03*
X180112Y168697D03*
X180307Y191941D03*
X182276Y224321D03*
X194014Y68581D03*
Y80581D03*
X197264Y149768D03*
X203339Y58013D03*
X199557Y114488D03*
X204200Y196665D03*
Y192665D03*
X204295Y204864D03*
X214560Y252371D03*
X229654Y106495D03*
X226338Y206864D03*
X218530Y242078D03*
X225509D03*
X230780Y384718D03*
Y380718D03*
Y392718D03*
Y396718D03*
Y400718D03*
Y404718D03*
Y408718D03*
Y412718D03*
X218316Y458800D03*
X227116Y553700D03*
X218516Y545800D03*
X227116Y557700D03*
X227560Y1474522D03*
X227559Y1478442D03*
Y1486442D03*
X229559Y1510442D03*
X229564Y1518578D03*
X235171Y250599D03*
X241941Y675832D03*
X246402Y816300D03*
X245402Y836800D03*
X246401Y1506058D03*
X249216Y453873D03*
Y458859D03*
X248401Y542712D03*
X248701Y1517958D03*
X279015Y151540D03*
X296376Y68581D03*
Y80581D03*
X282474Y168697D03*
X282669Y191941D03*
X284638Y224321D03*
X309197Y35007D03*
X305701Y58013D03*
X301919Y114488D03*
X299626Y149768D03*
X306562Y192665D03*
Y196665D03*
X306657Y204864D03*
X328700Y206864D03*
X320892Y242078D03*
X327871D03*
X316922Y252371D03*
X323973Y306652D03*
X315601Y545912D03*
Y626912D03*
X332016Y106495D03*
X337533Y250599D03*
X343941Y1146071D03*
X347541Y458334D03*
Y450334D03*
X357914Y1170370D03*
X351283Y1191599D03*
X368416Y488816D03*
X376102Y745300D03*
X374402Y764500D03*
X363984Y943480D03*
X372948Y959812D03*
Y955812D03*
Y951812D03*
Y963812D03*
Y967812D03*
Y971812D03*
X384836Y168697D03*
X385031Y191941D03*
X387000Y224321D03*
X388184Y470382D03*
X389711Y868286D03*
X384533Y1547700D03*
Y1555700D03*
X404281Y114488D03*
X408924Y192665D03*
Y196665D03*
X409019Y204864D03*
X404072Y331589D03*
Y335589D03*
X399817Y467560D03*
Y479560D03*
X402904Y889786D03*
X404481Y1446807D03*
X416991Y35983D03*
X415649Y425413D03*
X418189Y455301D03*
Y459101D03*
Y463101D03*
X421817Y474560D03*
X411305Y889551D03*
X410717Y1523296D03*
X424132Y1537088D03*
X424652Y1550211D03*
X429016Y151540D03*
X440689Y424601D03*
Y428101D03*
Y431601D03*
X449627Y149768D03*
X452675Y328285D03*
Y324685D03*
Y344033D03*
Y340433D03*
Y336159D03*
Y332559D03*
Y351907D03*
Y348307D03*
X453635Y464809D03*
Y472809D03*
X442956Y508999D03*
X450493Y638279D03*
X456301Y1002180D03*
Y1007180D03*
X453801Y1012325D03*
Y1016325D03*
X445607Y1022766D03*
Y1034266D03*
Y1030266D03*
X452685Y1043140D03*
X452608Y1047047D03*
X470893Y242078D03*
X466923Y252371D03*
X462919Y495669D03*
Y516609D03*
X482017Y106495D03*
X478701Y206864D03*
X477872Y242078D03*
X487534Y250599D03*
X485426Y387089D03*
Y391589D03*
X485576Y536726D03*
Y531726D03*
Y544726D03*
Y540726D03*
X487294Y629311D03*
Y625311D03*
X478878Y652906D03*
X482301Y1031680D03*
X491301Y1032180D03*
X495407Y478982D03*
Y483982D03*
Y487982D03*
Y499982D03*
Y491982D03*
X497701Y597393D03*
X504356Y631212D03*
X499619Y660441D03*
X505110Y989235D03*
X501107Y1004766D03*
Y996766D03*
Y1008766D03*
X500974Y1020258D03*
X501107Y1030766D03*
X515723Y749443D03*
X509107Y1000766D03*
Y1004766D03*
Y996766D03*
Y1016266D03*
Y1020266D03*
Y1030766D03*
X531378Y151540D03*
X534837Y168697D03*
X535032Y191941D03*
X537001Y224321D03*
X535702Y345723D03*
Y359223D03*
Y354723D03*
Y350223D03*
Y363723D03*
Y377223D03*
Y372723D03*
Y368223D03*
Y386223D03*
Y390723D03*
X537378Y571614D03*
Y575614D03*
X526121Y575841D03*
X532540Y779889D03*
X529202Y840700D03*
X548739Y68581D03*
Y80581D03*
X554282Y114488D03*
X551989Y149768D03*
X545702Y345723D03*
Y350223D03*
Y359223D03*
Y354723D03*
Y377223D03*
Y372723D03*
Y368223D03*
Y363723D03*
Y381723D03*
X549989Y684509D03*
Y700509D03*
Y688509D03*
Y692509D03*
Y696509D03*
Y704509D03*
Y708509D03*
Y712509D03*
Y716509D03*
Y720509D03*
X552642Y841388D03*
X558064Y58013D03*
X558925Y192665D03*
Y196665D03*
X559020Y204864D03*
X569285Y252371D03*
X567519Y747079D03*
X584379Y106495D03*
X581063Y206864D03*
X580234Y242078D03*
X573255D03*
X585805Y957207D03*
X573319Y961807D03*
X585448Y1509687D03*
X589896Y250599D03*
X601290Y554555D03*
Y558555D03*
Y562555D03*
X595001Y1493658D03*
Y1497558D03*
X595101Y1501458D03*
X591197Y1505794D03*
X608202Y382600D03*
Y463600D03*
X607570Y595588D03*
Y591588D03*
X607602Y603600D03*
X607570Y599588D03*
X607602Y611600D03*
Y619600D03*
X607570Y607588D03*
X607602Y615600D03*
Y623600D03*
Y627600D03*
Y637969D03*
Y641974D03*
X633740Y151540D03*
X637199Y168697D03*
X637394Y191941D03*
X651101Y68581D03*
Y80581D03*
X639363Y224321D03*
X660426Y58013D03*
X656644Y114488D03*
X654351Y149768D03*
X661287Y192665D03*
Y196665D03*
X661382Y204864D03*
X655843Y666275D03*
X657959Y710129D03*
X683425Y206864D03*
X675617Y242078D03*
X682596D03*
X671647Y252371D03*
X675402Y458800D03*
X684202Y553700D03*
X675602Y545800D03*
X684202Y557700D03*
X675602Y558800D03*
Y562800D03*
X686741Y106495D03*
X692258Y250599D03*
X687866Y384718D03*
Y380718D03*
Y392718D03*
Y396718D03*
Y400718D03*
Y404718D03*
Y408718D03*
Y412718D03*
X699027Y675832D03*
X706302Y453873D03*
Y458859D03*
X705487Y542712D03*
X713291Y696718D03*
X717212Y779958D03*
X710366Y783453D03*
X724862Y756137D03*
Y764137D03*
Y768137D03*
Y772137D03*
X732916Y1606600D03*
X732267Y1634485D03*
X732283Y1630030D03*
X736102Y151540D03*
X739561Y168697D03*
X739756Y191941D03*
X741725Y224321D03*
X762788Y58013D03*
X753463Y68581D03*
Y80581D03*
X759006Y114488D03*
X756713Y149768D03*
X763649Y196665D03*
Y192665D03*
X763744Y204864D03*
X777979Y242078D03*
X774009Y252371D03*
X781059Y306652D03*
X781608Y442498D03*
X781640Y450510D03*
Y446510D03*
X772687Y545912D03*
Y626912D03*
X780265Y1427432D03*
Y1431432D03*
Y1439432D03*
X778519Y1458066D03*
X771648Y1449870D03*
X789103Y106495D03*
X785787Y206864D03*
X784958Y242078D03*
X794620Y250599D03*
X796360Y1436559D03*
X804627Y444334D03*
Y452334D03*
X808840Y836919D03*
X812340Y893419D03*
X801028Y1146071D03*
X814958Y1171120D03*
X803360Y1436559D03*
X805021Y1476616D03*
X825502Y483816D03*
X827016Y758500D03*
Y762500D03*
Y780500D03*
Y776500D03*
Y794500D03*
Y798500D03*
Y812500D03*
Y816500D03*
X819250Y830038D03*
X816840Y900919D03*
X831220Y1444849D03*
X841923Y168697D03*
X842118Y191941D03*
X844087Y224321D03*
X845270Y465382D03*
X842801Y831558D03*
X836332Y839953D03*
X842873Y839292D03*
X839974Y879459D03*
X842761Y875507D03*
X840284Y871459D03*
X839974Y883459D03*
X841194Y892564D03*
X839881Y887490D03*
X835016Y901500D03*
X842247Y1440859D03*
X842260Y1448959D03*
Y1444959D03*
Y1457959D03*
X855825Y68581D03*
Y80581D03*
X861368Y114488D03*
X863970Y491303D03*
Y479303D03*
X860777Y713170D03*
Y705170D03*
X861516Y768000D03*
Y786000D03*
Y804000D03*
Y822000D03*
X853744Y831469D03*
X853775Y843459D03*
Y847459D03*
Y839459D03*
Y863459D03*
Y859459D03*
Y855459D03*
Y851459D03*
Y867459D03*
Y879459D03*
Y875459D03*
Y871459D03*
Y892959D03*
Y883459D03*
Y887759D03*
X865150Y58013D03*
X866011Y192665D03*
Y196665D03*
X866106Y204864D03*
X880493Y309368D03*
Y305368D03*
Y313368D03*
Y325368D03*
Y321368D03*
Y317368D03*
Y329368D03*
X872600Y337342D03*
X880493D03*
Y333368D03*
X869584Y554703D03*
Y558703D03*
Y574703D03*
Y586828D03*
X869010Y698388D03*
X878777Y686970D03*
Y698970D03*
X886102Y151540D03*
X885970Y486303D03*
X892516Y529633D03*
X883777Y718570D03*
X896930Y1081764D03*
X887397Y1102760D03*
X883233Y1257451D03*
X883760Y1440859D03*
Y1448859D03*
Y1464859D03*
X883735Y1452663D03*
X883760Y1472859D03*
X906713Y149768D03*
X899276Y362369D03*
Y370369D03*
X910975Y441754D03*
X913515Y471642D03*
Y479442D03*
Y475442D03*
X910669Y547348D03*
X906977Y683770D03*
Y695770D03*
Y699770D03*
X911290Y1104659D03*
Y1100659D03*
X901991Y1222723D03*
X927668Y305255D03*
X916861Y304585D03*
X926168Y561578D03*
Y565578D03*
X926152Y585578D03*
Y589578D03*
X926168Y594329D03*
Y598329D03*
X920966Y704111D03*
X921744Y1472100D03*
X939103Y106495D03*
X936453Y192035D03*
X942659Y236866D03*
X944605Y316739D03*
X938693Y351281D03*
X936015Y440942D03*
Y444442D03*
Y447942D03*
X942663Y536726D03*
Y531726D03*
Y544726D03*
Y540726D03*
X944381Y629311D03*
Y625311D03*
X944786Y878216D03*
X936386Y883790D03*
X936388Y887508D03*
X944930Y899890D03*
X952494Y478982D03*
Y483982D03*
Y487982D03*
Y499982D03*
Y491982D03*
X954788Y597393D03*
X961443Y631212D03*
X949700Y792505D03*
X954573Y846665D03*
X947659Y846635D03*
X953214Y870278D03*
X960907Y1081764D03*
X951374Y1102760D03*
X947210Y1257451D03*
X978122Y343112D03*
Y346612D03*
X975267Y1100659D03*
Y1104659D03*
X965968Y1222723D03*
X988464Y151540D03*
X991923Y168697D03*
X992118Y191941D03*
X994087Y224321D03*
X979641Y338972D03*
Y331972D03*
X994465Y571614D03*
Y575614D03*
X983208Y575841D03*
X979637Y848597D03*
X981719Y837159D03*
X983951Y1104622D03*
X983988Y1100302D03*
X1005825Y68581D03*
Y80581D03*
X1009075Y149768D03*
X1008687Y196620D03*
X1011024Y1353714D03*
X1010977Y1363533D03*
X1010999Y1372734D03*
X1010994Y1376752D03*
X1015150Y58013D03*
X1011368Y114488D03*
X1016011Y196665D03*
Y192665D03*
X1016106Y204864D03*
X1026371Y252371D03*
X1015219Y837659D03*
X1014935Y958822D03*
X1041465Y106495D03*
X1038149Y206864D03*
X1030341Y242078D03*
X1037320D03*
X1030004Y847222D03*
X1027421Y954222D03*
X1046982Y250599D03*
X1055741Y314539D03*
Y322843D03*
Y328156D03*
Y319243D03*
X1055628Y339509D03*
X1055741Y331756D03*
X1055220Y360151D03*
Y364276D03*
X1058377Y554555D03*
Y558555D03*
Y562555D03*
X1065289Y382600D03*
Y463600D03*
X1064657Y595588D03*
Y591588D03*
X1064689Y603600D03*
X1064657Y599588D03*
X1064689Y611600D03*
Y619600D03*
X1064657Y607588D03*
X1064689Y615600D03*
Y623600D03*
Y627600D03*
Y637969D03*
Y641974D03*
X1090826Y151540D03*
X1108187Y68581D03*
Y80581D03*
X1094285Y168697D03*
X1094480Y191941D03*
X1096449Y224321D03*
X1117512Y58013D03*
X1113730Y114488D03*
X1111437Y149768D03*
X1109994Y168713D03*
X1118373Y192665D03*
Y196665D03*
X1118468Y204864D03*
X1117516Y329000D03*
Y334000D03*
Y339000D03*
X1112930Y666275D03*
X1115046Y710129D03*
X1140511Y206864D03*
X1132703Y242078D03*
X1139682D03*
X1128733Y252371D03*
X1126016Y329000D03*
Y334000D03*
Y339000D03*
X1132489Y458800D03*
X1132689Y545800D03*
Y558800D03*
Y562800D03*
X1143827Y106495D03*
X1149344Y250599D03*
X1144953Y392718D03*
Y384718D03*
Y380718D03*
Y404718D03*
Y408718D03*
Y396718D03*
Y400718D03*
Y412718D03*
X1141289Y553700D03*
Y557700D03*
X1156114Y675832D03*
X1163389Y453873D03*
Y458859D03*
X1162574Y542712D03*
X1184100Y324142D03*
X1188980Y329398D03*
X1174686Y774434D03*
X1193188Y151540D03*
X1196647Y168697D03*
X1196842Y191941D03*
X1198811Y224321D03*
X1219874Y58013D03*
X1210549Y68581D03*
Y80581D03*
X1216092Y114488D03*
X1213799Y149768D03*
X1212356Y168713D03*
X1220735Y192665D03*
Y196665D03*
X1220830Y204864D03*
X1235065Y242078D03*
X1231095Y252371D03*
X1238146Y306652D03*
X1229774Y545912D03*
Y626912D03*
X1246189Y106495D03*
X1242873Y206864D03*
X1242044Y242078D03*
X1251706Y250599D03*
X1252956Y1192376D03*
X1258016Y336000D03*
X1261714Y450334D03*
Y458334D03*
X1261710Y894866D03*
X1258114Y1146071D03*
X1257201Y1523458D03*
X1257162Y1527334D03*
X1257201Y1543558D03*
X1257162Y1531334D03*
Y1539334D03*
X1257186Y1535385D03*
X1282589Y488816D03*
X1282030Y768576D03*
Y780576D03*
X1273687Y848145D03*
X1273783Y864487D03*
Y859487D03*
X1273771Y852029D03*
X1273783Y874487D03*
Y869487D03*
Y879487D03*
Y889487D03*
Y884487D03*
X1284016Y919500D03*
X1280392Y933598D03*
X1272044Y1171120D03*
X1299009Y168697D03*
X1299204Y191941D03*
X1301173Y224321D03*
X1295516Y326500D03*
Y337000D03*
Y330000D03*
Y333500D03*
X1302357Y470382D03*
X1288016Y819500D03*
Y839500D03*
Y843500D03*
Y847500D03*
Y851500D03*
Y863500D03*
Y867000D03*
X1288011Y885783D03*
X1301016Y942500D03*
X1318454Y114488D03*
X1314718Y168713D03*
X1313990Y467560D03*
Y479560D03*
X1331164Y35983D03*
X1323097Y196665D03*
Y192665D03*
X1323192Y204864D03*
X1329822Y425413D03*
X1332362Y455301D03*
Y459101D03*
Y463101D03*
X1329516Y558500D03*
Y562500D03*
Y566500D03*
X1321516D03*
X1329516Y574500D03*
Y586500D03*
Y578500D03*
Y582500D03*
X1321516D03*
Y586500D03*
X1329516Y590500D03*
Y605000D03*
X1321516Y590500D03*
X1329516Y609000D03*
Y613000D03*
Y621000D03*
X1321516Y613000D03*
X1329516Y637000D03*
Y633000D03*
Y625000D03*
Y629000D03*
X1321516D03*
Y633000D03*
Y637000D03*
X1329516Y653500D03*
Y649500D03*
X1321516Y645000D03*
X1329516Y665500D03*
Y657500D03*
X1321516D03*
X1329516Y669500D03*
X1321516Y677500D03*
Y681500D03*
Y673500D03*
X1329516D03*
Y681500D03*
Y677500D03*
Y696500D03*
Y700500D03*
X1321516Y704500D03*
X1329516D03*
Y712500D03*
Y716500D03*
X1321516Y720500D03*
Y728500D03*
Y724500D03*
X1329516Y728500D03*
Y724500D03*
Y720500D03*
X1321486Y736464D03*
X1343189Y151540D03*
X1335990Y474560D03*
X1339309Y749675D03*
Y745675D03*
Y741675D03*
Y737675D03*
Y765675D03*
Y761675D03*
Y757675D03*
Y753675D03*
Y769675D03*
Y781675D03*
X1363800Y149768D03*
X1355260Y327777D03*
Y331377D03*
Y335651D03*
Y339251D03*
Y343525D03*
Y347125D03*
Y351399D03*
Y354999D03*
X1354862Y424601D03*
Y428101D03*
Y431601D03*
X1367975Y1012325D03*
Y1016325D03*
X1359781Y1022766D03*
Y1034266D03*
X1366859Y1043140D03*
X1359781Y1030266D03*
X1366782Y1047047D03*
X1381096Y252371D03*
X1370475Y1002180D03*
Y1007180D03*
X1396190Y106495D03*
X1392874Y206864D03*
X1392045Y242078D03*
X1385066D03*
X1387967Y361371D03*
Y356871D03*
X1399750Y536726D03*
Y531726D03*
Y544726D03*
Y540726D03*
X1385602Y577192D03*
X1385603Y627817D03*
X1399516Y652000D03*
Y660000D03*
Y703000D03*
Y707000D03*
X1396475Y1031680D03*
X1401707Y250599D03*
X1409581Y478982D03*
Y483982D03*
Y487982D03*
Y499982D03*
Y491982D03*
X1411875Y597393D03*
X1401468Y629311D03*
Y625311D03*
X1412516Y689000D03*
Y705000D03*
Y713000D03*
Y709000D03*
Y733000D03*
X1412485Y720894D03*
X1412516Y749000D03*
Y753000D03*
Y757000D03*
X1412539Y765343D03*
X1408114Y815683D03*
X1408016Y832000D03*
Y828000D03*
X1407965Y823934D03*
X1407918Y819817D03*
X1408016Y848000D03*
Y840000D03*
Y836000D03*
Y852000D03*
Y864000D03*
Y856000D03*
Y880000D03*
Y868000D03*
Y884000D03*
Y896000D03*
Y900000D03*
X1411085Y992307D03*
X1415281Y1004766D03*
Y996766D03*
Y1008766D03*
X1415285Y1020250D03*
X1415281Y1030766D03*
X1405475Y1032180D03*
X1408627Y1539557D03*
X1408135Y1562235D03*
X1418530Y631212D03*
X1420516Y681000D03*
Y685000D03*
Y689000D03*
Y697000D03*
Y701000D03*
Y713000D03*
Y709000D03*
Y705000D03*
Y725000D03*
Y729000D03*
Y733000D03*
Y741000D03*
Y745000D03*
Y749000D03*
Y753000D03*
Y757000D03*
X1429516Y774500D03*
Y798500D03*
Y790500D03*
Y794500D03*
Y818500D03*
Y834500D03*
Y838500D03*
Y842500D03*
X1418230Y939292D03*
X1425097Y951563D03*
X1425037Y947595D03*
X1423281Y1000766D03*
Y1004766D03*
Y996766D03*
Y1016266D03*
Y1020266D03*
Y1030766D03*
X1423487Y1494706D03*
X1426457Y1524252D03*
X1445551Y151540D03*
X1449010Y168697D03*
X1449205Y191941D03*
X1443223Y320861D03*
Y325361D03*
Y329861D03*
Y334361D03*
Y338861D03*
Y343361D03*
Y347861D03*
Y352361D03*
Y356861D03*
X1440295Y575841D03*
X1437516Y766500D03*
Y774500D03*
Y770500D03*
Y782500D03*
Y798500D03*
Y794500D03*
Y790500D03*
Y786500D03*
Y814500D03*
Y810500D03*
Y830500D03*
Y826500D03*
Y818500D03*
Y834500D03*
Y838500D03*
Y842500D03*
X1462912Y68581D03*
Y80581D03*
X1464719Y168713D03*
X1451174Y224321D03*
X1453223Y320861D03*
Y325361D03*
Y329861D03*
Y334361D03*
Y338861D03*
Y343361D03*
Y347861D03*
Y352361D03*
X1451552Y571614D03*
Y575614D03*
X1456634Y950980D03*
X1476913Y38244D03*
X1472237Y58013D03*
X1468455Y114488D03*
X1466162Y149768D03*
X1473098Y196665D03*
Y192665D03*
X1473193Y204864D03*
X1482016Y685630D03*
X1466633Y947600D03*
X1495236Y206864D03*
X1487428Y242078D03*
X1494407D03*
X1483458Y252371D03*
X1490062Y358700D03*
Y354200D03*
X1482516Y727500D03*
X1497299Y907240D03*
X1498552Y106495D03*
X1504069Y250599D03*
X1499516Y769000D03*
Y813000D03*
X1522376Y382600D03*
Y463600D03*
X1515464Y554555D03*
Y558555D03*
Y562555D03*
X1521744Y595588D03*
Y591588D03*
X1521776Y603600D03*
X1521744Y599588D03*
X1521776Y611600D03*
Y619600D03*
X1521744Y607588D03*
X1521776Y615600D03*
Y623600D03*
Y627600D03*
Y637969D03*
Y641974D03*
X1517401Y968739D03*
X1543663Y969737D03*
X1547913Y151540D03*
X1551372Y168697D03*
X1551567Y191941D03*
X1553536Y224321D03*
X1558395Y316363D03*
Y325363D03*
X1548395Y316363D03*
Y325363D03*
X1558395Y329863D03*
Y334363D03*
Y343363D03*
X1548395Y329863D03*
Y334363D03*
Y343363D03*
X1558395Y352363D03*
X1574599Y58013D03*
X1565274Y68581D03*
Y80581D03*
X1570817Y114488D03*
X1568524Y149768D03*
X1567081Y168713D03*
X1575460Y192665D03*
Y196665D03*
X1575555Y204864D03*
X1571716Y341600D03*
X1570017Y666275D03*
X1572133Y710129D03*
X1589790Y242078D03*
X1585820Y252371D03*
X1589576Y458800D03*
X1589776Y545800D03*
X1590824Y1442557D03*
X1600914Y106495D03*
X1597598Y206864D03*
X1596769Y242078D03*
X1606431Y250599D03*
X1608813Y336252D03*
Y344252D03*
Y340252D03*
X1602040Y384718D03*
Y380718D03*
Y392718D03*
Y400718D03*
Y404718D03*
Y408718D03*
Y396718D03*
Y412718D03*
X1598376Y553700D03*
Y557700D03*
X1611118Y699917D03*
Y717817D03*
X1611418Y732417D03*
X1599382Y1468023D03*
X1603619Y1527334D03*
X1620476Y453873D03*
Y458859D03*
X1619661Y542712D03*
X1613201Y675832D03*
X1627518Y744317D03*
X1626818Y762717D03*
X1616518Y828117D03*
X1612701Y1528558D03*
X1616301Y1539358D03*
X1612401Y1535258D03*
X1631118Y711417D03*
X1638518Y728117D03*
X1640766Y881999D03*
X1641114Y917241D03*
X1640872Y952125D03*
X1650275Y151540D03*
X1653734Y168697D03*
X1653929Y191941D03*
X1655898Y224321D03*
X1648331Y871345D03*
X1648868Y909279D03*
X1648475Y942136D03*
X1676961Y58013D03*
X1667636Y68581D03*
Y80581D03*
X1673179Y114488D03*
X1670886Y149768D03*
X1669443Y168713D03*
X1677822Y192665D03*
Y196665D03*
X1677917Y204864D03*
X1692152Y242078D03*
X1688182Y252371D03*
X1686861Y545912D03*
Y626912D03*
X1703276Y106495D03*
X1699960Y206864D03*
X1699131Y242078D03*
X1708793Y250599D03*
X1695233Y306652D03*
X1718801Y458334D03*
Y450334D03*
X1715201Y1146071D03*
X1739676Y488816D03*
X1729131Y1171120D03*
X1756096Y168697D03*
X1756291Y191941D03*
X1758260Y224321D03*
X1750123Y879199D03*
X1750178Y897279D03*
X1754216Y935100D03*
X1769998Y68581D03*
Y80581D03*
X1771805Y168713D03*
X1759444Y470382D03*
X1771077Y471560D03*
Y479560D03*
X1779323Y58013D03*
X1775541Y114488D03*
X1780184Y196665D03*
Y192665D03*
X1780279Y204864D03*
X1789678Y200716D03*
X1786909Y425413D03*
X1789449Y455301D03*
Y459101D03*
Y463101D03*
X1789579Y989660D03*
X1787150Y1430956D03*
X1793077Y474560D03*
X1802065Y985060D03*
X1804887Y1082250D03*
X1795354Y1103246D03*
X1791190Y1257937D03*
X1811949Y424601D03*
Y428101D03*
Y431601D03*
X1819247Y1101145D03*
Y1105145D03*
X1809948Y1223209D03*
G54D91*
X75692Y616665D03*
Y635957D03*
X100833Y271685D03*
Y290977D03*
X203195Y271685D03*
Y290977D03*
X305557Y271685D03*
Y290977D03*
X407919Y271685D03*
Y290977D03*
X412801Y380817D03*
Y400109D03*
X532778Y616665D03*
Y635957D03*
X557920Y271685D03*
Y290977D03*
X660282Y271685D03*
Y290977D03*
X762644Y271685D03*
Y290977D03*
X865006Y271685D03*
Y290977D03*
X908127Y397158D03*
Y416450D03*
X989865Y616665D03*
Y635957D03*
X1015006Y271685D03*
Y290977D03*
X1117368Y271685D03*
Y290977D03*
X1219730Y271685D03*
Y290977D03*
X1322092Y271685D03*
Y290977D03*
X1326974Y380817D03*
Y400109D03*
X1446952Y616665D03*
Y635957D03*
X1472093Y271685D03*
Y290977D03*
X1574455Y271685D03*
Y290977D03*
X1676817Y271685D03*
Y290977D03*
X1779179Y271685D03*
Y290977D03*
X1784061Y380817D03*
Y400109D03*
G54D82*
X58504Y880295D03*
Y875295D03*
Y870295D03*
Y885295D03*
Y890295D03*
Y895295D03*
Y905295D03*
Y900295D03*
X96930Y875295D03*
Y880295D03*
Y870295D03*
Y895295D03*
Y890295D03*
Y885295D03*
Y905295D03*
Y900295D03*
X515444Y880295D03*
Y875295D03*
Y870295D03*
Y885295D03*
Y890295D03*
Y895295D03*
Y905295D03*
Y900295D03*
X553870Y875295D03*
Y880295D03*
Y870295D03*
Y895295D03*
Y890295D03*
Y885295D03*
Y905295D03*
Y900295D03*
X972833Y880295D03*
Y875295D03*
Y870295D03*
Y885295D03*
Y890295D03*
Y895295D03*
Y905295D03*
Y900295D03*
X1011259Y875295D03*
Y880295D03*
Y870295D03*
Y895295D03*
Y890295D03*
Y885295D03*
Y905295D03*
Y900295D03*
X1429617Y880295D03*
Y875295D03*
Y870295D03*
Y885295D03*
Y890295D03*
Y895295D03*
Y905295D03*
Y900295D03*
X1468043Y875295D03*
Y880295D03*
Y870295D03*
Y895295D03*
Y890295D03*
Y885295D03*
Y905295D03*
Y900295D03*
G54D139*
X406996Y1543915D03*
X921343Y363254D03*
G54D247*
X1155929Y786294D03*
Y808342D03*
X1171284Y786294D03*
X1158488D03*
X1161047D03*
X1163606D03*
X1166166D03*
X1168725D03*
X1158488Y808342D03*
X1171284D03*
X1161047D03*
X1163606D03*
X1166166D03*
X1168725D03*
X1173843Y786294D03*
Y808342D03*
G54D193*
X849441Y1367717D03*
G54D184*
X801057Y1448158D03*
Y1457016D03*
G54D238*
X1027569Y1344460D03*
Y1348200D03*
Y1351940D03*
X1037883D03*
Y1348200D03*
Y1344460D03*
G54D157*
X436004Y566055D03*
Y610547D03*
G54D28*
X18463Y250245D03*
Y270245D03*
X19075Y284082D03*
X25549Y250245D03*
Y270245D03*
X82918Y149414D03*
X84679Y1012213D03*
X90004Y149414D03*
X91765Y1012213D03*
X108643Y139695D03*
X127911Y250245D03*
X120825D03*
X192366Y149414D03*
X185280D03*
X211005Y139695D03*
X230273Y250245D03*
X223187D03*
X294728Y149414D03*
X287642D03*
X313367Y139695D03*
X325549Y250245D03*
X332635D03*
X408758Y471560D03*
X415844D03*
X437643Y149414D03*
X444729D03*
X463368Y139695D03*
X482636Y250245D03*
X475550D03*
X540005Y149414D03*
X547091D03*
X548852Y1012213D03*
X541766D03*
X565730Y139695D03*
X584998Y250245D03*
X577912D03*
X649453Y149414D03*
X642367D03*
X668092Y139695D03*
X680274Y250245D03*
X687360D03*
X744729Y149414D03*
X751815D03*
X770454Y139695D03*
X782636Y250245D03*
X789722D03*
X879997Y483303D03*
X872911D03*
X894729Y149414D03*
X901815D03*
X920454Y139695D03*
X1004177Y149414D03*
X997091D03*
X1005938Y1012213D03*
X998852D03*
X1022816Y139695D03*
X1042084Y250245D03*
X1034998D03*
X1106539Y149414D03*
X1099453D03*
X1125178Y139695D03*
X1137360Y250245D03*
X1144446D03*
X1201815Y149414D03*
X1208901D03*
X1227540Y139695D03*
X1246808Y250245D03*
X1239722D03*
X1267792Y905324D03*
X1274878D03*
X1330017Y471560D03*
X1322931D03*
X1351816Y149414D03*
X1358902D03*
X1377541Y139695D03*
X1396809Y250245D03*
X1389723D03*
X1421368Y1540385D03*
X1428454D03*
X1420995Y1561025D03*
X1428081D03*
X1461264Y149414D03*
X1454178D03*
X1463025Y1012213D03*
X1455939D03*
X1479903Y139695D03*
X1492085Y250245D03*
X1499171D03*
X1556540Y149414D03*
X1563626D03*
X1582265Y139695D03*
X1594447Y250245D03*
X1601533D03*
X1627155Y702883D03*
Y720783D03*
X1627455Y735383D03*
Y753583D03*
X1623741Y777783D03*
X1616655D03*
X1623541Y790483D03*
X1616455D03*
X1623241Y804583D03*
X1616155D03*
X1623341Y818683D03*
X1616255D03*
X1634241Y702883D03*
Y720783D03*
X1634541Y735383D03*
Y753583D03*
X1658902Y149414D03*
X1665988D03*
X1684627Y139695D03*
X1703895Y250245D03*
X1696809D03*
X1787104Y471560D03*
X1780018D03*
X1790264Y1443715D03*
X1783178D03*
X1790141Y1475905D03*
X1783055D03*
G54D73*
X51653Y1355533D03*
X97806Y23214D03*
X105562Y826044D03*
X382749Y609811D03*
X520770Y330592D03*
X582703Y1464683D03*
X657531Y943324D03*
X811771Y518798D03*
X899546Y1369736D03*
X908190Y63396D03*
X1244511Y960614D03*
X1308096Y548593D03*
X1344628Y177855D03*
X1679534Y33878D03*
X1773034Y1565233D03*
X1795900Y852600D03*
G54D148*
X425820Y750005D03*
Y748036D03*
Y765753D03*
Y763784D03*
Y761816D03*
Y759847D03*
Y757879D03*
Y755910D03*
Y753942D03*
Y751973D03*
Y777564D03*
Y775595D03*
Y773627D03*
Y771658D03*
Y769690D03*
Y767721D03*
X1798520Y880636D03*
Y896384D03*
Y894416D03*
Y892447D03*
Y890479D03*
Y888510D03*
Y886542D03*
Y884573D03*
Y882605D03*
Y910164D03*
Y908195D03*
Y906227D03*
Y904258D03*
Y902290D03*
Y900321D03*
Y898353D03*
G54D166*
X522524Y699411D03*
G54D46*
X37955Y1138071D03*
Y1180649D03*
X885145Y1147074D03*
Y1189652D03*
X949122Y1147074D03*
Y1189652D03*
X1793102Y1147560D03*
Y1190138D03*
G54D229*
X965740Y1360945D03*
G54D175*
X721756Y-31826D03*
X841756Y-71006D03*
X1005256Y-31826D03*
X1075256Y-71006D03*
X1291756Y-31956D03*
X1331756Y-71006D03*
X1576256Y-32086D03*
X1586256Y-71006D03*
G54D55*
X51043Y144095D03*
X57933Y66811D03*
X160295D03*
X153405Y144095D03*
X183435Y630650D03*
X190325Y374862D03*
X262657Y66811D03*
X255767Y144095D03*
X279360Y630650D03*
X286250Y374862D03*
X358129Y144095D03*
X365019Y66811D03*
X508130Y144095D03*
X515020Y66811D03*
X617382D03*
X610492Y144095D03*
X647411Y374862D03*
X640521Y630650D03*
X719744Y66811D03*
X712854Y144095D03*
X736446Y630650D03*
X743336Y374862D03*
X815216Y144095D03*
X822106Y66811D03*
X972106D03*
X965216Y144095D03*
X1074468Y66811D03*
X1067578Y144095D03*
X1104498Y374862D03*
X1097608Y630650D03*
X1169940Y144095D03*
X1176830Y66811D03*
X1200423Y374862D03*
X1193533Y630650D03*
X1272302Y144095D03*
X1279192Y66811D03*
X1429193D03*
X1422303Y144095D03*
X1531555Y66811D03*
X1524665Y144095D03*
X1561585Y374862D03*
X1554695Y630650D03*
X1627027Y144095D03*
X1633917Y66811D03*
X1657510Y374862D03*
X1650620Y630650D03*
X1736279Y66811D03*
X1729389Y144095D03*
G54D64*
X45012Y671782D03*
X66862D03*
G54D37*
X11313Y1116633D03*
X28635D03*
X43620Y1110100D03*
X60942D03*
X858003Y1125636D03*
X875325D03*
X890180Y1119103D03*
X907502D03*
X921980Y1125636D03*
X939302D03*
X954287Y1119103D03*
X971609D03*
X1771960Y1126122D03*
X1789282D03*
X1803760Y1119589D03*
X1821082D03*
G54D65*
X45449Y1074996D03*
X346629Y1218602D03*
X349458Y1221429D03*
X356156Y1215651D03*
X358985Y1218480D03*
X353328Y1212823D03*
X352287Y1224258D03*
X355116Y1227087D03*
X364642Y1224137D03*
X810415Y1212823D03*
X816072Y1218480D03*
X813243Y1215651D03*
X806545Y1221429D03*
X803716Y1218602D03*
X809374Y1224258D03*
X812203Y1227087D03*
X821729Y1224137D03*
X892139Y1083999D03*
X956116D03*
X1263631Y1221429D03*
X1260802Y1218602D03*
X1270329Y1215651D03*
X1267501Y1212823D03*
X1266460Y1224258D03*
X1269289Y1227087D03*
X1273158Y1218480D03*
X1278815Y1224137D03*
X1720718Y1221429D03*
X1717889Y1218602D03*
X1724588Y1212823D03*
X1723547Y1224258D03*
X1727416Y1215651D03*
X1730245Y1218480D03*
X1735902Y1224137D03*
X1726376Y1227087D03*
X1800096Y1084485D03*
G54D38*
X26789Y1373669D03*
X184851Y334492D03*
X235433Y1580079D03*
Y1626339D03*
X581890Y1580079D03*
Y1626339D03*
X1259055Y1580079D03*
Y1626339D03*
X1605512Y1580079D03*
Y1626339D03*
X1796847Y1517889D03*
X1809883Y120792D03*
G54D83*
X67191Y1046138D03*
X67163Y1050784D03*
X67209Y1055646D03*
X67273Y1060812D03*
X68999Y111123D03*
X71099D03*
X68999Y114723D03*
X71099D03*
X79401Y118235D03*
X81501D03*
X79401Y121835D03*
X81501D03*
X79401Y132409D03*
X81501D03*
X68999Y125296D03*
X71099D03*
X68999Y128896D03*
X71099D03*
X79401Y136009D03*
X81501D03*
X69291Y1046138D03*
X69263Y1050784D03*
X69309Y1055646D03*
X69373Y1060812D03*
X108138Y1009759D03*
X106038D03*
X147696Y401613D03*
X145596D03*
X147696Y398013D03*
X145596D03*
X145296Y415787D03*
X143196D03*
X145296Y412187D03*
X143196D03*
X145296Y429960D03*
X143196D03*
X145296Y440533D03*
X143196D03*
X145296Y426360D03*
X143196D03*
X145296Y444133D03*
X143196D03*
X145296Y472887D03*
X143196D03*
X145296Y469287D03*
X143196D03*
X145296Y487060D03*
X143196D03*
X145296Y483460D03*
X143196D03*
X145296Y517021D03*
X143196D03*
X145296Y513421D03*
X143196D03*
X145296Y531194D03*
X143196D03*
X145296Y527594D03*
X143196D03*
X155698Y390901D03*
X153598D03*
X155698Y394501D03*
X153598D03*
X155698Y408674D03*
X153598D03*
X155698Y405074D03*
X153598D03*
X155698Y422847D03*
X153598D03*
X155698Y419247D03*
X153598D03*
X155698Y437021D03*
X153598D03*
X155698Y433421D03*
X153598D03*
X155698Y490573D03*
X153598D03*
X155698Y476399D03*
X153598D03*
X155698Y479999D03*
X153598D03*
X155698Y494173D03*
X153598D03*
X155698Y520533D03*
X153598D03*
X155698Y524133D03*
X153598D03*
X155698Y538306D03*
X153598D03*
X155698Y534706D03*
X153598D03*
X171361Y111123D03*
X173461D03*
X171361Y114723D03*
X173461D03*
X181763Y118235D03*
Y132409D03*
Y121835D03*
X171361Y125296D03*
X173461D03*
X171361Y128896D03*
X173461D03*
X181763Y136009D03*
X183863Y118235D03*
Y132409D03*
Y121835D03*
Y136009D03*
X219559Y1447353D03*
X221659D03*
X219559Y1450953D03*
X221659D03*
X219559Y1458353D03*
X221659D03*
X219559Y1461953D03*
X221659D03*
X273723Y111123D03*
X275823D03*
X273723Y114723D03*
X275823D03*
X273723Y125296D03*
X275823D03*
X273723Y128896D03*
X275823D03*
X284125Y118235D03*
X286225D03*
X284125Y121835D03*
X286225D03*
X284125Y132409D03*
X286225D03*
X284125Y136009D03*
X286225D03*
X313987Y467206D03*
X316087D03*
X313987Y470806D03*
X316087D03*
X324389Y474318D03*
X326489D03*
X324389Y488491D03*
X326489D03*
X313987Y484979D03*
X316087D03*
X324389Y477918D03*
X326489D03*
X313987Y481379D03*
X316087D03*
X324389Y492091D03*
X326489D03*
X324389Y518452D03*
X326489D03*
X324389Y522052D03*
X326489D03*
X313987Y511339D03*
X316087D03*
X313987Y514939D03*
X316087D03*
X324389Y536225D03*
X326489D03*
X324389Y532625D03*
X326489D03*
X313987Y525513D03*
X316087D03*
X313987Y529113D03*
X316087D03*
X324389Y568491D03*
X326489D03*
X324389Y572091D03*
X326489D03*
X313987Y564979D03*
X316087D03*
X313987Y561379D03*
X316087D03*
X313987Y579152D03*
X316087D03*
X313987Y575552D03*
X316087D03*
X324389Y582665D03*
X326489D03*
X324389Y586265D03*
X326489D03*
X313987Y593325D03*
X316087D03*
X313987Y589725D03*
X316087D03*
X313987Y603899D03*
X316087D03*
X324389Y600438D03*
X326489D03*
X324389Y596838D03*
X326489D03*
X313987Y607499D03*
X316087D03*
X324389Y611011D03*
X326489D03*
X324389Y614611D03*
X326489D03*
X376085Y111123D03*
Y114723D03*
Y125296D03*
Y128896D03*
X378185Y111123D03*
Y114723D03*
Y125296D03*
Y128896D03*
X386487Y118235D03*
X388587D03*
X386487Y121835D03*
X388587D03*
X386487Y132409D03*
X388587D03*
X386487Y136009D03*
X388587D03*
X526086Y111123D03*
X528186D03*
X526086Y114723D03*
X528186D03*
X536488Y118235D03*
X538588D03*
X536488Y121835D03*
X538588D03*
X526086Y125296D03*
X528186D03*
X526086Y128896D03*
X528186D03*
X536488Y132409D03*
X538588D03*
X536488Y136009D03*
X538588D03*
X565225Y1009759D03*
X563125D03*
X602682Y398013D03*
Y401613D03*
X602382Y412187D03*
X600282D03*
X602382Y415787D03*
X600282D03*
X602382Y429960D03*
X600282D03*
X602382Y426360D03*
X600282D03*
X602382Y440533D03*
X600282D03*
X602382Y444133D03*
X600282D03*
X602382Y469287D03*
X600282D03*
X602382Y472887D03*
X600282D03*
X602382Y487060D03*
X600282D03*
X602382Y483460D03*
X600282D03*
X602382Y517021D03*
X600282D03*
X602382Y513421D03*
X600282D03*
X602382Y527594D03*
X600282D03*
X602382Y531194D03*
X600282D03*
X612784Y390901D03*
X610684D03*
X604782Y398013D03*
Y401613D03*
X612784Y394501D03*
X610684D03*
X612784Y408674D03*
X610684D03*
X612784Y405074D03*
X610684D03*
X612784Y422847D03*
X610684D03*
X612784Y419247D03*
X610684D03*
X612784Y433421D03*
X610684D03*
X612784Y437021D03*
X610684D03*
X612784Y490573D03*
X610684D03*
X612784Y476399D03*
X610684D03*
X612784Y479999D03*
X610684D03*
X612784Y494173D03*
X610684D03*
X612784Y520533D03*
X610684D03*
X612784Y524133D03*
X610684D03*
X612784Y534706D03*
X610684D03*
X612784Y538306D03*
X610684D03*
X628448Y111123D03*
X630548D03*
X628448Y114723D03*
X630548D03*
X628448Y125296D03*
X630548D03*
X628448Y128896D03*
X630548D03*
X638850Y118235D03*
X640950D03*
X638850Y121835D03*
X640950D03*
X638850Y132409D03*
X640950D03*
X638850Y136009D03*
X640950D03*
X730810Y114723D03*
X732910D03*
X730810Y111123D03*
X732910D03*
X730810Y125296D03*
X732910D03*
X730810Y128896D03*
X732910D03*
X741212Y118235D03*
X743312D03*
X741212Y132409D03*
X743312D03*
X741212Y121835D03*
X743312D03*
X741212Y136009D03*
X743312D03*
X771073Y470806D03*
X773173D03*
X771073Y467206D03*
X773173D03*
X781475Y474318D03*
Y488491D03*
Y477918D03*
X771073Y481379D03*
X773173D03*
X771073Y484979D03*
X773173D03*
X781475Y492091D03*
Y518452D03*
Y522052D03*
X771073Y511339D03*
X773173D03*
X771073Y514939D03*
X773173D03*
X771073Y525513D03*
X773173D03*
X781475Y532625D03*
Y536225D03*
X771073Y529113D03*
X773173D03*
X771073Y564979D03*
X773173D03*
X781475Y572091D03*
Y568491D03*
X771073Y561379D03*
X773173D03*
X781475Y582665D03*
Y586265D03*
X771073Y575552D03*
X773173D03*
X771073Y579152D03*
X773173D03*
X771073Y593325D03*
X773173D03*
X771073Y589725D03*
X773173D03*
X781475Y596838D03*
Y600438D03*
X771073Y603899D03*
X773173D03*
X771073Y607499D03*
X773173D03*
X781475Y611011D03*
Y614611D03*
X783575Y474318D03*
Y488491D03*
Y477918D03*
Y492091D03*
Y518452D03*
Y522052D03*
Y532625D03*
Y536225D03*
Y572091D03*
Y568491D03*
Y582665D03*
Y586265D03*
Y596838D03*
Y600438D03*
Y611011D03*
Y614611D03*
X833172Y111123D03*
X835272D03*
X833172Y114723D03*
X835272D03*
X833172Y125296D03*
X835272D03*
X833172Y128896D03*
X835272D03*
X843574Y118235D03*
X845674D03*
X843574Y121835D03*
X845674D03*
X843574Y132409D03*
X845674D03*
X843574Y136009D03*
X845674D03*
X911893Y1022889D03*
X911841Y1028101D03*
X913993Y1022889D03*
X913941Y1028101D03*
X919276Y1088717D03*
X921376D03*
X919304Y1080832D03*
X921404D03*
X983172Y111123D03*
X985272D03*
X983172Y114723D03*
X985272D03*
X993574Y118235D03*
Y121835D03*
X983172Y125296D03*
X985272D03*
X983172Y128896D03*
X985272D03*
X993574Y132409D03*
Y136009D03*
X995674Y118235D03*
Y121835D03*
Y132409D03*
Y136009D03*
X1022311Y1009759D03*
X1020211D03*
X1057369Y412187D03*
Y415787D03*
Y429960D03*
Y426360D03*
Y440533D03*
Y444133D03*
Y472887D03*
Y469287D03*
Y487060D03*
Y483460D03*
Y517021D03*
Y513421D03*
Y531194D03*
Y527594D03*
X1069871Y390901D03*
X1067771D03*
X1061869Y398013D03*
X1059769D03*
X1061869Y401613D03*
X1059769D03*
X1069871Y394501D03*
X1067771D03*
X1069871Y405074D03*
X1067771D03*
X1069871Y408674D03*
X1067771D03*
X1059469Y412187D03*
Y415787D03*
X1069871Y422847D03*
X1067771D03*
X1069871Y419247D03*
X1067771D03*
X1059469Y429960D03*
Y426360D03*
Y440533D03*
X1069871Y437021D03*
X1067771D03*
X1069871Y433421D03*
X1067771D03*
X1059469Y444133D03*
Y472887D03*
Y469287D03*
X1069871Y490573D03*
X1067771D03*
X1059469Y487060D03*
Y483460D03*
X1069871Y476399D03*
X1067771D03*
X1069871Y479999D03*
X1067771D03*
X1069871Y494173D03*
X1067771D03*
X1069871Y520533D03*
X1067771D03*
X1059469Y517021D03*
Y513421D03*
X1069871Y524133D03*
X1067771D03*
X1069871Y534706D03*
X1067771D03*
X1069871Y538306D03*
X1067771D03*
X1059469Y531194D03*
Y527594D03*
X1085534Y114723D03*
X1087634D03*
X1085534Y111123D03*
X1087634D03*
X1085534Y125296D03*
X1087634D03*
X1085534Y128896D03*
X1087634D03*
X1095936Y118235D03*
X1098036D03*
X1095936Y121835D03*
X1098036D03*
X1095936Y132409D03*
X1098036D03*
X1095936Y136009D03*
X1098036D03*
X1187896Y111123D03*
Y114723D03*
Y125296D03*
Y128896D03*
X1189996Y111123D03*
Y114723D03*
Y125296D03*
Y128896D03*
X1198298Y118235D03*
X1200398D03*
X1198298Y121835D03*
X1200398D03*
X1198298Y132409D03*
X1200398D03*
X1198298Y136009D03*
X1200398D03*
X1228160Y467206D03*
X1230260D03*
X1228160Y470806D03*
X1230260D03*
X1228160Y481379D03*
X1230260D03*
X1228160Y484979D03*
X1230260D03*
X1228160Y511339D03*
X1230260D03*
X1228160Y514939D03*
X1230260D03*
X1228160Y525513D03*
X1230260D03*
X1228160Y529113D03*
X1230260D03*
X1228160Y564979D03*
X1230260D03*
X1228160Y561379D03*
X1230260D03*
X1228160Y579152D03*
X1230260D03*
X1228160Y575552D03*
X1230260D03*
X1228160Y593325D03*
X1230260D03*
X1228160Y589725D03*
X1230260D03*
X1228160Y603899D03*
X1230260D03*
X1228160Y607499D03*
X1230260D03*
X1238562Y474318D03*
X1240662D03*
X1238562Y488491D03*
X1240662D03*
X1238562Y477918D03*
X1240662D03*
X1238562Y492091D03*
X1240662D03*
X1238562Y518452D03*
X1240662D03*
X1238562Y522052D03*
X1240662D03*
X1238562Y532625D03*
X1240662D03*
X1238562Y536225D03*
X1240662D03*
X1238562Y572091D03*
X1240662D03*
X1238562Y568491D03*
X1240662D03*
X1238562Y582665D03*
X1240662D03*
X1238562Y586265D03*
X1240662D03*
X1238562Y596838D03*
X1240662D03*
X1238562Y600438D03*
X1240662D03*
X1238562Y611011D03*
X1240662D03*
X1238562Y614611D03*
X1240662D03*
X1290258Y111123D03*
X1292358D03*
X1290258Y114723D03*
X1292358D03*
X1300660Y118235D03*
X1302760D03*
X1290258Y128896D03*
X1292358D03*
X1300660Y132409D03*
X1302760D03*
X1300660Y121835D03*
X1302760D03*
X1290258Y125296D03*
X1292358D03*
X1300660Y136009D03*
X1302760D03*
X1424453Y1491198D03*
X1426553D03*
X1440259Y111123D03*
X1442359D03*
X1440259Y114723D03*
X1442359D03*
X1440259Y125296D03*
X1442359D03*
X1440259Y128896D03*
X1442359D03*
X1450661Y118235D03*
X1452761D03*
X1450661Y132409D03*
X1452761D03*
X1450661Y121835D03*
X1452761D03*
X1450661Y136009D03*
X1452761D03*
X1479398Y1009759D03*
X1477298D03*
X1526958Y390901D03*
X1524858D03*
X1526958Y394501D03*
X1524858D03*
X1518956Y398013D03*
X1516856D03*
X1518956Y401613D03*
X1516856D03*
X1526958Y408674D03*
X1524858D03*
X1526958Y405074D03*
X1524858D03*
X1516556Y415787D03*
X1514456D03*
X1516556Y412187D03*
X1514456D03*
X1526958Y422847D03*
X1524858D03*
X1526958Y419247D03*
X1524858D03*
X1526958Y437021D03*
X1524858D03*
X1526958Y433421D03*
X1524858D03*
X1516556Y429960D03*
X1514456D03*
X1516556Y426360D03*
X1514456D03*
X1516556Y440533D03*
X1514456D03*
X1516556Y444133D03*
X1514456D03*
X1516556Y472887D03*
X1514456D03*
X1516556Y469287D03*
X1514456D03*
X1516556Y487060D03*
X1514456D03*
X1526958Y490573D03*
X1524858D03*
X1526958Y476399D03*
X1524858D03*
X1526958Y479999D03*
X1524858D03*
X1516556Y483460D03*
X1514456D03*
X1526958Y494173D03*
X1524858D03*
X1516556Y517021D03*
X1514456D03*
X1516556Y513421D03*
X1514456D03*
X1526958Y520533D03*
X1524858D03*
X1516556Y531194D03*
X1514456D03*
X1516556Y527594D03*
X1514456D03*
X1526958Y524133D03*
X1524858D03*
X1526958Y534706D03*
X1524858D03*
X1526958Y538306D03*
X1524858D03*
X1542621Y111123D03*
X1544721D03*
X1542621Y114723D03*
X1544721D03*
X1542621Y125296D03*
X1544721D03*
X1542621Y128896D03*
X1544721D03*
X1553023Y118235D03*
X1555123D03*
X1553023Y121835D03*
X1555123D03*
X1553023Y132409D03*
X1555123D03*
X1553023Y136009D03*
X1555123D03*
X1644983Y111123D03*
X1647083D03*
X1644983Y114723D03*
X1647083D03*
X1655385Y118235D03*
X1657485D03*
X1655385Y121835D03*
X1657485D03*
X1655385Y132409D03*
X1657485D03*
X1644983Y125296D03*
X1647083D03*
X1644983Y128896D03*
X1647083D03*
X1655385Y136009D03*
X1657485D03*
X1685247Y467206D03*
X1687347D03*
X1685247Y470806D03*
X1687347D03*
X1685247Y481379D03*
X1687347D03*
X1685247Y484979D03*
X1687347D03*
X1685247Y511339D03*
X1687347D03*
X1685247Y514939D03*
X1687347D03*
X1685247Y525513D03*
X1687347D03*
X1685247Y529113D03*
X1687347D03*
X1685247Y564979D03*
X1687347D03*
X1685247Y561379D03*
X1687347D03*
X1685247Y579152D03*
X1687347D03*
X1685247Y575552D03*
X1687347D03*
X1685247Y593325D03*
X1687347D03*
X1685247Y589725D03*
X1687347D03*
X1685247Y603899D03*
X1687347D03*
X1685247Y607499D03*
X1687347D03*
X1695649Y474318D03*
X1697749D03*
X1695649Y488491D03*
X1697749D03*
X1695649Y477918D03*
X1697749D03*
X1695649Y492091D03*
X1697749D03*
X1695649Y518452D03*
X1697749D03*
X1695649Y522052D03*
X1697749D03*
X1695649Y532625D03*
X1697749D03*
X1695649Y536225D03*
X1697749D03*
X1695649Y568491D03*
X1697749D03*
X1695649Y572091D03*
X1697749D03*
X1695649Y582665D03*
X1697749D03*
X1695649Y586265D03*
X1697749D03*
X1695649Y596838D03*
X1697749D03*
X1695649Y600438D03*
X1697749D03*
X1695649Y614611D03*
X1697749D03*
X1695649Y611011D03*
X1697749D03*
X1747345Y111123D03*
X1749445D03*
X1747345Y114723D03*
X1749445D03*
X1757747Y118235D03*
Y121835D03*
X1747345Y125296D03*
X1749445D03*
X1747345Y128896D03*
X1749445D03*
X1757747Y132409D03*
Y136009D03*
X1759847Y118235D03*
Y121835D03*
Y132409D03*
Y136009D03*
X1818878Y1041550D03*
X1816778D03*
X1819068Y1056783D03*
X1816968D03*
X1818959Y1051219D03*
X1816859D03*
X1818902Y1046756D03*
X1816802D03*
G54D92*
X76388Y670837D03*
X74419D03*
X78356Y678711D03*
X74419D03*
X76388D03*
X80325D03*
Y670837D03*
X78356D03*
G54D185*
X797907Y1443778D03*
Y1461396D03*
X815624Y1443778D03*
X813852D03*
X812080D03*
X810309D03*
X808537D03*
X806765D03*
X801450D03*
X803222D03*
X804994D03*
X799679D03*
X804994Y1461396D03*
X806765D03*
X808537D03*
X810309D03*
X812080D03*
X813852D03*
X815624D03*
X799679D03*
X801450D03*
X803222D03*
X819167Y1443778D03*
X817395D03*
Y1461396D03*
X819167D03*
G54D239*
X1015674Y1396137D03*
X1023862D03*
G54D56*
X39423Y163264D03*
X48085Y167004D03*
X39423Y170744D03*
G54D167*
X537944Y760782D03*
Y767474D03*
X546606D03*
Y760782D03*
X1511365Y894825D03*
X1502703Y888133D03*
Y894825D03*
X1511365Y888133D03*
G54D176*
X714937Y734432D03*
X707063Y738172D03*
X714937Y741912D03*
X893324Y715230D03*
Y722710D03*
X907324Y706030D03*
Y713510D03*
X901198Y718970D03*
X915198Y709770D03*
X1025466Y1373216D03*
Y1380696D03*
X1033340Y1376956D03*
G54D149*
X421962Y875715D03*
G54D29*
X12804Y252371D03*
Y272371D03*
X11394Y284118D03*
X19363Y1464612D03*
X19274Y1496782D03*
X15691Y1501619D03*
X32082Y97667D03*
X27898Y102495D03*
X33811Y241681D03*
X34754Y289272D03*
Y285272D03*
X31458Y527726D03*
Y548726D03*
X33176Y621311D03*
X41024Y177606D03*
X41289Y495982D03*
X52508Y688473D03*
X38214Y1078372D03*
X44869Y1193263D03*
X51908Y1192250D03*
X63287Y483388D03*
X53477Y529269D03*
X60176Y608311D03*
X59233Y843118D03*
X67568Y1071656D03*
Y1075656D03*
Y1067656D03*
Y1083656D03*
Y1087656D03*
Y1079656D03*
X54647Y1124923D03*
X61269Y1209720D03*
X54395Y1213709D03*
X81229Y141247D03*
X77259Y147540D03*
X88208Y141247D03*
X97870Y145768D03*
X87598Y678107D03*
Y682107D03*
X94495Y1021177D03*
X87200Y1021048D03*
X104806Y172665D03*
Y180665D03*
Y176665D03*
Y168665D03*
Y184665D03*
Y188665D03*
X104901Y200864D03*
Y208864D03*
Y212864D03*
Y216864D03*
Y221864D03*
X104898Y225719D03*
X115166Y248371D03*
X111288Y1027361D03*
X130260Y102495D03*
X124689Y134838D03*
Y138838D03*
X134444Y97667D03*
X136173Y241681D03*
X154084Y378600D03*
Y459600D03*
X154172Y554555D03*
X154204Y562567D03*
X154172Y558555D03*
X153484Y631421D03*
X179621Y147540D03*
X186316Y80140D03*
Y76140D03*
Y84140D03*
X197027Y76587D03*
Y72587D03*
X183591Y141247D03*
X190570D03*
X200232Y145768D03*
X207168Y172665D03*
Y180665D03*
Y176665D03*
Y168665D03*
Y184665D03*
Y188665D03*
X207263Y208864D03*
Y212864D03*
Y216864D03*
Y221864D03*
X207260Y225719D03*
X227051Y134838D03*
Y138838D03*
X217528Y248371D03*
X221284Y462800D03*
X221484Y549800D03*
X230084Y549700D03*
X221484Y562800D03*
Y558800D03*
X221884Y621400D03*
Y625400D03*
X230521Y1494361D03*
X230527Y1482442D03*
Y1490442D03*
X222999Y1515642D03*
X222699Y1522542D03*
X236806Y97667D03*
X232622Y102495D03*
X238535Y241681D03*
X233748Y388718D03*
X232532Y1514578D03*
Y1526578D03*
Y1522578D03*
X252184Y445873D03*
Y449873D03*
Y462859D03*
X251369Y546712D03*
X251749Y675889D03*
X249550Y1514169D03*
Y1510142D03*
X286853Y27156D03*
X288678Y84140D03*
Y76140D03*
Y80140D03*
X281983Y147540D03*
X292932Y141247D03*
X285953D03*
X289999Y317873D03*
X299389Y76587D03*
Y72587D03*
X302594Y145768D03*
X309530Y180665D03*
Y172665D03*
Y176665D03*
Y168665D03*
Y184665D03*
X302575Y196286D03*
X309530Y188665D03*
X309625Y208864D03*
Y212864D03*
Y216864D03*
Y221864D03*
X309622Y225719D03*
X328390Y15806D03*
Y19806D03*
Y11806D03*
Y27806D03*
Y23806D03*
Y31806D03*
X319890Y248371D03*
X320392Y350850D03*
X318569Y541912D03*
Y622912D03*
X339168Y97667D03*
X334984Y102495D03*
X329413Y134838D03*
Y138838D03*
X340897Y241681D03*
X350509Y454334D03*
X353840Y1171120D03*
X364460Y406532D03*
X364804Y447357D03*
X373508Y458309D03*
Y454309D03*
Y462309D03*
X377384Y786400D03*
X375916Y939976D03*
Y943812D03*
Y947812D03*
X391040Y84140D03*
Y80140D03*
Y76140D03*
X389898Y401923D03*
X391152Y466409D03*
Y474382D03*
Y487382D03*
Y482382D03*
Y478382D03*
X379084Y750000D03*
X392654Y864408D03*
X387501Y1539700D03*
Y1543700D03*
Y1551700D03*
Y1559700D03*
X404568Y196620D03*
X402785Y471560D03*
Y475560D03*
X403684Y789000D03*
X401893Y860535D03*
Y864409D03*
X401835Y868286D03*
X399809Y948536D03*
X400004Y971780D03*
X407599Y1442942D03*
X419887Y26534D03*
X419982Y22627D03*
X419959Y30483D03*
X411892Y180665D03*
Y172665D03*
Y176665D03*
Y168665D03*
Y184665D03*
Y188665D03*
X411987Y208864D03*
Y212864D03*
Y216864D03*
Y221864D03*
X411984Y225719D03*
X419922Y834800D03*
X412174Y1098826D03*
X420188Y1523296D03*
X435954Y141247D03*
X431984Y147540D03*
X437575Y620456D03*
X427708Y1546372D03*
X434708Y1550158D03*
X452595Y145768D03*
X442933Y141247D03*
X443657Y435101D03*
Y439101D03*
Y443101D03*
Y447101D03*
Y452601D03*
X456603Y468809D03*
X446121Y620456D03*
X453461Y634279D03*
X446492Y640876D03*
X453456Y642588D03*
X445320Y711199D03*
X448575Y1026266D03*
X457075Y1024766D03*
X444302Y1098826D03*
X469891Y248371D03*
X470875Y461864D03*
X465887Y491669D03*
Y499669D03*
Y503669D03*
Y507669D03*
Y512669D03*
X489169Y97667D03*
X484985Y102495D03*
X479414Y134838D03*
Y138838D03*
X490898Y241681D03*
X478291Y347995D03*
Y352495D03*
X478394Y360089D03*
X488291Y347995D03*
Y352495D03*
X488394Y360089D03*
X478394Y364589D03*
Y369089D03*
Y373589D03*
X488394Y364589D03*
Y369089D03*
Y373589D03*
X478394Y378089D03*
Y382589D03*
Y387089D03*
Y391589D03*
X488394Y378089D03*
Y382589D03*
X479602Y468784D03*
Y472784D03*
Y476784D03*
X488544Y527726D03*
Y548726D03*
X490262Y621311D03*
X481890Y648968D03*
X477761Y1098826D03*
X498375Y495982D03*
X502664Y655149D03*
X498418Y685006D03*
Y689006D03*
Y697006D03*
Y693006D03*
X504075Y1000766D03*
Y1016266D03*
Y1012266D03*
X520373Y483388D03*
X510563Y529269D03*
X517262Y608311D03*
X509225Y844649D03*
X513754Y969933D03*
X513706Y973885D03*
X509889Y1098826D03*
X538316Y141247D03*
X534346Y147540D03*
X538670Y381723D03*
X535051Y394309D03*
X528164Y1103717D03*
X541041Y80140D03*
Y76140D03*
Y84140D03*
X551752Y76587D03*
Y72587D03*
X545295Y141247D03*
X554957Y145768D03*
X548670Y386223D03*
Y390723D03*
X555665Y738558D03*
X547686Y746514D03*
X542508Y779889D03*
X551582Y1021177D03*
X544287Y1021048D03*
X561893Y180665D03*
Y172665D03*
Y176665D03*
Y168665D03*
Y184665D03*
Y188665D03*
X561988Y208864D03*
Y212864D03*
Y216864D03*
Y221864D03*
X561985Y225719D03*
X572253Y248371D03*
X570504Y743122D03*
X564271Y754992D03*
X567829Y1026933D03*
X587347Y102495D03*
X581776Y134838D03*
Y138838D03*
X575098Y776700D03*
Y780700D03*
X576287Y957207D03*
X588416Y1497687D03*
Y1493687D03*
X585199Y1514042D03*
X588416Y1501687D03*
X584450Y1505724D03*
X575241Y1526224D03*
X591531Y97667D03*
X593260Y241681D03*
X611170Y378600D03*
Y459600D03*
X611258Y554555D03*
Y558555D03*
X611290Y562567D03*
X610570Y631421D03*
X636708Y147540D03*
X643403Y76140D03*
Y84140D03*
Y80140D03*
X647657Y141247D03*
X640678D03*
X654114Y76587D03*
Y72587D03*
X657319Y145768D03*
X664255Y180665D03*
Y172665D03*
Y176665D03*
Y168665D03*
Y184665D03*
Y188665D03*
X664350Y208864D03*
Y212864D03*
Y216864D03*
Y221864D03*
X664347Y225719D03*
X661026Y660402D03*
X665047Y689694D03*
X669830Y763137D03*
X656330Y759137D03*
Y767137D03*
Y763137D03*
X669830Y779137D03*
Y771137D03*
X656330Y779137D03*
Y775137D03*
Y771137D03*
Y783137D03*
Y787137D03*
X669830D03*
X684138Y134838D03*
Y138838D03*
X674615Y248371D03*
X678370Y462800D03*
X678570Y549800D03*
X678970Y621400D03*
Y625400D03*
X693893Y97667D03*
X689709Y102495D03*
X695622Y241681D03*
X690834Y388718D03*
X687170Y549700D03*
X709270Y445873D03*
Y449873D03*
Y462859D03*
X708455Y546712D03*
X708835Y675889D03*
X707069Y709303D03*
X710074Y728050D03*
X720273Y691609D03*
X727830Y760137D03*
X745765Y84140D03*
Y76140D03*
Y80140D03*
X750019Y141247D03*
X743040D03*
X739070Y147540D03*
X747085Y317873D03*
X739214Y1622015D03*
X756476Y72562D03*
Y76587D03*
X759681Y145768D03*
X766617Y180665D03*
Y172665D03*
Y176665D03*
Y168665D03*
Y184665D03*
Y188665D03*
X759293Y196620D03*
X766712Y200864D03*
Y208864D03*
Y212864D03*
Y216864D03*
Y221864D03*
X776977Y248371D03*
X777478Y350850D03*
X775655Y541912D03*
Y622912D03*
X783245Y1443445D03*
X783233Y1435432D03*
X774694Y1454305D03*
X796255Y97667D03*
X792071Y102495D03*
X786500Y134838D03*
Y138838D03*
X797984Y241681D03*
X791608Y442510D03*
Y450510D03*
Y446510D03*
X814961Y305368D03*
Y309368D03*
X806961Y305368D03*
Y309368D03*
X814961Y313368D03*
X806961D03*
X814961Y317368D03*
Y321368D03*
Y325368D03*
X806961Y317368D03*
Y321368D03*
Y325368D03*
X814961Y329368D03*
X806961D03*
X814961Y333368D03*
X806961Y337368D03*
Y333368D03*
X814961Y346368D03*
X806961D03*
X814961Y350368D03*
X814958Y354741D03*
X807595Y448334D03*
X811808Y840919D03*
X810927Y1171120D03*
X810113Y1404769D03*
X807978Y1484354D03*
X821867Y441389D03*
X830594Y456309D03*
Y448309D03*
Y452309D03*
X820047Y742502D03*
X829984Y766500D03*
Y784500D03*
Y802500D03*
Y820500D03*
X823461Y933571D03*
X828894Y1462461D03*
X848127Y76140D03*
Y80140D03*
Y84140D03*
X848238Y461382D03*
Y469382D03*
Y473382D03*
Y482382D03*
Y477382D03*
X841326Y827459D03*
X843748Y843790D03*
Y847490D03*
X845793Y835459D03*
Y851459D03*
X843221Y863413D03*
X843348Y855395D03*
X843221Y867413D03*
X834188Y1440849D03*
Y1448849D03*
X845228Y1461959D03*
X834206Y1454525D03*
X858838Y76587D03*
Y72587D03*
X861655Y196620D03*
X853458Y414760D03*
X864715Y414533D03*
X853458Y418760D03*
X863745Y701170D03*
Y709170D03*
X863545Y722670D03*
X864484Y756000D03*
Y760000D03*
Y764000D03*
Y778000D03*
Y782000D03*
Y774000D03*
Y792000D03*
Y796000D03*
Y800000D03*
Y814000D03*
Y810000D03*
X856815Y827468D03*
X864484Y818000D03*
X849124Y827686D03*
X856743Y835459D03*
X868979Y180665D03*
Y172665D03*
Y176665D03*
Y168665D03*
Y184665D03*
Y188665D03*
X869074Y208864D03*
Y212864D03*
Y216864D03*
Y221864D03*
X875461Y309368D03*
Y305368D03*
Y313368D03*
Y325368D03*
Y321368D03*
Y317368D03*
X865229Y340454D03*
X875461Y329368D03*
Y333368D03*
X866938Y487303D03*
Y483303D03*
X872397Y549771D03*
X872552Y562703D03*
Y570703D03*
Y566703D03*
Y578703D03*
Y582828D03*
X876212Y794227D03*
X893040Y141247D03*
X889070Y147540D03*
X883461Y341342D03*
X891371Y341537D03*
X883461Y345342D03*
X885224Y415264D03*
X881745Y694970D03*
Y690970D03*
X886745Y727178D03*
Y722770D03*
X884904Y1087375D03*
X888559Y1202266D03*
X895598Y1201253D03*
X886728Y1444859D03*
Y1460859D03*
Y1476859D03*
Y1468859D03*
X900019Y141247D03*
X909681Y145768D03*
X902244Y358369D03*
Y354369D03*
Y374369D03*
Y366369D03*
X909945Y687770D03*
Y691770D03*
X910745Y718970D03*
X906818Y948607D03*
X901337Y1133926D03*
X904959Y1218723D03*
X898085Y1222712D03*
X920051Y310985D03*
X920870Y547348D03*
X929136Y557641D03*
Y569578D03*
Y573578D03*
Y577578D03*
Y581578D03*
X914258Y1076659D03*
Y1080659D03*
Y1084659D03*
Y1088659D03*
Y1092659D03*
Y1096659D03*
X925324Y1449536D03*
X924688Y1468100D03*
X942071Y102495D03*
X936500Y134838D03*
Y138838D03*
X938983Y451442D03*
Y455442D03*
Y459442D03*
Y463442D03*
Y468942D03*
X945631Y527726D03*
Y548726D03*
X943570Y792330D03*
X930690Y798271D03*
X939312Y891216D03*
X946255Y97667D03*
X948650Y226852D03*
X955462Y495982D03*
X947349Y621311D03*
X952512Y782467D03*
X952668Y799233D03*
X952437Y786366D03*
X947611Y864862D03*
X947548Y883146D03*
X955048Y899890D03*
X948881Y1087375D03*
X952536Y1202122D03*
X959575Y1201253D03*
X962062Y1222712D03*
X977460Y483388D03*
X967650Y529269D03*
X974349Y608311D03*
X976569Y831799D03*
X976575Y827907D03*
X978235Y1076659D03*
Y1088659D03*
Y1084659D03*
Y1080659D03*
Y1092659D03*
Y1096659D03*
X965314Y1133926D03*
X968936Y1218723D03*
X991432Y147540D03*
X982609Y328472D03*
Y335472D03*
X984687Y825159D03*
Y829159D03*
Y833159D03*
X998127Y84140D03*
Y76140D03*
Y80140D03*
X1008838Y72587D03*
Y76587D03*
X1002381Y141247D03*
X995402D03*
X997661Y314653D03*
X1008668Y1021177D03*
X1012043Y145768D03*
X1018979Y180665D03*
Y172665D03*
Y176665D03*
Y168665D03*
Y184665D03*
Y188665D03*
X1019074Y200864D03*
Y208864D03*
Y212864D03*
Y216864D03*
Y221864D03*
X1019071Y225719D03*
X1019379Y754546D03*
Y771974D03*
Y775974D03*
X1019342Y815046D03*
X1019379Y825981D03*
Y818974D03*
X1018187Y833659D03*
X1018687Y848680D03*
X1017903Y954222D03*
X1024915Y1026933D03*
X1013988Y1357938D03*
X1013976Y1368835D03*
X1013971Y1380797D03*
X1038862Y134838D03*
Y138838D03*
X1029339Y248371D03*
X1043147Y1309487D03*
X1038924Y1357372D03*
X1038867Y1361287D03*
X1038875Y1365009D03*
X1048617Y97667D03*
X1044433Y102495D03*
X1050346Y241681D03*
X1058709Y310574D03*
X1058596Y343509D03*
X1058188Y356151D03*
Y368276D03*
X1057471Y1311436D03*
X1057517Y1315605D03*
X1051420Y1323611D03*
X1068257Y378600D03*
Y459600D03*
X1068345Y554555D03*
Y558555D03*
X1068377Y562567D03*
X1067657Y631421D03*
X1061319Y1456486D03*
X1100489Y76140D03*
Y80140D03*
Y84140D03*
X1093794Y147540D03*
X1104743Y141247D03*
X1097764D03*
X1111200Y72587D03*
Y76587D03*
X1114405Y145768D03*
X1121341Y180665D03*
Y172665D03*
Y176665D03*
Y168665D03*
Y188665D03*
Y184665D03*
X1121436Y200864D03*
Y208864D03*
Y212864D03*
Y216864D03*
Y221864D03*
X1121433Y225719D03*
X1118113Y660402D03*
X1122134Y689694D03*
X1131701Y248371D03*
X1135457Y462800D03*
X1135657Y549800D03*
X1136057Y621400D03*
Y625400D03*
X1150979Y97667D03*
X1146795Y102495D03*
X1141224Y134838D03*
Y138838D03*
X1152708Y241681D03*
X1147921Y388718D03*
X1144257Y549700D03*
X1166357Y445873D03*
Y449873D03*
Y462859D03*
X1165542Y546712D03*
X1165922Y675889D03*
X1182820Y339103D03*
X1202851Y84140D03*
Y76140D03*
Y80140D03*
X1200126Y141247D03*
X1196156Y147540D03*
X1204172Y317873D03*
X1213562Y72587D03*
Y76587D03*
X1216767Y145768D03*
X1207105Y141247D03*
X1216379Y196620D03*
X1223703Y180665D03*
Y172665D03*
Y176665D03*
Y168665D03*
Y184665D03*
Y188665D03*
X1223798Y200864D03*
Y208864D03*
Y212864D03*
Y216864D03*
Y221864D03*
X1223795Y225719D03*
X1234063Y248371D03*
X1234565Y350850D03*
X1232742Y541912D03*
Y622912D03*
X1253341Y97667D03*
X1249157Y102495D03*
X1243586Y134838D03*
Y138838D03*
X1250599Y1531342D03*
X1255070Y241681D03*
X1261984Y327000D03*
X1264682Y454334D03*
X1268013Y1171120D03*
X1260117Y1519459D03*
X1278633Y406532D03*
X1278977Y447357D03*
X1284998Y776576D03*
Y772576D03*
Y784576D03*
X1280984Y914000D03*
X1271774Y914949D03*
Y918956D03*
X1287681Y458309D03*
Y454309D03*
Y462309D03*
X1298550Y796321D03*
X1290984Y827500D03*
Y831500D03*
Y823500D03*
Y835500D03*
Y859500D03*
Y855500D03*
X1290979Y877783D03*
Y881783D03*
Y889767D03*
X1293984Y919500D03*
X1305213Y84140D03*
Y76140D03*
Y80140D03*
X1318741Y196620D03*
X1304071Y401923D03*
X1305325Y466409D03*
X1316958Y471560D03*
X1305325Y474382D03*
Y487382D03*
Y482382D03*
X1316958Y475560D03*
X1305325Y478382D03*
X1334060Y26534D03*
X1334132Y30483D03*
X1334155Y22627D03*
X1326065Y168665D03*
Y176665D03*
Y172665D03*
Y180665D03*
Y184665D03*
Y188665D03*
X1326160Y200864D03*
Y208864D03*
Y212864D03*
Y216864D03*
Y221864D03*
X1326157Y225719D03*
X1324484Y558500D03*
Y562500D03*
Y574500D03*
Y578500D03*
X1332484Y594500D03*
X1324484D03*
Y605000D03*
Y621000D03*
Y609000D03*
Y625000D03*
X1332484Y641000D03*
X1324484Y653500D03*
Y641000D03*
Y649500D03*
Y665500D03*
Y669500D03*
Y685500D03*
X1332484D03*
X1324484Y700500D03*
Y696500D03*
Y716500D03*
Y712500D03*
Y732500D03*
X1332484D03*
X1326348Y1098826D03*
X1350127Y141247D03*
X1346157Y147540D03*
X1342277Y773675D03*
X1357106Y141247D03*
X1366768Y145768D03*
X1357830Y435101D03*
Y439101D03*
Y443101D03*
Y447101D03*
Y452601D03*
X1362749Y1026266D03*
X1358476Y1098826D03*
X1384064Y248371D03*
X1380935Y320871D03*
Y325371D03*
Y343371D03*
Y338871D03*
Y334371D03*
Y329871D03*
Y347871D03*
Y361371D03*
Y356871D03*
Y352371D03*
X1371249Y1024766D03*
X1399158Y102495D03*
X1393587Y134838D03*
Y138838D03*
X1390935Y320871D03*
Y325371D03*
Y329871D03*
Y343371D03*
Y338871D03*
Y334371D03*
Y352371D03*
Y347871D03*
X1388225Y569000D03*
Y565000D03*
Y561000D03*
X1388571Y581317D03*
X1388225Y615500D03*
Y611500D03*
Y607500D03*
X1388570Y623692D03*
X1394484Y652000D03*
Y656000D03*
Y660000D03*
X1393984Y675000D03*
X1394484Y699000D03*
Y703000D03*
Y707000D03*
X1393984Y722000D03*
X1391935Y1098826D03*
X1403342Y97667D03*
X1405071Y241681D03*
X1412549Y495982D03*
X1402718Y527726D03*
Y548726D03*
X1404436Y621311D03*
X1402484Y656000D03*
X1401984Y675000D03*
X1415484Y681000D03*
Y685000D03*
X1402484Y699000D03*
X1415484Y697000D03*
Y701000D03*
Y717000D03*
X1401984Y722000D03*
X1415484Y725000D03*
Y729000D03*
Y741000D03*
Y745000D03*
Y761000D03*
X1410984Y844000D03*
Y860000D03*
Y876000D03*
Y872000D03*
Y888000D03*
Y892000D03*
Y904000D03*
X1410798Y911137D03*
Y915186D03*
X1414052Y988403D03*
X1424737Y529269D03*
X1431436Y608311D03*
X1423484Y717000D03*
X1432484Y766500D03*
X1423484Y761000D03*
X1432484Y770500D03*
Y782500D03*
Y786500D03*
Y802500D03*
Y814500D03*
Y810500D03*
Y830500D03*
Y826500D03*
Y846500D03*
X1428017Y943390D03*
X1418249Y1000766D03*
Y1016266D03*
Y1012266D03*
X1424063Y1098826D03*
X1426461Y1498545D03*
X1429423Y1520364D03*
X1419648Y1548217D03*
X1419006Y1569486D03*
X1448519Y147540D03*
X1437667Y359673D03*
X1434547Y483388D03*
X1440484Y802500D03*
Y846500D03*
X1438940Y951902D03*
X1443096Y1001518D03*
X1435578Y1001519D03*
X1442338Y1103717D03*
X1454569Y26393D03*
Y30393D03*
X1454285Y39193D03*
X1455214Y84140D03*
Y76140D03*
Y80140D03*
X1452489Y141247D03*
X1459468D03*
X1456191Y356861D03*
X1461680Y928177D03*
X1464832Y932887D03*
X1458460Y1021048D03*
X1465755Y1021177D03*
X1465925Y72587D03*
Y76587D03*
X1469130Y145768D03*
X1476066Y168665D03*
Y176665D03*
Y172665D03*
Y180665D03*
Y184665D03*
Y188665D03*
X1476161Y200864D03*
Y208864D03*
Y212864D03*
Y216864D03*
Y221864D03*
X1476158Y225719D03*
X1469684Y939543D03*
X1469648Y943496D03*
X1473984Y972000D03*
X1482002Y1026933D03*
X1496106Y19043D03*
Y15043D03*
Y23043D03*
Y31043D03*
Y27043D03*
Y35043D03*
X1495949Y138838D03*
Y134838D03*
X1486426Y248371D03*
X1493030Y322700D03*
X1483030Y327200D03*
Y322700D03*
X1493030Y327200D03*
Y331700D03*
Y340700D03*
X1483030D03*
Y331700D03*
X1493030Y349700D03*
X1483030Y345200D03*
Y358700D03*
Y354200D03*
Y349700D03*
X1493030Y345200D03*
X1492997Y368576D03*
X1484984Y681630D03*
Y677630D03*
Y697630D03*
Y689630D03*
Y693630D03*
X1492984Y706500D03*
X1484984D03*
X1485484Y731500D03*
Y723500D03*
Y735500D03*
X1484984Y750500D03*
X1485484Y743500D03*
Y739500D03*
X1492984Y750500D03*
X1505704Y97667D03*
X1501520Y102495D03*
X1507433Y241681D03*
X1502484Y765000D03*
Y781000D03*
Y773000D03*
Y777000D03*
X1509984Y792000D03*
X1501984D03*
X1502484Y785000D03*
Y809000D03*
Y817000D03*
Y825000D03*
Y821000D03*
Y829000D03*
X1509984Y836000D03*
X1501984D03*
X1507267Y907240D03*
X1525344Y378600D03*
Y459600D03*
X1525432Y554555D03*
Y558555D03*
X1525464Y562567D03*
X1524744Y631421D03*
X1541192Y352053D03*
X1557576Y84140D03*
Y76140D03*
Y80140D03*
X1550881Y147540D03*
X1561830Y141247D03*
X1554851D03*
X1551363Y352363D03*
X1554198Y956600D03*
X1568287Y72587D03*
Y76587D03*
X1571492Y145768D03*
X1578428Y168665D03*
Y176665D03*
Y172665D03*
Y180665D03*
Y184665D03*
Y188665D03*
X1578523Y200864D03*
Y208864D03*
Y212864D03*
Y216864D03*
Y221864D03*
X1578520Y225719D03*
X1574684Y336200D03*
X1575200Y660402D03*
X1579221Y689694D03*
X1588788Y248371D03*
X1592544Y462800D03*
X1592744Y549800D03*
Y558800D03*
Y562800D03*
X1593144Y621400D03*
Y625400D03*
X1593766Y1446488D03*
X1608066Y97667D03*
X1603882Y102495D03*
X1598311Y134838D03*
Y138838D03*
X1609795Y241681D03*
X1605008Y388718D03*
X1601344Y549700D03*
X1604596Y1471973D03*
X1606587Y1539334D03*
X1606575Y1543373D03*
X1619781Y344252D03*
Y340252D03*
X1623444Y445873D03*
Y449873D03*
Y462859D03*
X1622629Y546712D03*
X1623009Y675889D03*
X1659938Y84140D03*
Y80140D03*
Y76140D03*
X1657213Y141247D03*
X1653243Y147540D03*
X1670649Y72587D03*
Y76587D03*
X1664192Y141247D03*
X1673854Y145768D03*
X1673466Y196620D03*
X1661259Y317873D03*
X1680790Y168665D03*
Y176665D03*
Y172665D03*
Y180665D03*
Y188665D03*
Y184665D03*
X1680885Y200864D03*
Y208864D03*
Y212864D03*
Y216864D03*
Y221864D03*
X1680882Y225719D03*
X1691150Y248371D03*
X1691652Y350850D03*
X1689829Y541912D03*
Y622912D03*
X1706244Y102495D03*
X1700673Y134838D03*
Y138838D03*
X1710428Y97667D03*
X1712157Y241681D03*
X1721769Y454334D03*
X1725100Y1171120D03*
X1735720Y406532D03*
X1736064Y447357D03*
X1744768Y458309D03*
Y454309D03*
Y462309D03*
X1753092Y884649D03*
X1752326Y915451D03*
X1757184Y931100D03*
X1762300Y80140D03*
Y76140D03*
Y84140D03*
X1773011Y72587D03*
Y76587D03*
X1761158Y401923D03*
X1762412Y466409D03*
X1774045Y467560D03*
X1762412Y474382D03*
Y487382D03*
Y482382D03*
X1774045Y475560D03*
X1762412Y478382D03*
X1763991Y824383D03*
Y820883D03*
X1783152Y168665D03*
Y176665D03*
Y172665D03*
Y180665D03*
X1775828Y196620D03*
X1783152Y184665D03*
Y188665D03*
X1783247Y200864D03*
Y208864D03*
Y212864D03*
Y216864D03*
Y221864D03*
X1783244Y225719D03*
X1781452Y924546D03*
X1786114Y1462700D03*
X1792672Y196531D03*
X1792547Y985060D03*
X1792861Y1087861D03*
X1803555Y1201739D03*
X1796516Y1202756D03*
X1806042Y1223198D03*
X1803005Y1444543D03*
X1802882Y1476733D03*
X1814917Y435101D03*
Y439101D03*
Y443101D03*
Y447101D03*
Y452601D03*
X1822215Y1077145D03*
Y1081145D03*
Y1089145D03*
Y1085145D03*
Y1093145D03*
Y1097145D03*
X1813294Y1134412D03*
X1812916Y1219209D03*
G54D74*
X46348Y1727941D03*
Y1737941D03*
X46248Y1760941D03*
Y1750941D03*
X46348Y1773941D03*
Y1783941D03*
X46248Y1806941D03*
Y1796941D03*
X318448Y1727941D03*
Y1737941D03*
Y1750941D03*
Y1760941D03*
Y1773941D03*
Y1783941D03*
X318348Y1796941D03*
Y1806941D03*
X333286Y1728583D03*
Y1738583D03*
X333112Y1751624D03*
X333212Y1774624D03*
X333112Y1761624D03*
X333212Y1784624D03*
Y1797624D03*
Y1807624D03*
X605386Y1728583D03*
Y1738583D03*
X605312Y1751624D03*
Y1774624D03*
Y1761624D03*
Y1784624D03*
Y1807624D03*
Y1797624D03*
X620083Y1728286D03*
Y1738286D03*
X619861Y1751765D03*
X619711Y1775438D03*
X619861Y1761765D03*
X619711Y1785438D03*
X619475Y1798845D03*
Y1808845D03*
X892183Y1728286D03*
Y1738286D03*
X891911Y1751765D03*
X891761Y1775438D03*
X891911Y1761765D03*
X891761Y1785438D03*
X891525Y1808845D03*
Y1798845D03*
X907279Y1738990D03*
Y1728990D03*
X907163Y1752566D03*
Y1762566D03*
X907073Y1776014D03*
Y1786014D03*
X907166Y1800435D03*
Y1810435D03*
X1179329Y1728990D03*
Y1738990D03*
X1179263Y1752566D03*
Y1762566D03*
X1179123Y1776014D03*
Y1786014D03*
X1179216Y1800435D03*
Y1810435D03*
G54D194*
X843012Y1592787D03*
Y1602787D03*
Y1612787D03*
Y1622787D03*
X853012Y1592787D03*
Y1602787D03*
Y1612787D03*
Y1622787D03*
X878012Y1592787D03*
Y1602787D03*
Y1612787D03*
Y1622787D03*
X888012Y1592787D03*
Y1602787D03*
Y1612787D03*
Y1622787D03*
X913012Y1592787D03*
Y1602787D03*
Y1612787D03*
Y1622787D03*
X923012Y1592787D03*
Y1602787D03*
Y1612787D03*
Y1622787D03*
X948012Y1592787D03*
Y1602787D03*
Y1612787D03*
Y1622787D03*
X958012Y1592787D03*
Y1602787D03*
Y1612787D03*
Y1622787D03*
X983012Y1592787D03*
X993012D03*
X983012Y1602787D03*
Y1612787D03*
X993012Y1602787D03*
Y1612787D03*
X983012Y1622787D03*
X993012D03*
X1018012Y1592787D03*
X1028012D03*
X1018012Y1602787D03*
Y1612787D03*
X1028012Y1602787D03*
Y1612787D03*
X1018012Y1622787D03*
G54D248*
X1236871Y1715189D03*
Y1744208D03*
X1236864Y1773377D03*
X1235371Y1802909D03*
X1250055Y1710189D03*
Y1720189D03*
Y1739208D03*
Y1749208D03*
X1250048Y1768377D03*
Y1778377D03*
X1248555Y1797909D03*
Y1807909D03*
X1734069Y1710189D03*
Y1720189D03*
Y1739208D03*
Y1749208D03*
X1734062Y1768377D03*
Y1778377D03*
X1734069Y1797909D03*
Y1807909D03*
X1747253Y1715189D03*
Y1744208D03*
X1747246Y1773377D03*
X1747253Y1802909D03*
G54D158*
X438244Y1059069D03*
Y1080329D03*
X471246Y1059069D03*
Y1080329D03*
X1352418Y1059069D03*
Y1080329D03*
X1385420Y1059069D03*
Y1080329D03*
G54D47*
X34731Y1206917D03*
X427063Y634044D03*
X878421Y1215920D03*
X942398D03*
X1786378Y1216406D03*
G54D168*
X526897Y797102D03*
Y799071D03*
Y812850D03*
Y804976D03*
Y803008D03*
Y801039D03*
Y806945D03*
Y808913D03*
Y810882D03*
Y814819D03*
Y826630D03*
Y824661D03*
Y822693D03*
Y816787D03*
Y818756D03*
Y820724D03*
X571975Y799071D03*
Y797102D03*
Y803008D03*
Y812850D03*
Y814819D03*
Y810882D03*
Y808913D03*
Y806945D03*
Y804976D03*
Y801039D03*
Y824661D03*
Y826630D03*
Y822693D03*
Y820724D03*
Y818756D03*
Y816787D03*
X1491656Y924453D03*
Y926422D03*
Y928390D03*
Y940201D03*
Y932327D03*
Y930359D03*
Y934296D03*
Y936264D03*
Y938233D03*
Y942170D03*
Y944138D03*
Y953981D03*
Y952012D03*
Y950044D03*
Y946107D03*
Y948075D03*
X1536734Y928390D03*
Y926422D03*
Y924453D03*
Y930359D03*
Y940201D03*
Y944138D03*
Y942170D03*
Y938233D03*
Y936264D03*
Y934296D03*
Y932327D03*
Y952012D03*
Y953981D03*
Y950044D03*
Y948075D03*
Y946107D03*
G54D48*
X34731Y1199141D03*
X45755Y1212527D03*
X410938Y870105D03*
X421962Y883491D03*
X427063Y626268D03*
X438087Y639654D03*
X878421Y1208144D03*
X889445Y1221530D03*
X942398Y1208144D03*
X953422Y1221530D03*
X1786378Y1208630D03*
X1797402Y1222016D03*
G54D93*
X77372Y674774D03*
G54D195*
X863687Y1443780D03*
X861718D03*
X859750D03*
Y1461398D03*
X861718D03*
X863687D03*
X869592Y1443780D03*
X867624D03*
X865655D03*
Y1461398D03*
X867624D03*
X869592D03*
X911592Y1443780D03*
X909624D03*
X907655D03*
X905687D03*
X903718D03*
X901750D03*
Y1461398D03*
X903718D03*
X905687D03*
X907655D03*
X909624D03*
X911592D03*
G54D66*
X49754Y1079154D03*
X51723D03*
X49754Y1090178D03*
X51723D03*
X55660D03*
Y1079154D03*
X53691D03*
Y1090178D03*
X76452Y582336D03*
X70546D03*
X74483D03*
X72515D03*
X70546Y593360D03*
X72515D03*
X76452D03*
X74483D03*
X86992Y177338D03*
X92898D03*
X90929D03*
X88961D03*
X92898Y188362D03*
X86992D03*
X88961D03*
X90929D03*
X189354Y177338D03*
X195260D03*
X193291D03*
X191323D03*
X195260Y188362D03*
X189354D03*
X191323D03*
X193291D03*
X291716Y177338D03*
X295653D03*
X293685D03*
X291716Y188362D03*
X293685D03*
X295653D03*
X297622Y177338D03*
Y188362D03*
X360480Y389013D03*
X356543D03*
X358512D03*
X356543Y400037D03*
X358512D03*
X360480D03*
X362449Y389013D03*
Y400037D03*
X384856Y952115D03*
X390762D03*
X388793D03*
X386825D03*
X390762Y963139D03*
X384856D03*
X386825D03*
X388793D03*
X394078Y177338D03*
X399984D03*
X398015D03*
X396047D03*
X399984Y188362D03*
X394078D03*
X396047D03*
X398015D03*
X409101Y1110233D03*
X419731D03*
X425046D03*
X416187D03*
X412644D03*
X421502D03*
X423274D03*
X417959D03*
X410872D03*
X414416D03*
X441229D03*
X451859D03*
X457174D03*
X448315D03*
X444772D03*
X453630D03*
X455402D03*
X450087D03*
X443000D03*
X446544D03*
X474688D03*
X485318D03*
X490633D03*
X481774D03*
X478231D03*
X487089D03*
X488861D03*
X483546D03*
X476459D03*
X480003D03*
X506816D03*
X517446D03*
X522761D03*
X513902D03*
X510359D03*
X519217D03*
X520989D03*
X515674D03*
X508587D03*
X512131D03*
X533538Y582336D03*
X527632D03*
X531569D03*
X529601D03*
X527632Y593360D03*
X529601D03*
X533538D03*
X531569D03*
X544079Y177338D03*
X549985D03*
X548016D03*
X546048D03*
X549985Y188362D03*
X544079D03*
X546048D03*
X548016D03*
X646441Y177338D03*
X652347D03*
X650378D03*
X648410D03*
X652347Y188362D03*
X646441D03*
X648410D03*
X650378D03*
X748803Y177338D03*
Y188362D03*
X754709Y177338D03*
X752740D03*
X750772D03*
X754709Y188362D03*
X750772D03*
X752740D03*
X851165Y177338D03*
X857071D03*
X855102D03*
X853134D03*
X857071Y188362D03*
X851165D03*
X853134D03*
X855102D03*
X857298Y408038D03*
X863204D03*
X859267D03*
X863204Y397014D03*
X861235Y408038D03*
Y397014D03*
X857298D03*
X859267D03*
X896444Y1088157D03*
Y1099181D03*
X902350Y1088157D03*
X900381D03*
X898413D03*
Y1099181D03*
X900381D03*
X902350D03*
X960421Y1088157D03*
Y1099181D03*
X966327Y1088157D03*
X964358D03*
X962390D03*
Y1099181D03*
X964358D03*
X966327D03*
X990625Y582336D03*
X984719D03*
X988656D03*
X986688D03*
X984719Y593360D03*
X986688D03*
X990625D03*
X988656D03*
X1001165Y177338D03*
X1007071D03*
X1005102D03*
X1003134D03*
X1007071Y188362D03*
X1001165D03*
X1003134D03*
X1005102D03*
X1103527Y177338D03*
X1107464D03*
X1105496D03*
X1103527Y188362D03*
X1105496D03*
X1107464D03*
X1109433Y177338D03*
Y188362D03*
X1205889Y177338D03*
X1211795D03*
X1209826D03*
X1207858D03*
X1211795Y188362D03*
X1205889D03*
X1207858D03*
X1209826D03*
X1276622Y389013D03*
X1274653D03*
X1270716D03*
X1272685D03*
X1270716Y400037D03*
X1276622D03*
X1272685D03*
X1274653D03*
X1308251Y177338D03*
X1314157D03*
X1312188D03*
X1310220D03*
X1314157Y188362D03*
X1308251D03*
X1310220D03*
X1312188D03*
X1323275Y1110233D03*
X1333905D03*
X1330361D03*
X1326818D03*
X1332133D03*
X1325046D03*
X1328590D03*
X1339220D03*
X1335676D03*
X1337448D03*
X1355403D03*
X1366033D03*
X1362489D03*
X1358946D03*
X1367804D03*
X1364261D03*
X1357174D03*
X1360718D03*
X1371348D03*
X1369576D03*
X1388862D03*
X1399492D03*
X1395948D03*
X1392405D03*
X1397720D03*
X1390633D03*
X1394177D03*
X1404807D03*
X1401263D03*
X1403035D03*
X1420990D03*
X1431620D03*
X1428076D03*
X1424533D03*
X1429848D03*
X1422761D03*
X1426305D03*
X1447712Y582336D03*
X1441806D03*
X1445743D03*
X1443775D03*
X1441806Y593360D03*
X1443775D03*
X1447712D03*
X1445743D03*
X1436935Y1110233D03*
X1433391D03*
X1435163D03*
X1458252Y177338D03*
X1464158D03*
X1462189D03*
X1460221D03*
X1464158Y188362D03*
X1458252D03*
X1460221D03*
X1462189D03*
X1560614Y177338D03*
X1562583D03*
X1560614Y188362D03*
X1562583D03*
X1566520Y177338D03*
X1564551D03*
X1566520Y188362D03*
X1564551D03*
X1662976Y177338D03*
X1668882D03*
X1666913D03*
X1664945D03*
X1668882Y188362D03*
X1662976D03*
X1664945D03*
X1666913D03*
X1733709Y389013D03*
X1731740D03*
X1727803D03*
X1729772D03*
X1727803Y400037D03*
X1733709D03*
X1729772D03*
X1731740D03*
X1765338Y177338D03*
X1771244D03*
X1769275D03*
X1767307D03*
X1771244Y188362D03*
X1765338D03*
X1767307D03*
X1769275D03*
X1804401Y1088643D03*
X1806370D03*
X1804401Y1099667D03*
X1806370D03*
X1810307Y1088643D03*
X1808338D03*
X1810307Y1099667D03*
X1808338D03*
G54D249*
X1298720Y807880D03*
Y802762D03*
X1305412Y807880D03*
Y802762D03*
G54D39*
X20079Y1433831D03*
X12599D03*
X16339Y1441705D03*
X20041Y1449735D03*
X12561D03*
X16301Y1457609D03*
X1056934Y1443022D03*
X1053194Y1450896D03*
X1060674D03*
G54D186*
X795791Y1446386D03*
Y1448158D03*
Y1457016D03*
Y1458788D03*
Y1453473D03*
Y1449930D03*
Y1455244D03*
Y1451701D03*
X821283Y1446386D03*
Y1448158D03*
Y1458788D03*
Y1451701D03*
Y1457016D03*
Y1453473D03*
Y1455244D03*
Y1449930D03*
G54D57*
X45643Y454376D03*
Y461462D03*
X246031Y633786D03*
Y640872D03*
X485485Y421374D03*
Y428460D03*
X500729Y451376D03*
Y458462D03*
X703117Y633786D03*
Y640872D03*
X943111Y242721D03*
Y249807D03*
X959816Y454376D03*
Y461462D03*
X1160204Y633786D03*
Y640872D03*
X1292500Y938043D03*
Y930957D03*
X1414903Y451376D03*
Y458462D03*
X1429546Y1508327D03*
Y1515413D03*
X1600410Y1456276D03*
Y1463362D03*
X1617291Y633786D03*
Y640872D03*
G54D177*
X725006Y-32810D03*
Y-30842D03*
X845006Y-71990D03*
Y-70022D03*
X949942Y-30814D03*
Y-32782D03*
X974786Y-69994D03*
Y-71962D03*
X1008506Y-32810D03*
Y-30842D03*
X1078506Y-71990D03*
Y-70022D03*
X1228086Y-69994D03*
Y-71962D03*
X1233442Y-30944D03*
Y-32912D03*
X1295006Y-32940D03*
Y-30972D03*
X1335006Y-71990D03*
Y-70022D03*
X1484586Y-69994D03*
Y-71962D03*
X1519942Y-31074D03*
Y-33042D03*
X1579506Y-33070D03*
Y-31102D03*
X1589506Y-71990D03*
Y-70022D03*
X1739086Y-69994D03*
Y-71962D03*
X1804442Y-31204D03*
Y-33172D03*
G54D159*
X427378Y1555499D03*
X434070Y1560617D03*
Y1555499D03*
X427378Y1560617D03*
X948452Y360607D03*
X955144D03*
Y365725D03*
X948452D03*
G54D84*
X68529Y1201565D03*
Y1205835D03*
X207354Y200864D03*
X204204D03*
X309716D03*
X306566D03*
X390470Y1516448D03*
X393620D03*
X408928Y200864D03*
X404053Y1516556D03*
X400903D03*
X412078Y200864D03*
X485485Y552726D03*
X488635D03*
X562079Y200864D03*
X558929D03*
X664441D03*
X661291D03*
X869165D03*
X866015D03*
X912085Y323302D03*
Y329602D03*
X912220Y1214838D03*
Y1210568D03*
X915235Y323302D03*
X923902D03*
X920752D03*
X915235Y329602D03*
X923902D03*
X920752D03*
X943787Y336817D03*
X935137D03*
X938287D03*
X943787Y330517D03*
X935137D03*
X938287D03*
X942572Y552726D03*
X945722D03*
X946937Y336817D03*
Y330517D03*
X976197Y1214838D03*
Y1210568D03*
X1399659Y552726D03*
X1402809D03*
X1820177Y1215324D03*
Y1211054D03*
G54D75*
X59848Y211751D03*
Y227499D03*
X59617Y271043D03*
Y286791D03*
X83374Y480347D03*
Y496095D03*
X73543Y526091D03*
Y541839D03*
X162210Y211751D03*
Y227499D03*
X161979Y271043D03*
Y286791D03*
X264572Y211751D03*
Y227499D03*
X264341Y271043D03*
Y286791D03*
X348329Y476109D03*
Y491857D03*
X366934Y211751D03*
Y227499D03*
X366703Y271043D03*
Y286791D03*
X390521Y437459D03*
Y453207D03*
X419390Y496242D03*
Y511990D03*
X516935Y211751D03*
Y227499D03*
X516704Y271043D03*
Y286791D03*
X540460Y480347D03*
Y496095D03*
X530629Y526091D03*
Y541839D03*
X619297Y211751D03*
Y227499D03*
X619066Y271043D03*
Y286791D03*
X721659Y211751D03*
Y227499D03*
X721428Y271043D03*
Y286791D03*
X805415Y471109D03*
Y486857D03*
X824021Y211751D03*
Y227499D03*
X823790Y271043D03*
Y286791D03*
X885801Y453800D03*
Y469548D03*
X974021Y211751D03*
Y227499D03*
X973790Y271043D03*
Y286791D03*
X987716Y526091D03*
Y541839D03*
X997547Y480347D03*
Y496095D03*
X1076383Y211751D03*
Y227499D03*
X1076152Y271043D03*
Y286791D03*
X1178745Y211751D03*
Y227499D03*
X1178514Y271043D03*
Y286791D03*
X1262502Y476109D03*
Y491857D03*
X1281107Y211751D03*
Y227499D03*
X1280876Y271043D03*
Y286791D03*
X1304748Y437459D03*
Y453207D03*
X1431108Y211751D03*
Y227499D03*
X1430877Y271043D03*
Y286791D03*
X1444803Y526091D03*
Y541839D03*
X1454634Y480347D03*
Y496095D03*
X1533470Y211751D03*
Y227499D03*
X1533239Y271043D03*
Y286791D03*
X1635832Y211751D03*
Y227499D03*
X1635601Y271043D03*
Y286791D03*
X1719589Y476109D03*
Y491857D03*
X1738194Y211751D03*
Y227499D03*
X1737963Y271043D03*
Y286791D03*
X1761835Y437459D03*
Y453207D03*
G54D169*
X538609Y789327D03*
X536641D03*
X534672D03*
X536641Y834405D03*
X534672D03*
X538609D03*
X550420Y789327D03*
X540578D03*
X544515D03*
X554357D03*
X542546D03*
X548452D03*
X546483D03*
X552389D03*
X546483Y834405D03*
X540578D03*
X542546D03*
X544515D03*
X548452D03*
X550420D03*
X552389D03*
X554357D03*
X556326Y789327D03*
X558294D03*
X560263D03*
X562231D03*
X564200D03*
X556326Y834405D03*
X558294D03*
X560263D03*
X562231D03*
X564200D03*
X1505337Y916678D03*
X1509274D03*
X1503368D03*
X1501400D03*
X1507305D03*
X1499431D03*
X1513211D03*
X1511242D03*
Y961756D03*
X1501400D03*
X1499431D03*
X1503368D03*
X1505337D03*
X1507305D03*
X1509274D03*
X1513211D03*
X1515179Y916678D03*
X1521085D03*
X1523053D03*
X1525022D03*
X1526990D03*
X1519116D03*
X1517148D03*
X1528959D03*
X1521085Y961756D03*
X1523053D03*
X1525022D03*
X1515179D03*
X1517148D03*
X1519116D03*
X1526990D03*
X1528959D03*
G54D178*
X729727Y736204D03*
Y743684D03*
X740357D03*
Y739944D03*
Y736204D03*
X1042925Y1315612D03*
X1032295D03*
Y1319352D03*
X1042925Y1323092D03*
X1032295D03*
X1041602Y1334065D03*
X1032272Y1330325D03*
Y1337805D03*
G54D94*
X76012Y1355193D03*
Y1353093D03*
X79612Y1355193D03*
Y1353093D03*
X76012Y1379391D03*
Y1377291D03*
X79612Y1379391D03*
Y1377291D03*
X100492Y1355193D03*
Y1353093D03*
X91852Y1355193D03*
Y1353093D03*
X88252Y1355193D03*
Y1353093D03*
X100492Y1379391D03*
Y1377291D03*
X91852Y1379391D03*
Y1377291D03*
X88252Y1379391D03*
Y1377291D03*
Y1403589D03*
Y1401489D03*
X91852Y1403589D03*
Y1401489D03*
X100492Y1403589D03*
Y1401489D03*
X103001Y1035088D03*
Y1032988D03*
X106113Y1035102D03*
Y1033002D03*
X110430Y1105228D03*
Y1107328D03*
Y1130428D03*
Y1132528D03*
Y1143028D03*
Y1145128D03*
Y1168228D03*
Y1170328D03*
Y1180828D03*
Y1182928D03*
X104092Y1355193D03*
Y1353093D03*
X116332Y1355193D03*
Y1353093D03*
X112732Y1355193D03*
Y1353093D03*
X116332Y1379391D03*
Y1377291D03*
X104092Y1379391D03*
Y1377291D03*
X112732Y1379391D03*
Y1377291D03*
X116332Y1403589D03*
Y1401489D03*
X112732Y1403589D03*
Y1401489D03*
X104092Y1403589D03*
Y1401489D03*
X122076Y1012491D03*
Y1014591D03*
Y1025091D03*
Y1027191D03*
X124972Y1355193D03*
Y1353093D03*
X128572Y1355193D03*
Y1353093D03*
Y1379391D03*
Y1377291D03*
X124972Y1379391D03*
Y1377291D03*
X128572Y1403589D03*
Y1401489D03*
X124972Y1403589D03*
Y1401489D03*
X149452Y1355193D03*
Y1353093D03*
X137212Y1355193D03*
Y1353093D03*
X140812Y1355193D03*
Y1353093D03*
X149452Y1379391D03*
Y1377291D03*
X137212Y1379391D03*
Y1377291D03*
X140812Y1379391D03*
Y1377291D03*
X149452Y1403589D03*
Y1401489D03*
X137212Y1403589D03*
Y1401489D03*
X140812Y1403589D03*
Y1401489D03*
X165292Y1355193D03*
Y1353093D03*
X161692Y1355193D03*
Y1353093D03*
X153052Y1355193D03*
Y1353093D03*
X165292Y1379391D03*
Y1377291D03*
X161692Y1379391D03*
Y1377291D03*
X153052Y1379391D03*
Y1377291D03*
X161692Y1403589D03*
Y1401489D03*
X165292Y1403589D03*
Y1401489D03*
X153052Y1403589D03*
Y1401489D03*
X173932Y1355193D03*
Y1353093D03*
X177532Y1355193D03*
Y1353093D03*
X173932Y1379391D03*
Y1377291D03*
X177532Y1379391D03*
Y1377291D03*
X173932Y1403589D03*
Y1401489D03*
X177532Y1403589D03*
Y1401489D03*
X198412Y1355193D03*
Y1353093D03*
X189772Y1355193D03*
Y1353093D03*
X186172Y1355193D03*
Y1353093D03*
X198412Y1379391D03*
Y1377291D03*
X189772Y1379391D03*
Y1377291D03*
X186172Y1379391D03*
Y1377291D03*
X198412Y1403589D03*
Y1401489D03*
X189772Y1403589D03*
Y1401489D03*
X186172Y1403589D03*
Y1401489D03*
X202012Y1355193D03*
Y1353093D03*
Y1379391D03*
Y1377291D03*
Y1403589D03*
Y1401489D03*
X245123Y1355193D03*
Y1353093D03*
X241523Y1355193D03*
Y1353093D03*
X245123Y1379391D03*
Y1377291D03*
X241523Y1379391D03*
Y1377291D03*
X253763Y1355193D03*
Y1353093D03*
X257363Y1355193D03*
Y1353093D03*
Y1379391D03*
Y1377291D03*
X253763Y1379391D03*
Y1377291D03*
Y1403589D03*
Y1401489D03*
X257363Y1403589D03*
Y1401489D03*
X266003Y1355193D03*
Y1353093D03*
X269603Y1355193D03*
Y1353093D03*
X278243Y1355193D03*
Y1353093D03*
X266003Y1379391D03*
Y1377291D03*
X269603Y1379391D03*
Y1377291D03*
X278243Y1379391D03*
Y1377291D03*
X269603Y1403589D03*
Y1401489D03*
X266003Y1403589D03*
Y1401489D03*
X278243Y1403589D03*
Y1401489D03*
X281843Y1355193D03*
Y1353093D03*
X290483Y1355193D03*
Y1353093D03*
X294083Y1355193D03*
Y1353093D03*
X281843Y1379391D03*
Y1377291D03*
X290483Y1379391D03*
Y1377291D03*
X294083Y1379391D03*
Y1377291D03*
X281843Y1403589D03*
Y1401489D03*
X290483Y1403589D03*
Y1401489D03*
X294083Y1403589D03*
Y1401489D03*
X306323Y1355193D03*
Y1353093D03*
X302723Y1355193D03*
Y1353093D03*
X306323Y1379391D03*
Y1377291D03*
X302723Y1379391D03*
Y1377291D03*
Y1403589D03*
Y1401489D03*
X306323Y1403589D03*
Y1401489D03*
X327203Y1355193D03*
Y1353093D03*
X314963Y1355193D03*
Y1353093D03*
X318563Y1355193D03*
Y1353093D03*
X327203Y1379391D03*
Y1377291D03*
X318563Y1379391D03*
Y1377291D03*
X314963Y1379391D03*
Y1377291D03*
X327203Y1403589D03*
Y1401489D03*
X318563Y1403589D03*
Y1401489D03*
X314963Y1403589D03*
Y1401489D03*
X343043Y1355193D03*
Y1353093D03*
X339443Y1355193D03*
Y1353093D03*
X330803Y1355193D03*
Y1353093D03*
X339443Y1379391D03*
Y1377291D03*
X343043Y1379391D03*
Y1377291D03*
X330803Y1379391D03*
Y1377291D03*
X343043Y1403589D03*
Y1401489D03*
X339443Y1403589D03*
Y1401489D03*
X330803Y1403589D03*
Y1401489D03*
X355283Y1355193D03*
Y1353093D03*
X351683Y1355193D03*
Y1353093D03*
Y1379391D03*
Y1377291D03*
X355283Y1379391D03*
Y1377291D03*
Y1403589D03*
Y1401489D03*
X351683Y1403589D03*
Y1401489D03*
X367523Y1355193D03*
Y1353093D03*
X363923Y1355193D03*
Y1353093D03*
Y1379391D03*
Y1377291D03*
X367523Y1379391D03*
Y1377291D03*
Y1403589D03*
Y1401489D03*
X363923Y1403589D03*
Y1401489D03*
X440302Y1355193D03*
Y1353093D03*
Y1379391D03*
Y1377291D03*
X452542Y1355193D03*
Y1353093D03*
X456142Y1355193D03*
Y1353093D03*
X443902Y1355193D03*
Y1353093D03*
X452542Y1379391D03*
Y1377291D03*
X456142Y1379391D03*
Y1377291D03*
X443902Y1379391D03*
Y1377291D03*
X452542Y1403589D03*
Y1401489D03*
X456142Y1403589D03*
Y1401489D03*
X468382Y1355193D03*
Y1353093D03*
X464782Y1355193D03*
Y1353093D03*
Y1379391D03*
Y1377291D03*
X468382Y1379391D03*
Y1377291D03*
X464782Y1403589D03*
Y1401489D03*
X468382Y1403589D03*
Y1401489D03*
X477022Y1355193D03*
Y1353093D03*
X480622Y1355193D03*
Y1353093D03*
X489262Y1355193D03*
Y1353093D03*
X477022Y1379391D03*
Y1377291D03*
X489262Y1379391D03*
Y1377291D03*
X480622Y1379391D03*
Y1377291D03*
X489262Y1403589D03*
Y1401489D03*
X477022Y1403589D03*
Y1401489D03*
X480622Y1403589D03*
Y1401489D03*
X505102Y1355193D03*
Y1353093D03*
X501502Y1355193D03*
Y1353093D03*
X492862Y1355193D03*
Y1353093D03*
X505102Y1379391D03*
Y1377291D03*
X501502Y1379391D03*
Y1377291D03*
X492862Y1379391D03*
Y1377291D03*
X505102Y1403589D03*
Y1401489D03*
X501502Y1403589D03*
Y1401489D03*
X492862Y1403589D03*
Y1401489D03*
X517342Y1355193D03*
Y1353093D03*
X513742Y1355193D03*
Y1353093D03*
X517342Y1379391D03*
Y1377291D03*
X513742Y1379391D03*
Y1377291D03*
Y1403589D03*
Y1401489D03*
X517342Y1403589D03*
Y1401489D03*
X529582Y1355193D03*
Y1353093D03*
X538222Y1355193D03*
Y1353093D03*
X525982Y1355193D03*
Y1353093D03*
X538222Y1379391D03*
Y1377291D03*
X525982Y1379391D03*
Y1377291D03*
X529582Y1379391D03*
Y1377291D03*
X538222Y1403589D03*
Y1401489D03*
X529582Y1403589D03*
Y1401489D03*
X525982Y1403589D03*
Y1401489D03*
X555395Y1035088D03*
Y1032988D03*
X554062Y1355193D03*
Y1353093D03*
X550462Y1355193D03*
Y1353093D03*
X541822Y1355193D03*
Y1353093D03*
X550462Y1379391D03*
Y1377291D03*
X554062Y1379391D03*
Y1377291D03*
X541822Y1379391D03*
Y1377291D03*
X554062Y1403589D03*
Y1401489D03*
X550462Y1403589D03*
Y1401489D03*
X541822Y1403589D03*
Y1401489D03*
X563200Y1035102D03*
Y1033002D03*
X560088Y1035088D03*
Y1032988D03*
X567517Y1105228D03*
Y1107328D03*
Y1117828D03*
Y1119928D03*
Y1130428D03*
Y1132528D03*
Y1143028D03*
Y1145128D03*
Y1155628D03*
Y1157728D03*
Y1180828D03*
Y1182928D03*
X566302Y1355193D03*
Y1353093D03*
X562702Y1355193D03*
Y1353093D03*
Y1379391D03*
Y1377291D03*
X566302Y1379391D03*
Y1377291D03*
Y1403589D03*
Y1401489D03*
X562702Y1403589D03*
Y1401489D03*
X579163Y1012491D03*
Y1014591D03*
Y1025091D03*
Y1027191D03*
X629788Y1403589D03*
Y1401489D03*
X626188Y1403589D03*
Y1401489D03*
X650668Y1355193D03*
Y1353093D03*
Y1379391D03*
Y1377291D03*
X642028Y1379391D03*
Y1377291D03*
X638428Y1379391D03*
Y1377291D03*
X650668Y1403589D03*
Y1401489D03*
X642028Y1403589D03*
Y1401489D03*
X638428Y1403589D03*
Y1401489D03*
X666508Y1355193D03*
Y1353093D03*
X662908Y1355193D03*
Y1353093D03*
X654268Y1355193D03*
Y1353093D03*
Y1379391D03*
Y1377291D03*
X662908Y1379391D03*
Y1377291D03*
X666508Y1379391D03*
Y1377291D03*
X654268Y1403589D03*
Y1401489D03*
X666508Y1403589D03*
Y1401489D03*
X662908Y1403589D03*
Y1401489D03*
X678748Y1355193D03*
Y1353093D03*
X675148Y1355193D03*
Y1353093D03*
X678748Y1379391D03*
Y1377291D03*
X675148Y1379391D03*
Y1377291D03*
X678748Y1403589D03*
Y1401489D03*
X675148Y1403589D03*
Y1401489D03*
X699628Y1355193D03*
Y1353093D03*
X690988Y1355193D03*
Y1353093D03*
X687388Y1355193D03*
Y1353093D03*
X699628Y1379391D03*
Y1377291D03*
X690988Y1379391D03*
Y1377291D03*
X687388Y1379391D03*
Y1377291D03*
X699628Y1403589D03*
Y1401489D03*
X690988Y1403589D03*
Y1401489D03*
X687388Y1403589D03*
Y1401489D03*
X715468Y1355193D03*
Y1353093D03*
X711868Y1355193D03*
Y1353093D03*
X703228Y1355193D03*
Y1353093D03*
X711868Y1379391D03*
Y1377291D03*
X715468Y1379391D03*
Y1377291D03*
X703228Y1379391D03*
Y1377291D03*
X715468Y1403589D03*
Y1401489D03*
X711868Y1403589D03*
Y1401489D03*
X703228Y1403589D03*
Y1401489D03*
X727708Y1355193D03*
Y1353093D03*
X724108Y1355193D03*
Y1353093D03*
Y1379391D03*
Y1377291D03*
X727708Y1379391D03*
Y1377291D03*
X724108Y1403495D03*
Y1401395D03*
X727708Y1403495D03*
Y1401395D03*
X748588Y1355193D03*
Y1353093D03*
X739948Y1355193D03*
Y1353093D03*
X736348Y1355193D03*
Y1353093D03*
X748588Y1379391D03*
Y1377291D03*
X736348Y1379391D03*
Y1377291D03*
X739948Y1379391D03*
Y1377291D03*
X736348Y1403495D03*
Y1401395D03*
X739948Y1403495D03*
Y1401395D03*
X752188Y1355193D03*
Y1353093D03*
X760828Y1355193D03*
Y1353093D03*
X764428Y1355193D03*
Y1353093D03*
X760828Y1379391D03*
Y1377291D03*
X764428Y1379391D03*
Y1377291D03*
X752188Y1379391D03*
Y1377291D03*
X776668Y1355193D03*
Y1353093D03*
X773068Y1355193D03*
Y1353093D03*
X896371Y1073980D03*
Y1076080D03*
X899583Y1074008D03*
X906117Y1074004D03*
X902986Y1073977D03*
X899583Y1076108D03*
X906117Y1076104D03*
X902986Y1076077D03*
X1012517Y1035088D03*
Y1032988D03*
X1020286Y1035102D03*
Y1033002D03*
X1017174Y1035088D03*
Y1032988D03*
X1024603Y1105228D03*
Y1107328D03*
Y1117828D03*
Y1119928D03*
Y1130428D03*
Y1132528D03*
Y1143028D03*
Y1145128D03*
Y1155628D03*
Y1157728D03*
Y1180828D03*
Y1182928D03*
X1036249Y1012491D03*
Y1014591D03*
Y1025091D03*
Y1027191D03*
X1058213Y1355193D03*
Y1353093D03*
X1054613Y1355193D03*
Y1353093D03*
X1058213Y1379391D03*
Y1377291D03*
X1054613Y1379391D03*
Y1377291D03*
X1070453Y1355193D03*
Y1353093D03*
X1066853Y1355193D03*
Y1353093D03*
Y1379391D03*
Y1377291D03*
X1070453Y1379391D03*
Y1377291D03*
Y1403589D03*
Y1401489D03*
X1066853Y1403589D03*
Y1401489D03*
X1082693Y1355193D03*
Y1353093D03*
X1079093Y1355193D03*
Y1353093D03*
X1091333Y1355193D03*
Y1353093D03*
X1079093Y1379391D03*
Y1377291D03*
X1082693Y1379391D03*
Y1377291D03*
X1091333Y1379391D03*
Y1377291D03*
X1079093Y1403589D03*
Y1401489D03*
X1082693Y1403589D03*
Y1401489D03*
X1091333Y1403589D03*
Y1401489D03*
X1094933Y1355193D03*
Y1353093D03*
X1103573Y1355193D03*
Y1353093D03*
X1107173Y1355193D03*
Y1353093D03*
X1094933Y1379391D03*
Y1377291D03*
X1103573Y1379391D03*
Y1377291D03*
X1107173Y1379391D03*
Y1377291D03*
X1094933Y1403589D03*
Y1401489D03*
X1107173Y1403589D03*
Y1401489D03*
X1103573Y1403589D03*
Y1401489D03*
X1115813Y1355193D03*
Y1353093D03*
X1119413Y1355193D03*
Y1353093D03*
X1115813Y1379391D03*
Y1377291D03*
X1119413Y1379391D03*
Y1377291D03*
X1115813Y1403589D03*
Y1401489D03*
X1119413Y1403589D03*
Y1401489D03*
X1131653Y1355193D03*
Y1353093D03*
X1128053Y1355193D03*
Y1353093D03*
X1140293Y1355193D03*
Y1353093D03*
X1128053Y1379391D03*
Y1377291D03*
X1131653Y1379391D03*
Y1377291D03*
X1140293Y1379391D03*
Y1377291D03*
X1131653Y1403589D03*
Y1401489D03*
X1128053Y1403589D03*
Y1401489D03*
X1140293Y1403589D03*
Y1401489D03*
X1143893Y1355193D03*
Y1353093D03*
X1156133Y1355193D03*
Y1353093D03*
X1152533Y1355193D03*
Y1353093D03*
X1143893Y1379391D03*
Y1377291D03*
X1152533Y1379391D03*
Y1377291D03*
X1156133Y1379391D03*
Y1377291D03*
X1143893Y1403589D03*
Y1401489D03*
X1152533Y1403589D03*
Y1401489D03*
X1156133Y1403589D03*
Y1401489D03*
X1168373Y1355193D03*
Y1353093D03*
X1164773Y1355193D03*
Y1353093D03*
Y1379391D03*
Y1377291D03*
X1168373Y1379391D03*
Y1377291D03*
X1164773Y1403589D03*
Y1401489D03*
X1168373Y1403589D03*
Y1401489D03*
X1180613Y1355193D03*
Y1353093D03*
X1177013Y1355193D03*
Y1353093D03*
X1180613Y1379391D03*
Y1377291D03*
X1177013Y1379391D03*
Y1377291D03*
X1180613Y1403589D03*
Y1401489D03*
X1177013Y1403589D03*
Y1401489D03*
X1230226Y1355193D03*
Y1353093D03*
X1233826Y1355193D03*
Y1353093D03*
Y1379391D03*
Y1377291D03*
X1230226Y1379391D03*
Y1377291D03*
X1246066Y1355193D03*
Y1353093D03*
X1242466Y1355193D03*
Y1353093D03*
X1246066Y1379391D03*
Y1377291D03*
X1242466Y1379391D03*
Y1377291D03*
X1246066Y1403589D03*
Y1401489D03*
X1242466Y1403589D03*
Y1401489D03*
X1258306Y1355193D03*
Y1353093D03*
X1254706Y1355193D03*
Y1353093D03*
X1270546Y1355193D03*
Y1353093D03*
X1266946Y1355193D03*
Y1353093D03*
X1254706Y1379391D03*
Y1377291D03*
X1258306Y1379391D03*
Y1377291D03*
X1270546Y1379391D03*
Y1377291D03*
X1266946Y1379391D03*
Y1377291D03*
X1258306Y1403589D03*
Y1401489D03*
X1254706Y1403589D03*
Y1401489D03*
X1270546Y1403589D03*
Y1401489D03*
X1266946Y1403589D03*
Y1401489D03*
X1282786Y1355193D03*
Y1353093D03*
X1279186Y1355193D03*
Y1353093D03*
Y1379391D03*
Y1377291D03*
X1282786Y1379391D03*
Y1377291D03*
X1279186Y1403589D03*
Y1401489D03*
X1282786Y1403589D03*
Y1401489D03*
X1295026Y1355193D03*
Y1353093D03*
X1291426Y1355193D03*
Y1353093D03*
X1295026Y1379391D03*
Y1377291D03*
X1291426Y1379391D03*
Y1377291D03*
X1295026Y1403589D03*
Y1401489D03*
X1291426Y1403589D03*
Y1401489D03*
X1303666Y1355193D03*
Y1353093D03*
X1307266Y1355193D03*
Y1353093D03*
X1315906Y1355193D03*
Y1353093D03*
X1303666Y1379391D03*
Y1377291D03*
X1307266Y1379391D03*
Y1377291D03*
X1315906Y1379391D03*
Y1377291D03*
X1303666Y1403589D03*
Y1401489D03*
X1307266Y1403589D03*
Y1401489D03*
X1315906Y1403589D03*
Y1401489D03*
X1319506Y1355193D03*
Y1353093D03*
X1331746Y1355193D03*
Y1353093D03*
X1328146Y1355193D03*
Y1353093D03*
X1319506Y1379391D03*
Y1377291D03*
X1331746Y1379391D03*
Y1377291D03*
X1328146Y1379391D03*
Y1377291D03*
X1319506Y1403589D03*
Y1401489D03*
X1328146Y1403589D03*
Y1401489D03*
X1331746Y1403589D03*
Y1401489D03*
X1343986Y1355193D03*
Y1353093D03*
X1340386Y1355193D03*
Y1353093D03*
Y1379391D03*
Y1377291D03*
X1343986Y1379391D03*
Y1377291D03*
Y1403589D03*
Y1401489D03*
X1340386Y1403589D03*
Y1401489D03*
X1352626Y1355193D03*
Y1353093D03*
X1356226Y1355193D03*
Y1353093D03*
X1352626Y1379391D03*
Y1377291D03*
X1356226Y1379391D03*
Y1377291D03*
X1352626Y1403589D03*
Y1401489D03*
X1356226Y1403589D03*
Y1401489D03*
X1404239Y1545478D03*
Y1543378D03*
X1403747Y1568156D03*
Y1566056D03*
X1461270Y1355193D03*
Y1353093D03*
X1464870Y1355193D03*
Y1353093D03*
X1461270Y1379391D03*
Y1377291D03*
X1464870Y1379391D03*
Y1377291D03*
X1477373Y1035102D03*
Y1033002D03*
X1474261Y1035088D03*
Y1032988D03*
X1481690Y1105228D03*
Y1107328D03*
Y1117828D03*
Y1119928D03*
Y1130428D03*
Y1132528D03*
Y1143028D03*
Y1145128D03*
Y1155628D03*
Y1168228D03*
Y1170328D03*
Y1157728D03*
Y1180828D03*
Y1182928D03*
X1477110Y1355193D03*
Y1353093D03*
X1473510Y1355193D03*
Y1353093D03*
X1477110Y1379391D03*
Y1377291D03*
X1473510Y1379391D03*
Y1377291D03*
Y1403589D03*
Y1401489D03*
X1477110Y1403589D03*
Y1401489D03*
X1493336Y1025091D03*
Y1012491D03*
Y1014591D03*
Y1027191D03*
X1485750Y1355193D03*
Y1353093D03*
X1489350Y1355193D03*
Y1353093D03*
X1497990Y1355193D03*
Y1353093D03*
Y1379391D03*
Y1377291D03*
X1485750Y1379391D03*
Y1377291D03*
X1489350Y1379391D03*
Y1377291D03*
Y1403589D03*
Y1401489D03*
X1485750Y1403589D03*
Y1401489D03*
X1497990Y1403589D03*
Y1401489D03*
X1501590Y1355193D03*
Y1353093D03*
X1510230Y1355193D03*
Y1353093D03*
X1513830Y1355193D03*
Y1353093D03*
X1501590Y1379391D03*
Y1377291D03*
X1510230Y1379391D03*
Y1377291D03*
X1513830Y1379391D03*
Y1377291D03*
X1501590Y1403589D03*
Y1401489D03*
X1510230Y1403589D03*
Y1401489D03*
X1513830Y1403589D03*
Y1401489D03*
X1522470Y1355193D03*
Y1353093D03*
X1526070Y1355193D03*
Y1353093D03*
Y1379391D03*
Y1377291D03*
X1522470Y1379391D03*
Y1377291D03*
Y1403589D03*
Y1401489D03*
X1526070Y1403589D03*
Y1401489D03*
X1534710Y1355193D03*
Y1353093D03*
X1538310Y1355193D03*
Y1353093D03*
X1534710Y1379391D03*
Y1377291D03*
X1538310Y1379391D03*
Y1377291D03*
Y1403589D03*
Y1401489D03*
X1534710Y1403589D03*
Y1401489D03*
X1559190Y1355193D03*
Y1353093D03*
X1562790Y1355193D03*
Y1353093D03*
X1550550Y1355193D03*
Y1353093D03*
X1546950Y1355193D03*
Y1353093D03*
Y1379391D03*
Y1377291D03*
X1550550Y1379391D03*
Y1377291D03*
X1559190Y1379391D03*
Y1377291D03*
X1562790Y1379391D03*
Y1377291D03*
X1546950Y1403589D03*
Y1401489D03*
X1550550Y1403589D03*
Y1401489D03*
X1562790Y1403589D03*
Y1401489D03*
X1559190Y1403589D03*
Y1401489D03*
X1575030Y1355193D03*
Y1353093D03*
X1571430Y1355193D03*
Y1353093D03*
X1575030Y1379391D03*
Y1377291D03*
X1571430Y1379391D03*
Y1377291D03*
Y1403589D03*
Y1401489D03*
X1575030Y1403589D03*
Y1401489D03*
X1583670Y1355193D03*
Y1353093D03*
X1587270Y1355193D03*
Y1353093D03*
X1583670Y1379391D03*
Y1377291D03*
X1587270Y1379391D03*
Y1377291D03*
X1583670Y1403589D03*
Y1401489D03*
X1587270Y1403589D03*
Y1401489D03*
X1593942Y1437014D03*
Y1439114D03*
X1611298Y1355193D03*
Y1353093D03*
Y1379391D03*
Y1377291D03*
X1623538Y1355193D03*
Y1353093D03*
X1627138Y1355193D03*
Y1353093D03*
X1614898Y1355193D03*
Y1353093D03*
X1627138Y1379391D03*
Y1377291D03*
X1623538Y1379391D03*
Y1377291D03*
X1614898Y1379391D03*
Y1377291D03*
X1623538Y1403589D03*
Y1401489D03*
X1627138Y1403589D03*
Y1401489D03*
X1639378Y1355193D03*
Y1353093D03*
X1635778Y1355193D03*
Y1353093D03*
Y1379391D03*
Y1377291D03*
X1639378Y1379391D03*
Y1377291D03*
X1635778Y1403589D03*
Y1401489D03*
X1639378Y1403589D03*
Y1401489D03*
X1660258Y1355193D03*
Y1353093D03*
X1648018Y1355193D03*
Y1353093D03*
X1651618Y1355193D03*
Y1353093D03*
X1660258Y1379391D03*
Y1377291D03*
X1651618Y1379391D03*
Y1377291D03*
X1648018Y1379391D03*
Y1377291D03*
X1651618Y1403589D03*
Y1401489D03*
X1660258Y1403589D03*
Y1401489D03*
X1648018Y1403589D03*
Y1401489D03*
X1672498Y1355193D03*
Y1353093D03*
X1676098Y1355193D03*
Y1353093D03*
X1663858Y1355193D03*
Y1353093D03*
X1676098Y1379391D03*
Y1377291D03*
X1672498Y1379391D03*
Y1377291D03*
X1663858Y1379391D03*
Y1377291D03*
X1672498Y1403589D03*
Y1401489D03*
X1676098Y1403589D03*
Y1401489D03*
X1663858Y1403589D03*
Y1401489D03*
X1684738Y1355193D03*
Y1353093D03*
X1688338Y1355193D03*
Y1353093D03*
Y1379391D03*
Y1377291D03*
X1684738Y1379391D03*
Y1377291D03*
Y1403589D03*
Y1401489D03*
X1688338Y1403589D03*
Y1401489D03*
X1700578Y1355193D03*
Y1353093D03*
X1696978Y1355193D03*
Y1353093D03*
X1709218Y1355193D03*
Y1353093D03*
Y1379391D03*
Y1377291D03*
X1696978Y1379391D03*
Y1377291D03*
X1700578Y1379391D03*
Y1377291D03*
X1709218Y1403589D03*
Y1401489D03*
X1696978Y1403589D03*
Y1401489D03*
X1700578Y1403589D03*
Y1401489D03*
X1721458Y1355193D03*
Y1353093D03*
X1725058Y1355193D03*
Y1353093D03*
X1712818Y1355193D03*
Y1353093D03*
X1725058Y1379391D03*
Y1377291D03*
X1721458Y1379391D03*
Y1377291D03*
X1712818Y1379391D03*
Y1377291D03*
X1725058Y1403589D03*
Y1401489D03*
X1721458Y1403589D03*
Y1401489D03*
X1712818Y1403589D03*
Y1401489D03*
X1733698Y1355193D03*
Y1353093D03*
X1737298Y1355193D03*
Y1353093D03*
Y1379391D03*
Y1377291D03*
X1733698Y1379391D03*
Y1377291D03*
Y1403589D03*
Y1401489D03*
X1737298Y1403589D03*
Y1401489D03*
X1807393Y1438622D03*
Y1440722D03*
X1807270Y1470812D03*
Y1472912D03*
G54D196*
X857781Y1443730D03*
Y1461448D03*
X871561Y1443730D03*
Y1461448D03*
X899781Y1443730D03*
Y1461448D03*
X913561Y1443730D03*
Y1461448D03*
G54D67*
X47195Y1081713D03*
Y1087619D03*
Y1083682D03*
Y1085650D03*
X67987Y584895D03*
Y586864D03*
Y590801D03*
Y588832D03*
X58219Y1087619D03*
Y1085650D03*
Y1081713D03*
Y1083682D03*
X84433Y179897D03*
Y181866D03*
Y185803D03*
Y183834D03*
X79011Y584895D03*
Y586864D03*
Y590801D03*
Y588832D03*
X95457Y179897D03*
Y181866D03*
Y185803D03*
Y183834D03*
X186795Y179897D03*
Y181866D03*
X197819Y179897D03*
Y181866D03*
X186795Y185803D03*
X197819D03*
X186795Y183834D03*
X197819D03*
X289157Y179897D03*
Y181866D03*
Y185803D03*
Y183834D03*
X300181Y179897D03*
Y181866D03*
Y185803D03*
Y183834D03*
X353984Y391572D03*
Y397478D03*
Y393541D03*
Y395509D03*
X365008Y391572D03*
Y397478D03*
Y395509D03*
Y393541D03*
X391519Y179897D03*
Y181866D03*
Y185803D03*
Y183834D03*
X393321Y960580D03*
Y954674D03*
Y958611D03*
X382297Y954674D03*
X393321Y956643D03*
X382297D03*
Y960580D03*
Y958611D03*
X402543Y179897D03*
Y181866D03*
Y185803D03*
Y183834D03*
X426660Y1112693D03*
Y1116237D03*
Y1118008D03*
Y1119780D03*
Y1121552D03*
Y1114465D03*
X458788Y1112693D03*
Y1116237D03*
Y1118008D03*
Y1119780D03*
Y1121552D03*
Y1114465D03*
X492247Y1112693D03*
Y1116237D03*
Y1118008D03*
Y1119780D03*
Y1121552D03*
Y1114465D03*
X536097Y584895D03*
Y586864D03*
X525073Y584895D03*
Y586864D03*
Y590801D03*
X536097D03*
Y588832D03*
X525073D03*
X524375Y1112693D03*
Y1116237D03*
Y1118008D03*
Y1119780D03*
Y1121552D03*
Y1114465D03*
X541520Y179897D03*
Y181866D03*
X552544Y179897D03*
Y181866D03*
X541520Y185803D03*
X552544D03*
X541520Y183834D03*
X552544D03*
X643882Y179897D03*
Y181866D03*
Y185803D03*
Y183834D03*
X654906Y179897D03*
Y181866D03*
Y185803D03*
Y183834D03*
X746244Y179897D03*
Y181866D03*
Y185803D03*
Y183834D03*
X757268Y179897D03*
Y181866D03*
Y185803D03*
Y183834D03*
X848606Y179897D03*
Y181866D03*
Y185803D03*
Y183834D03*
X859630Y179897D03*
Y181866D03*
Y185803D03*
Y183834D03*
X854739Y405479D03*
Y399573D03*
Y401542D03*
Y403510D03*
X865763Y399573D03*
Y405479D03*
Y403510D03*
Y401542D03*
X893885Y1090716D03*
Y1092685D03*
Y1094653D03*
Y1096622D03*
X904909Y1090716D03*
Y1096622D03*
Y1094653D03*
Y1092685D03*
X957862Y1090716D03*
Y1092685D03*
Y1094653D03*
Y1096622D03*
X968886Y1090716D03*
Y1096622D03*
Y1094653D03*
Y1092685D03*
X993184Y584895D03*
Y586864D03*
X982160Y584895D03*
Y586864D03*
Y590801D03*
X993184D03*
Y588832D03*
X982160D03*
X998606Y179897D03*
Y181866D03*
X1009630Y179897D03*
Y181866D03*
X998606Y185803D03*
X1009630D03*
X998606Y183834D03*
X1009630D03*
X1100968Y179897D03*
Y181866D03*
Y185803D03*
Y183834D03*
X1111992Y179897D03*
Y181866D03*
Y185803D03*
Y183834D03*
X1203330Y179897D03*
Y181866D03*
Y185803D03*
Y183834D03*
X1214354Y179897D03*
Y181866D03*
Y185803D03*
Y183834D03*
X1268157Y391572D03*
Y397478D03*
Y393541D03*
Y395509D03*
X1279181Y391572D03*
Y397478D03*
Y395509D03*
Y393541D03*
X1305692Y179897D03*
Y181866D03*
X1316716Y179897D03*
Y181866D03*
X1305692Y185803D03*
X1316716D03*
X1305692Y183834D03*
X1316716D03*
X1340834Y1112693D03*
Y1116237D03*
Y1118008D03*
Y1119780D03*
Y1121552D03*
Y1114465D03*
X1372962Y1112693D03*
Y1116237D03*
Y1118008D03*
Y1119780D03*
Y1121552D03*
Y1114465D03*
X1406421Y1112693D03*
Y1116237D03*
Y1118008D03*
Y1119780D03*
Y1121552D03*
Y1114465D03*
X1439247Y584895D03*
Y586864D03*
Y590801D03*
Y588832D03*
X1438549Y1112693D03*
Y1116237D03*
Y1118008D03*
Y1119780D03*
Y1121552D03*
Y1114465D03*
X1455693Y179897D03*
Y181866D03*
Y185803D03*
Y183834D03*
X1450271Y584895D03*
Y586864D03*
Y590801D03*
Y588832D03*
X1466717Y179897D03*
Y181866D03*
Y185803D03*
Y183834D03*
X1558055Y179897D03*
Y181866D03*
Y185803D03*
Y183834D03*
X1569079Y179897D03*
Y181866D03*
Y185803D03*
Y183834D03*
X1660417Y179897D03*
Y181866D03*
Y185803D03*
Y183834D03*
X1671441Y179897D03*
Y181866D03*
Y185803D03*
Y183834D03*
X1725244Y391572D03*
Y397478D03*
Y393541D03*
Y395509D03*
X1736268Y391572D03*
Y397478D03*
Y395509D03*
Y393541D03*
X1762779Y179897D03*
Y181866D03*
X1773803Y179897D03*
Y181866D03*
X1762779Y185803D03*
X1773803D03*
X1762779Y183834D03*
X1773803D03*
X1801842Y1091202D03*
Y1097108D03*
Y1093171D03*
Y1095139D03*
X1812866Y1091202D03*
Y1097108D03*
Y1095139D03*
Y1093171D03*
G54D76*
X67159Y560848D03*
X85663D03*
X346698Y422440D03*
X365202D03*
X524245Y560848D03*
X542749D03*
X839129Y429363D03*
X857633D03*
X981332Y560848D03*
X999836D03*
X1260871Y422440D03*
X1279375D03*
X1438419Y560848D03*
X1456923D03*
X1717958Y422440D03*
X1736462D03*
G54D187*
X814069Y848569D03*
Y859199D03*
X826165Y848651D03*
X828134D03*
X830102D03*
X819975Y848569D03*
X816038D03*
X818006D03*
X826165Y859281D03*
X828134D03*
X830102D03*
X816038Y859199D03*
X818006D03*
X819975D03*
X832071Y848651D03*
Y859281D03*
G54D85*
X65379Y1201565D03*
Y1205835D03*
X909070Y1214838D03*
Y1210568D03*
X973047Y1214838D03*
Y1210568D03*
X1817027Y1215324D03*
Y1211054D03*
G54D49*
X31623Y1463463D03*
X30543Y1479284D03*
X71404Y1452463D03*
X405498Y1524334D03*
X906950Y322671D03*
X905870Y335995D03*
X918458Y317736D03*
G54D58*
X54060Y492696D03*
X44229Y539440D03*
X89162Y214150D03*
X191524D03*
X293886D03*
X375084Y477527D03*
X396248Y214150D03*
X448704Y498641D03*
X501315Y539440D03*
X511146Y492696D03*
X546249Y214150D03*
X648611D03*
X750973D03*
X832170Y472527D03*
X853335Y214150D03*
X958402Y539440D03*
X968233Y492696D03*
X1003335Y214150D03*
X1105697D03*
X1208059D03*
X1289257Y477527D03*
X1310421Y214150D03*
X1415489Y539440D03*
X1425320Y492696D03*
X1460422Y214150D03*
X1562784D03*
X1665146D03*
X1746344Y477527D03*
X1767508Y214150D03*
G54D77*
X58395Y619312D03*
X515481D03*
X972568D03*
X1429655D03*
G54D59*
X48154Y487775D03*
Y489743D03*
Y491712D03*
Y493680D03*
Y495649D03*
Y497617D03*
X38323Y534519D03*
Y536487D03*
Y538456D03*
X50135D03*
Y536487D03*
Y534519D03*
X38323Y540424D03*
Y542393D03*
Y544361D03*
X50135D03*
Y542393D03*
Y540424D03*
X59966Y489743D03*
Y487775D03*
Y497617D03*
Y495649D03*
Y493680D03*
Y491712D03*
X83256Y209229D03*
Y211197D03*
Y213166D03*
Y215134D03*
Y217103D03*
Y219071D03*
X95068Y213166D03*
Y211197D03*
Y209229D03*
Y219071D03*
Y217103D03*
Y215134D03*
X197430Y213166D03*
Y211197D03*
Y209229D03*
X185618D03*
Y211197D03*
Y213166D03*
X197430Y219071D03*
Y217103D03*
Y215134D03*
X185618D03*
Y217103D03*
Y219071D03*
X287980Y209229D03*
Y211197D03*
Y213166D03*
Y215134D03*
Y217103D03*
Y219071D03*
X299792Y213166D03*
Y211197D03*
Y209229D03*
Y219071D03*
Y217103D03*
Y215134D03*
X369178Y472606D03*
Y474574D03*
Y476543D03*
Y478511D03*
Y480480D03*
Y482448D03*
X390342Y209229D03*
Y211197D03*
Y213166D03*
Y215134D03*
Y217103D03*
Y219071D03*
X380990Y474574D03*
Y472606D03*
Y482448D03*
Y480480D03*
Y478511D03*
Y476543D03*
X402154Y213166D03*
Y211197D03*
Y209229D03*
Y219071D03*
Y217103D03*
Y215134D03*
X442798Y493720D03*
Y495688D03*
Y497657D03*
Y499625D03*
Y501594D03*
Y503562D03*
X454610D03*
Y501594D03*
Y499625D03*
Y497657D03*
Y495688D03*
Y493720D03*
X505240Y487775D03*
Y489743D03*
Y491712D03*
Y493680D03*
Y495649D03*
Y497617D03*
X495409Y534519D03*
Y536487D03*
Y538456D03*
X507221D03*
Y536487D03*
Y534519D03*
X495409Y540424D03*
Y542393D03*
Y544361D03*
X507221D03*
Y542393D03*
Y540424D03*
X517052Y489743D03*
Y487775D03*
Y497617D03*
Y495649D03*
Y493680D03*
Y491712D03*
X552155Y213166D03*
Y211197D03*
Y209229D03*
X540343D03*
Y211197D03*
Y213166D03*
X552155Y219071D03*
Y217103D03*
Y215134D03*
X540343D03*
Y217103D03*
Y219071D03*
X642705Y209229D03*
Y211197D03*
Y213166D03*
Y215134D03*
Y217103D03*
Y219071D03*
X654517Y213166D03*
Y211197D03*
Y209229D03*
Y219071D03*
Y217103D03*
Y215134D03*
X745067Y209229D03*
Y211197D03*
Y213166D03*
Y215134D03*
Y217103D03*
Y219071D03*
X756879Y213166D03*
Y211197D03*
Y209229D03*
Y219071D03*
Y217103D03*
Y215134D03*
X826264Y467606D03*
Y469574D03*
Y471543D03*
Y473511D03*
Y475480D03*
Y477448D03*
X847429Y209229D03*
Y211197D03*
Y213166D03*
Y215134D03*
Y217103D03*
Y219071D03*
X838076Y473511D03*
Y471543D03*
Y469574D03*
Y467606D03*
Y477448D03*
Y475480D03*
X859241Y213166D03*
Y211197D03*
Y209229D03*
Y219071D03*
Y217103D03*
Y215134D03*
X962327Y487775D03*
Y489743D03*
Y491712D03*
Y493680D03*
Y495649D03*
Y497617D03*
X952496Y534519D03*
Y536487D03*
Y538456D03*
Y540424D03*
Y542393D03*
Y544361D03*
X974139Y489743D03*
Y487775D03*
Y497617D03*
Y495649D03*
Y493680D03*
Y491712D03*
X964308Y538456D03*
Y536487D03*
Y534519D03*
Y544361D03*
Y542393D03*
Y540424D03*
X1009241Y213166D03*
Y211197D03*
Y209229D03*
X997429D03*
Y211197D03*
Y213166D03*
X1009241Y219071D03*
Y217103D03*
Y215134D03*
X997429D03*
Y217103D03*
Y219071D03*
X1099791Y209229D03*
Y211197D03*
Y213166D03*
Y215134D03*
Y217103D03*
Y219071D03*
X1111603Y213166D03*
Y211197D03*
Y209229D03*
Y219071D03*
Y217103D03*
Y215134D03*
X1202153Y209229D03*
Y211197D03*
Y213166D03*
Y215134D03*
Y217103D03*
Y219071D03*
X1213965Y213166D03*
Y211197D03*
Y209229D03*
Y219071D03*
Y217103D03*
Y215134D03*
X1283351Y472606D03*
Y474574D03*
Y476543D03*
Y478511D03*
Y480480D03*
Y482448D03*
X1295163Y474574D03*
Y472606D03*
Y482448D03*
Y480480D03*
Y478511D03*
Y476543D03*
X1316327Y213166D03*
Y211197D03*
Y209229D03*
X1304515D03*
Y211197D03*
Y213166D03*
X1316327Y219071D03*
Y217103D03*
Y215134D03*
X1304515D03*
Y217103D03*
Y219071D03*
X1409583Y534519D03*
Y536487D03*
Y538456D03*
Y540424D03*
Y542393D03*
Y544361D03*
X1419414Y487775D03*
Y489743D03*
X1431226D03*
Y487775D03*
X1419414Y491712D03*
Y493680D03*
Y495649D03*
Y497617D03*
X1431226D03*
Y495649D03*
Y493680D03*
Y491712D03*
X1421395Y538456D03*
Y536487D03*
Y534519D03*
Y544361D03*
Y542393D03*
Y540424D03*
X1454516Y209229D03*
Y211197D03*
Y213166D03*
Y215134D03*
Y217103D03*
Y219071D03*
X1466328Y213166D03*
Y211197D03*
Y209229D03*
Y219071D03*
Y217103D03*
Y215134D03*
X1556878Y209229D03*
Y211197D03*
Y213166D03*
Y215134D03*
Y217103D03*
Y219071D03*
X1568690Y213166D03*
Y211197D03*
Y209229D03*
Y219071D03*
Y217103D03*
Y215134D03*
X1659240Y209229D03*
Y211197D03*
Y213166D03*
Y215134D03*
Y217103D03*
Y219071D03*
X1671052Y213166D03*
Y211197D03*
Y209229D03*
Y219071D03*
Y217103D03*
Y215134D03*
X1740438Y472606D03*
Y474574D03*
Y476543D03*
Y478511D03*
Y480480D03*
Y482448D03*
X1752250Y474574D03*
Y472606D03*
Y482448D03*
Y480480D03*
Y478511D03*
Y476543D03*
X1773414Y213166D03*
Y211197D03*
Y209229D03*
X1761602D03*
Y211197D03*
Y213166D03*
X1773414Y219071D03*
Y217103D03*
Y215134D03*
X1761602D03*
Y217103D03*
Y219071D03*
G54D86*
X64242Y1434190D03*
X68664Y1483644D03*
X414025Y1509344D03*
X429730Y1457016D03*
X420388Y1467886D03*
G54D197*
X855812Y1445699D03*
Y1459479D03*
X873530Y1445699D03*
Y1459479D03*
X897812Y1445699D03*
Y1459479D03*
X915530Y1445699D03*
Y1459479D03*
G54D188*
X814800Y876864D03*
Y885526D03*
X826804Y878504D03*
X831922D03*
X829363D03*
X819918Y876864D03*
X831922Y887166D03*
X826804D03*
X819918Y885526D03*
X817359D03*
X1285941Y913331D03*
Y904669D03*
X1291059Y913331D03*
Y904669D03*
X1288500D03*
X1443428Y1023064D03*
X1438310D03*
Y1014402D03*
X1443428D03*
X1440869D03*
G54D68*
X52707Y1084666D03*
X73499Y587848D03*
X89945Y182850D03*
X192307D03*
X294669D03*
X359496Y394525D03*
X387809Y957627D03*
X397031Y182850D03*
X530585Y587848D03*
X547032Y182850D03*
X649394D03*
X751756D03*
X854118D03*
X860251Y402526D03*
X899397Y1093669D03*
X963374D03*
X987672Y587848D03*
X1004118Y182850D03*
X1106480D03*
X1208842D03*
X1273669Y394525D03*
X1311204Y182850D03*
X1444759Y587848D03*
X1461205Y182850D03*
X1563567D03*
X1665929D03*
X1730756Y394525D03*
X1768291Y182850D03*
X1807354Y1094155D03*
G54D95*
X82638Y1417010D03*
X931080Y313436D03*
G54D179*
X736702Y1431659D03*
Y1451659D03*
X747528Y1441659D03*
G54D69*
X43350Y1077095D03*
X344530Y1220701D03*
X354057Y1217750D03*
X356886Y1220579D03*
X351229Y1214922D03*
X347359Y1223528D03*
X350188Y1226357D03*
X353017Y1229186D03*
X362543Y1226236D03*
X808316Y1214922D03*
X813973Y1220579D03*
X811144Y1217750D03*
X801617Y1220701D03*
X807275Y1226357D03*
X804446Y1223528D03*
X810104Y1229186D03*
X819630Y1226236D03*
X890040Y1086098D03*
X954017D03*
X1258703Y1220701D03*
X1268230Y1217750D03*
X1271059Y1220579D03*
X1265402Y1214922D03*
X1261532Y1223528D03*
X1264361Y1226357D03*
X1267190Y1229186D03*
X1276716Y1226236D03*
X1715790Y1220701D03*
X1725317Y1217750D03*
X1722489Y1214922D03*
X1718619Y1223528D03*
X1721448Y1226357D03*
X1724277Y1229186D03*
X1728146Y1220579D03*
X1733803Y1226236D03*
X1797997Y1086584D03*
G54D78*
X57066Y624724D03*
X514152D03*
X971239D03*
X1428326D03*
G54D189*
X812474Y1452587D03*
X864671Y1452589D03*
X906671D03*
G54D87*
X68689Y1597855D03*
Y1618721D03*
X73689Y1597855D03*
X78689D03*
X83689D03*
Y1618721D03*
X78689D03*
X73689D03*
X1758820Y1604357D03*
X1763820D03*
X1768820D03*
X1773820D03*
X1758820Y1625223D03*
X1773820D03*
X1768820D03*
X1763820D03*
G54D198*
X855862Y1447668D03*
Y1457510D03*
Y1451605D03*
Y1455542D03*
Y1449636D03*
Y1453573D03*
X873480Y1447668D03*
Y1451605D03*
Y1457510D03*
Y1453573D03*
Y1455542D03*
Y1449636D03*
X897862Y1447668D03*
Y1457510D03*
Y1451605D03*
Y1455542D03*
Y1449636D03*
Y1453573D03*
X915480Y1447668D03*
Y1451605D03*
Y1457510D03*
Y1453573D03*
Y1455542D03*
Y1449636D03*
G54D96*
X91838Y682577D03*
X214191Y1429058D03*
Y1432208D03*
Y1429058D03*
Y1425908D03*
X221543Y1428961D03*
Y1432111D03*
Y1428961D03*
Y1425811D03*
X373264Y372604D03*
Y375754D03*
X393620Y1513298D03*
Y1516448D03*
Y1519598D03*
Y1516448D03*
X400903Y1513406D03*
Y1516556D03*
Y1519706D03*
Y1516556D03*
X411487Y1498124D03*
X418839Y1498027D03*
D03*
Y1494877D03*
X411487Y1498124D03*
Y1494974D03*
Y1501274D03*
X418839Y1501177D03*
X454290Y625894D03*
X872736Y385705D03*
Y388855D03*
X915235Y326452D03*
Y323302D03*
Y326452D03*
X920752D03*
D03*
Y323302D03*
X915235Y329602D03*
X920752D03*
X938287Y333667D03*
Y330517D03*
X943787Y333667D03*
Y330517D03*
X938287Y336817D03*
Y333667D03*
X943787Y336817D03*
Y333667D03*
X1025399Y1316576D03*
Y1313426D03*
X1744524Y372604D03*
Y375754D03*
G54D199*
X877727Y722060D03*
Y727178D03*
X870727D03*
Y722060D03*
Y724619D03*
G54D97*
X91838Y679427D03*
X454290Y629044D03*
G54D79*
X56446Y829677D03*
X68652D03*
X56446Y831645D03*
X68652D03*
X56446Y837551D03*
X68652D03*
X56446Y833614D03*
Y835583D03*
X68652D03*
Y833614D03*
X573500Y943766D03*
X585706D03*
X573500Y951640D03*
X585706D03*
X573500Y945734D03*
Y947703D03*
Y949672D03*
X585706D03*
Y947703D03*
Y945734D03*
X995234Y838324D03*
Y846198D03*
Y840292D03*
Y842261D03*
Y844230D03*
X1007440Y846198D03*
Y838324D03*
Y844230D03*
Y842261D03*
Y840292D03*
X1015116Y940781D03*
X1027322D03*
X1015116Y942749D03*
Y944718D03*
X1027322D03*
Y942749D03*
X1015116Y948655D03*
X1027322D03*
X1015116Y946687D03*
X1027322D03*
X1789760Y971619D03*
Y973587D03*
Y975556D03*
Y977525D03*
Y979493D03*
X1801966Y971619D03*
Y977525D03*
Y975556D03*
Y973587D03*
Y979493D03*
G54D88*
X56348Y1727941D03*
Y1737941D03*
X56248Y1750941D03*
X56348Y1773941D03*
X56248Y1760941D03*
X56348Y1783941D03*
X56248Y1806941D03*
Y1796941D03*
X308448Y1737941D03*
Y1727941D03*
Y1750941D03*
Y1760941D03*
Y1773941D03*
Y1783941D03*
X308348Y1796941D03*
Y1806941D03*
X343286Y1738583D03*
Y1728583D03*
X343112Y1751624D03*
X343212Y1774624D03*
X343112Y1761624D03*
X343212Y1784624D03*
Y1797624D03*
Y1807624D03*
X595386Y1728583D03*
Y1738583D03*
X595312Y1751624D03*
Y1774624D03*
Y1761624D03*
Y1784624D03*
Y1807624D03*
Y1797624D03*
X630083Y1738286D03*
Y1728286D03*
X629861Y1751765D03*
X629711Y1775438D03*
X629861Y1761765D03*
X629711Y1785438D03*
X629475Y1798845D03*
Y1808845D03*
X882183Y1728286D03*
Y1738286D03*
X881911Y1751765D03*
X881761Y1775438D03*
X881911Y1761765D03*
X881761Y1785438D03*
X881525Y1798845D03*
Y1808845D03*
X917279Y1738990D03*
Y1728990D03*
X917163Y1752566D03*
Y1762566D03*
X917073Y1786014D03*
Y1776014D03*
X917166Y1800435D03*
Y1810435D03*
X1169329Y1728990D03*
Y1738990D03*
X1169263Y1752566D03*
Y1762566D03*
X1169123Y1776014D03*
Y1786014D03*
X1169216Y1800435D03*
Y1810435D03*
G54D89*
X83565Y273540D03*
X185927D03*
X288289D03*
X390651D03*
X540652D03*
X643014D03*
X745376D03*
X847738D03*
X997738D03*
X1100100D03*
X1202462D03*
X1304824D03*
X1454825D03*
X1557187D03*
X1659549D03*
X1761911D03*
G54D98*
X90658Y1003349D03*
X94398D03*
X547745D03*
X551485D03*
X1004831D03*
X1008571D03*
X1259368Y854487D03*
X1263108D03*
X1259368Y864487D03*
X1263108D03*
X1259368Y859487D03*
X1263108D03*
X1259368Y874487D03*
X1263108D03*
X1259368Y879487D03*
X1263108D03*
X1259368Y869487D03*
X1263108D03*
X1259368Y884487D03*
X1263108D03*
X1259368Y889487D03*
X1263108D03*
X1273264Y895646D03*
X1277004D03*
X1461918Y1003349D03*
X1465658D03*
X1775991Y826570D03*
X1783471D03*
Y818696D03*
G54D99*
X103958Y1021783D03*
Y1014303D03*
X561045Y1021783D03*
Y1014303D03*
X1018131Y1021783D03*
Y1014303D03*
X1475218Y1021783D03*
Y1014303D03*
M02*
